{ Packager-XL run on 30-Nov-2015 AT 15:33:22 }
FILE_TYPE = BACK_ANNOTATION;
DRAWING = "@baseboard_fab2_lib.baseboard_fab2(sch_1):page209";
BODY = "RES","I3": #LOCATION = "R1E5" !CDS_LOCATION = "R1E5" &SEC = "1" #&CDS_SEC = "1";
"A":   PN = "1"  !CDS_PN = "1";
"B":   PN = "2"  !CDS_PN = "2";
BODY = "CAP","I5": #LOCATION = "C9N27" !CDS_LOCATION = "C9N27" #SEC = "1" !CDS_SEC = "1";
"A":   PN = "1"  !CDS_PN = "1";
"B":   PN = "2"  !CDS_PN = "2";
BODY = "CAP","I7": #LOCATION = "C9N26" !CDS_LOCATION = "C9N26" #SEC = "1" !CDS_SEC = "1";
"A":   PN = "1"  !CDS_PN = "1";
"B":   PN = "2"  !CDS_PN = "2";
BODY = "CAP","I8": #LOCATION = "C9N25" !CDS_LOCATION = "C9N25" #SEC = "1" !CDS_SEC = "1";
"A":   PN = "1"  !CDS_PN = "1";
"B":   PN = "2"  !CDS_PN = "2";
BODY = "RES","I9": #LOCATION = "R1E8" !CDS_LOCATION = "R1E8" &SEC = "1" #&CDS_SEC = "1";
"A":   PN = "1"  !CDS_PN = "1";
"B":   PN = "2"  !CDS_PN = "2";
BODY = "RES","I10": #LOCATION = "R1E7" !CDS_LOCATION = "R1E7" &SEC = "1" #&CDS_SEC = "1";
"A":   PN = "1"  !CDS_PN = "1";
"B":   PN = "2"  !CDS_PN = "2";
BODY = "RES","I11": #LOCATION = "R1E6" !CDS_LOCATION = "R1E6" &SEC = "1" #&CDS_SEC = "1";
"A":   PN = "1"  !CDS_PN = "1";
"B":   PN = "2"  !CDS_PN = "2";
BODY = "RES","I15": #LOCATION = "R1E4" !CDS_LOCATION = "R1E4" &SEC = "1" #&CDS_SEC = "1";
"A":   PN = "1"  !CDS_PN = "1";
"B":   PN = "2"  !CDS_PN = "2";
BODY = "CAP","I16": #LOCATION = "C1C26" !CDS_LOCATION = "C1C26" #SEC = "1" !CDS_SEC = "1";
"A":   PN = "1"  !CDS_PN = "1";
"B":   PN = "2"  !CDS_PN = "2";
BODY = "CAP_A","I17": #LOCATION = "C1C25" !CDS_LOCATION = "C1C25" #SEC = "1" !CDS_SEC = "1";
"A":   PN = "1"  !CDS_PN = "1";
"B":   PN = "2"  !CDS_PN = "2";
BODY = "CAP","I18": #LOCATION = "C1D32" !CDS_LOCATION = "C1D32" #SEC = "1" !CDS_SEC = "1";
"A":   PN = "1"  !CDS_PN = "1";
"B":   PN = "2"  !CDS_PN = "2";
BODY = "CAP","I20": #LOCATION = "C1C24" !CDS_LOCATION = "C1C24" #SEC = "1" !CDS_SEC = "1";
"A":   PN = "1"  !CDS_PN = "1";
"B":   PN = "2"  !CDS_PN = "2";
BODY = "CAP_A","I21": #LOCATION = "C1C18" !CDS_LOCATION = "C1C18" #SEC = "1" !CDS_SEC = "1";
"A":   PN = "1"  !CDS_PN = "1";
"B":   PN = "2"  !CDS_PN = "2";
BODY = "CAP","I22": #LOCATION = "C1D33" !CDS_LOCATION = "C1D33" #SEC = "1" !CDS_SEC = "1";
"A":   PN = "1"  !CDS_PN = "1";
"B":   PN = "2"  !CDS_PN = "2";
BODY = "RES","I24": #LOCATION = "R9P32" !CDS_LOCATION = "R9P32" #SEC = "1" !CDS_SEC = "1";
"A":   PN = "1"  !CDS_PN = "1";
"B":   PN = "2"  !CDS_PN = "2";
BODY = "CAP_A","I30": #LOCATION = "C1B16" !CDS_LOCATION = "C1B16" &SEC = "1" #&CDS_SEC = "1";
"A":   PN = "1"  !CDS_PN = "1";
"B":   PN = "2"  !CDS_PN = "2";
BODY = "INDUCTOR","I32": #LOCATION = "L1B2" !CDS_LOCATION = "L1B2" #SEC = "1" !CDS_SEC = "1";
"INA":   PN = "1"  !CDS_PN = "1";
"INB":   PN = "2"  !CDS_PN = "2";
BODY = "CAPP","I35": #LOCATION = "C1C1" !CDS_LOCATION = "C1C1" #SEC = "1" !CDS_SEC = "1";
"A":   PN = "1"  !CDS_PN = "1";
"B":   PN = "2"  !CDS_PN = "2";
BODY = "CAPP","I37": #LOCATION = "C1E18" !CDS_LOCATION = "C1E18" #SEC = "1" !CDS_SEC = "1";
"A":   PN = "1"  !CDS_PN = "1";
"B":   PN = "2"  !CDS_PN = "2";
BODY = "CAPP","I38": #LOCATION = "C1C2" !CDS_LOCATION = "C1C2" #SEC = "1" !CDS_SEC = "1";
"A":   PN = "1"  !CDS_PN = "1";
"B":   PN = "2"  !CDS_PN = "2";
BODY = "RES","I39": #LOCATION = "R1B20" !CDS_LOCATION = "R1B20" #SEC = "1" !CDS_SEC = "1";
"A":   PN = "1"  !CDS_PN = "1";
"B":   PN = "2"  !CDS_PN = "2";
BODY = "INDUCTOR","I40": #LOCATION = "L1C2" !CDS_LOCATION = "L1C2" &SEC = "1" #&CDS_SEC = "1";
"INA":   PN = "1"  !CDS_PN = "1";
"INB":   PN = "2"  !CDS_PN = "2";
BODY = "CAP_A","I42": #LOCATION = "C1D24" !CDS_LOCATION = "C1D24" #SEC = "1" !CDS_SEC = "1";
"A":   PN = "1"  !CDS_PN = "1";
"B":   PN = "2"  !CDS_PN = "2";
BODY = "ADM4073","I52": #LOCATION = "U1B3" !CDS_LOCATION = "U1B3" #SEC = "1" !CDS_SEC = "1";
"GND<0>":   PN = "1"  !CDS_PN = "1";
"GND<1>":   PN = "2"  !CDS_PN = "2";
"OUT":   PN = "6"  !CDS_PN = "6";
"RSN":   PN = "5"  !CDS_PN = "5";
"RSP":   PN = "4"  !CDS_PN = "4";
"VCC":   PN = "3"  !CDS_PN = "3";
BODY = "CAP_A","I55": #LOCATION = "C9P20" !CDS_LOCATION = "C9P20" #SEC = "1" !CDS_SEC = "1";
"A":   PN = "1"  !CDS_PN = "1";
"B":   PN = "2"  !CDS_PN = "2";
BODY = "IR354XX","I56": #LOCATION = "EU1C3" !CDS_LOCATION = "EU1C3" #SEC = "1" !CDS_SEC = "1";
"BOOST":   PN = "33"  !CDS_PN = "33";
"EN":   PN = "35"  !CDS_PN = "35";
"GL<0>":   PN = "6"  !CDS_PN = "6";
"GL<1>":   PN = "41"  !CDS_PN = "41";
"IOUT":   PN = "38"  !CDS_PN = "38";
"LGND":   PN = "2"  !CDS_PN = "2";
"NC":   PN = "31"  !CDS_PN = "31";
"OCSET":   PN = "37"  !CDS_PN = "37";
"PGND<0>":   PN = "5"  !CDS_PN = "5";
"PGND<1>":   PN = "7"  !CDS_PN = "7";
"PGND<2>":   PN = "40"  !CDS_PN = "40";
"PHASE":   PN = "32"  !CDS_PN = "32";
"PWM":   PN = "34"  !CDS_PN = "34";
"REFIN":   PN = "39"  !CDS_PN = "39";
"SW":   PN = "10"  !CDS_PN = "10";
"TOUT_FLT":   PN = "36"  !CDS_PN = "36";
"VCC":   PN = "3"  !CDS_PN = "3";
"VDRV":   PN = "4"  !CDS_PN = "4";
"VIN<0>":   PN = "25"  !CDS_PN = "25";
"VIN<1>":   PN = "30"  !CDS_PN = "30";
"VOS":   PN = "1"  !CDS_PN = "1";
BODY = "RES","I59": #LOCATION = "R1D52" !CDS_LOCATION = "R1D52" &SEC = "1" #&CDS_SEC = "1";
"A":   PN = "1"  !CDS_PN = "1";
"B":   PN = "2"  !CDS_PN = "2";
BODY = "CAP_A","I62": #LOCATION = "CT13" !CDS_LOCATION = "CT13" &SEC = "1" #&CDS_SEC = "1";
"A":   PN = "1"  !CDS_PN = "1";
"B":   PN = "2"  !CDS_PN = "2";
BODY = "SC2K2P50V3KX-GP","I64": #LOCATION = "CT14" !CDS_LOCATION = "CT14" &SEC = "1" #&CDS_SEC = "1";
"1":   PN = "1"  !CDS_PN = "1";
"2":   PN = "2"  !CDS_PN = "2";
BODY = "CAP","I67": #LOCATION = "CT15" !CDS_LOCATION = "CT15" &SEC = "1" #&CDS_SEC = "1";
"A":   PN = "1"  !CDS_PN = "1";
"B":   PN = "2"  !CDS_PN = "2";
BODY = "3D01R5F-GP","I66": #LOCATION = "RT10" !CDS_LOCATION = "RT10" &SEC = "1" #&CDS_SEC = "1";
"1":   PN = "1"  !CDS_PN = "1";
"2":   PN = "2"  !CDS_PN = "2";
BODY = "RES","I69": #LOCATION = "RT9" !CDS_LOCATION = "RT9" &SEC = "1" #&CDS_SEC = "1";
"A":   PN = "1"  !CDS_PN = "1";
"B":   PN = "2"  !CDS_PN = "2";
DRAWING = "@baseboard_fab2_lib.baseboard_fab2(sch_1):page227";
BODY = "CAP","I6": #LOCATION = "C1A12" !CDS_LOCATION = "C1A12" #SEC = "1" !CDS_SEC = "1";
"A":   PN = "1"  !CDS_PN = "1";
"B":   PN = "2"  !CDS_PN = "2";
BODY = "CAP","I44": #LOCATION = "C1A18" !CDS_LOCATION = "C1A18" #SEC = "1" !CDS_SEC = "1";
"A":   PN = "1"  !CDS_PN = "1";
"B":   PN = "2"  !CDS_PN = "2";
BODY = "CAP","I45": #LOCATION = "C9L11" !CDS_LOCATION = "C9L11" #SEC = "1" !CDS_SEC = "1";
"A":   PN = "1"  !CDS_PN = "1";
"B":   PN = "2"  !CDS_PN = "2";
BODY = "CAP","I46": #LOCATION = "C9L10" !CDS_LOCATION = "C9L10" #SEC = "1" !CDS_SEC = "1";
"A":   PN = "1"  !CDS_PN = "1";
"B":   PN = "2"  !CDS_PN = "2";
BODY = "CAP","I47": #LOCATION = "C9L6" !CDS_LOCATION = "C9L6" #SEC = "1" !CDS_SEC = "1";
"A":   PN = "1"  !CDS_PN = "1";
"B":   PN = "2"  !CDS_PN = "2";
BODY = "CAP","I48": #LOCATION = "C1A19" !CDS_LOCATION = "C1A19" #SEC = "1" !CDS_SEC = "1";
"A":   PN = "1"  !CDS_PN = "1";
"B":   PN = "2"  !CDS_PN = "2";
BODY = "CAP","I50": #LOCATION = "C1B20" !CDS_LOCATION = "C1B20" #SEC = "1" !CDS_SEC = "1";
"A":   PN = "1"  !CDS_PN = "1";
"B":   PN = "2"  !CDS_PN = "2";
BODY = "CAP_A","I51": #LOCATION = "C1A10" !CDS_LOCATION = "C1A10" #SEC = "1" !CDS_SEC = "1";
"A":   PN = "1"  !CDS_PN = "1";
"B":   PN = "2"  !CDS_PN = "2";
BODY = "RES","I52": #LOCATION = "R9L9" !CDS_LOCATION = "R9L9" #SEC = "1" !CDS_SEC = "1";
"A":   PN = "1"  !CDS_PN = "1";
"B":   PN = "2"  !CDS_PN = "2";
BODY = "CAP_A","I53": #LOCATION = "C1A2" !CDS_LOCATION = "C1A2" #SEC = "1" !CDS_SEC = "1";
"A":   PN = "1"  !CDS_PN = "1";
"B":   PN = "2"  !CDS_PN = "2";
BODY = "CAP","I54": #LOCATION = "C1B21" !CDS_LOCATION = "C1B21" #SEC = "1" !CDS_SEC = "1";
"A":   PN = "1"  !CDS_PN = "1";
"B":   PN = "2"  !CDS_PN = "2";
BODY = "INDUCTOR","I55": #LOCATION = "L1A2" !CDS_LOCATION = "L1A2" #SEC = "1" !CDS_SEC = "1";
"INA":   PN = "1"  !CDS_PN = "1";
"INB":   PN = "2"  !CDS_PN = "2";
BODY = "INDUCTOR","I65": #LOCATION = "L1A1" !CDS_LOCATION = "L1A1" #SEC = "1" !CDS_SEC = "1";
"INA":   PN = "1"  !CDS_PN = "1";
"INB":   PN = "2"  !CDS_PN = "2";
BODY = "CAP","I68": #LOCATION = "C1A1" !CDS_LOCATION = "C1A1" #SEC = "1" !CDS_SEC = "1";
"A":   PN = "1"  !CDS_PN = "1";
"B":   PN = "2"  !CDS_PN = "2";
BODY = "CAP","I72": #LOCATION = "C1A13" !CDS_LOCATION = "C1A13" #SEC = "1" !CDS_SEC = "1";
"A":   PN = "1"  !CDS_PN = "1";
"B":   PN = "2"  !CDS_PN = "2";
BODY = "CAP_A","I73": #LOCATION = "C1A11" !CDS_LOCATION = "C1A11" #SEC = "1" !CDS_SEC = "1";
"A":   PN = "1"  !CDS_PN = "1";
"B":   PN = "2"  !CDS_PN = "2";
BODY = "CAP","I75": #LOCATION = "C1A8" !CDS_LOCATION = "C1A8" #SEC = "1" !CDS_SEC = "1";
"A":   PN = "1"  !CDS_PN = "1";
"B":   PN = "2"  !CDS_PN = "2";
BODY = "RES","I76": #LOCATION = "R9L4" !CDS_LOCATION = "R9L4" #SEC = "1" !CDS_SEC = "1";
"A":   PN = "1"  !CDS_PN = "1";
"B":   PN = "2"  !CDS_PN = "2";
BODY = "CAP","I77": #LOCATION = "C1A6" !CDS_LOCATION = "C1A6" #SEC = "1" !CDS_SEC = "1";
"A":   PN = "1"  !CDS_PN = "1";
"B":   PN = "2"  !CDS_PN = "2";
BODY = "CAP_A","I78": #LOCATION = "C1A20" !CDS_LOCATION = "C1A20" #SEC = "1" !CDS_SEC = "1";
"A":   PN = "1"  !CDS_PN = "1";
"B":   PN = "2"  !CDS_PN = "2";
BODY = "CAP","I79": #LOCATION = "C1A9" !CDS_LOCATION = "C1A9" #SEC = "1" !CDS_SEC = "1";
"A":   PN = "1"  !CDS_PN = "1";
"B":   PN = "2"  !CDS_PN = "2";
BODY = "CAP","I80": #LOCATION = "C9L5" !CDS_LOCATION = "C9L5" #SEC = "1" !CDS_SEC = "1";
"A":   PN = "1"  !CDS_PN = "1";
"B":   PN = "2"  !CDS_PN = "2";
BODY = "CAP","I81": #LOCATION = "C9L13" !CDS_LOCATION = "C9L13" #SEC = "1" !CDS_SEC = "1";
"A":   PN = "1"  !CDS_PN = "1";
"B":   PN = "2"  !CDS_PN = "2";
BODY = "CAP","I84": #LOCATION = "C9L14" !CDS_LOCATION = "C9L14" #SEC = "1" !CDS_SEC = "1";
"A":   PN = "1"  !CDS_PN = "1";
"B":   PN = "2"  !CDS_PN = "2";
BODY = "IR354XX","I101": #LOCATION = "EU1A2" !CDS_LOCATION = "EU1A2" #SEC = "1" !CDS_SEC = "1";
"BOOST":   PN = "33"  !CDS_PN = "33";
"EN":   PN = "35"  !CDS_PN = "35";
"GL<0>":   PN = "6"  !CDS_PN = "6";
"GL<1>":   PN = "41"  !CDS_PN = "41";
"IOUT":   PN = "38"  !CDS_PN = "38";
"LGND":   PN = "2"  !CDS_PN = "2";
"NC":   PN = "31"  !CDS_PN = "31";
"OCSET":   PN = "37"  !CDS_PN = "37";
"PGND<0>":   PN = "5"  !CDS_PN = "5";
"PGND<1>":   PN = "7"  !CDS_PN = "7";
"PGND<2>":   PN = "40"  !CDS_PN = "40";
"PHASE":   PN = "32"  !CDS_PN = "32";
"PWM":   PN = "34"  !CDS_PN = "34";
"REFIN":   PN = "39"  !CDS_PN = "39";
"SW":   PN = "10"  !CDS_PN = "10";
"TOUT_FLT":   PN = "36"  !CDS_PN = "36";
"VCC":   PN = "3"  !CDS_PN = "3";
"VDRV":   PN = "4"  !CDS_PN = "4";
"VIN<0>":   PN = "25"  !CDS_PN = "25";
"VIN<1>":   PN = "30"  !CDS_PN = "30";
"VOS":   PN = "1"  !CDS_PN = "1";
BODY = "IR354XX","I102": #LOCATION = "EU1A1" !CDS_LOCATION = "EU1A1" #SEC = "1" !CDS_SEC = "1";
"BOOST":   PN = "33"  !CDS_PN = "33";
"EN":   PN = "35"  !CDS_PN = "35";
"GL<0>":   PN = "6"  !CDS_PN = "6";
"GL<1>":   PN = "41"  !CDS_PN = "41";
"IOUT":   PN = "38"  !CDS_PN = "38";
"LGND":   PN = "2"  !CDS_PN = "2";
"NC":   PN = "31"  !CDS_PN = "31";
"OCSET":   PN = "37"  !CDS_PN = "37";
"PGND<0>":   PN = "5"  !CDS_PN = "5";
"PGND<1>":   PN = "7"  !CDS_PN = "7";
"PGND<2>":   PN = "40"  !CDS_PN = "40";
"PHASE":   PN = "32"  !CDS_PN = "32";
"PWM":   PN = "34"  !CDS_PN = "34";
"REFIN":   PN = "39"  !CDS_PN = "39";
"SW":   PN = "10"  !CDS_PN = "10";
"TOUT_FLT":   PN = "36"  !CDS_PN = "36";
"VCC":   PN = "3"  !CDS_PN = "3";
"VDRV":   PN = "4"  !CDS_PN = "4";
"VIN<0>":   PN = "25"  !CDS_PN = "25";
"VIN<1>":   PN = "30"  !CDS_PN = "30";
"VOS":   PN = "1"  !CDS_PN = "1";
BODY = "RES","I103": #LOCATION = "R1A3" !CDS_LOCATION = "R1A3" #SEC = "1" !CDS_SEC = "1";
"A":   PN = "1"  !CDS_PN = "1";
"B":   PN = "2"  !CDS_PN = "2";
BODY = "RES","I105": #LOCATION = "R1A2" !CDS_LOCATION = "R1A2" #SEC = "1" !CDS_SEC = "1";
"A":   PN = "1"  !CDS_PN = "1";
"B":   PN = "2"  !CDS_PN = "2";
BODY = "CAP_A","I109": #LOCATION = "CT7" !CDS_LOCATION = "CT7" &SEC = "1" #&CDS_SEC = "1";
"A":   PN = "1"  !CDS_PN = "1";
"B":   PN = "2"  !CDS_PN = "2";
BODY = "SC2K2P50V3KX-GP","I111": #LOCATION = "CT9" !CDS_LOCATION = "CT9" &SEC = "1" #&CDS_SEC = "1";
"1":   PN = "1"  !CDS_PN = "1";
"2":   PN = "2"  !CDS_PN = "2";
BODY = "CAP","I114": #LOCATION = "CT8" !CDS_LOCATION = "CT8" &SEC = "1" #&CDS_SEC = "1";
"A":   PN = "1"  !CDS_PN = "1";
"B":   PN = "2"  !CDS_PN = "2";
BODY = "SC2K2P50V3KX-GP","I116": #LOCATION = "CT11" !CDS_LOCATION = "CT11" &SEC = "1" #&CDS_SEC = "1";
"1":   PN = "1"  !CDS_PN = "1";
"2":   PN = "2"  !CDS_PN = "2";
BODY = "CAP","I119": #LOCATION = "CT10" !CDS_LOCATION = "CT10" &SEC = "1" #&CDS_SEC = "1";
"A":   PN = "1"  !CDS_PN = "1";
"B":   PN = "2"  !CDS_PN = "2";
BODY = "CAP_A","I122": #LOCATION = "CT12" !CDS_LOCATION = "CT12" &SEC = "1" #&CDS_SEC = "1";
"A":   PN = "1"  !CDS_PN = "1";
"B":   PN = "2"  !CDS_PN = "2";
BODY = "3D01R5F-GP","I124": #LOCATION = "RT7" !CDS_LOCATION = "RT7" &SEC = "1" #&CDS_SEC = "1";
"1":   PN = "1"  !CDS_PN = "1";
"2":   PN = "2"  !CDS_PN = "2";
BODY = "3D01R5F-GP","I125": #LOCATION = "RT6" !CDS_LOCATION = "RT6" &SEC = "1" #&CDS_SEC = "1";
"1":   PN = "1"  !CDS_PN = "1";
"2":   PN = "2"  !CDS_PN = "2";
BODY = "RES","I126": #LOCATION = "RT5" !CDS_LOCATION = "RT5" &SEC = "1" #&CDS_SEC = "1";
"A":   PN = "1"  !CDS_PN = "1";
"B":   PN = "2"  !CDS_PN = "2";
BODY = "RES","I127": #LOCATION = "RT8" !CDS_LOCATION = "RT8" &SEC = "1" #&CDS_SEC = "1";
"A":   PN = "1"  !CDS_PN = "1";
"B":   PN = "2"  !CDS_PN = "2";
DRAWING = "@baseboard_fab2_lib.baseboard_fab2(sch_1):page208";
BODY = "RES","I7": #LOCATION = "R1E3" !CDS_LOCATION = "R1E3" #SEC = "1" !CDS_SEC = "1";
"A":   PN = "1"  !CDS_PN = "1";
"B":   PN = "2"  !CDS_PN = "2";
BODY = "CAP_A","I9": #LOCATION = "C1D14" !CDS_LOCATION = "C1D14" #SEC = "1" !CDS_SEC = "1";
"A":   PN = "1"  !CDS_PN = "1";
"B":   PN = "2"  !CDS_PN = "2";
BODY = "INDUCTOR","I11": #LOCATION = "L1D2" !CDS_LOCATION = "L1D2" &SEC = "1" #&CDS_SEC = "1";
"INA":   PN = "1"  !CDS_PN = "1";
"INB":   PN = "2"  !CDS_PN = "2";
BODY = "CAPP","I12": #LOCATION = "C9P8" !CDS_LOCATION = "C9P8" #SEC = "1" !CDS_SEC = "1";
"A":   PN = "1"  !CDS_PN = "1";
"B":   PN = "2"  !CDS_PN = "2";
BODY = "CAPP","I14": #LOCATION = "C9P5" !CDS_LOCATION = "C9P5" #SEC = "1" !CDS_SEC = "1";
"A":   PN = "1"  !CDS_PN = "1";
"B":   PN = "2"  !CDS_PN = "2";
BODY = "INDUCTOR","I20": #LOCATION = "L1D1" !CDS_LOCATION = "L1D1" &SEC = "1" #&CDS_SEC = "1";
"INA":   PN = "1"  !CDS_PN = "1";
"INB":   PN = "2"  !CDS_PN = "2";
BODY = "CAP_A","I22": #LOCATION = "C1D3" !CDS_LOCATION = "C1D3" #SEC = "1" !CDS_SEC = "1";
"A":   PN = "1"  !CDS_PN = "1";
"B":   PN = "2"  !CDS_PN = "2";
BODY = "CAPP","I24": #LOCATION = "C9N24" !CDS_LOCATION = "C9N24" #SEC = "1" !CDS_SEC = "1";
"A":   PN = "1"  !CDS_PN = "1";
"B":   PN = "2"  !CDS_PN = "2";
BODY = "CAPP","I25": #LOCATION = "C9R9" !CDS_LOCATION = "C9R9" #SEC = "1" !CDS_SEC = "1";
"A":   PN = "1"  !CDS_PN = "1";
"B":   PN = "2"  !CDS_PN = "2";
BODY = "CAPP","I26": #LOCATION = "C9R3" !CDS_LOCATION = "C9R3" #SEC = "1" !CDS_SEC = "1";
"A":   PN = "1"  !CDS_PN = "1";
"B":   PN = "2"  !CDS_PN = "2";
BODY = "IR354XX","I27": #LOCATION = "EU1D3" !CDS_LOCATION = "EU1D3" #SEC = "1" !CDS_SEC = "1";
"BOOST":   PN = "33"  !CDS_PN = "33";
"EN":   PN = "35"  !CDS_PN = "35";
"GL<0>":   PN = "6"  !CDS_PN = "6";
"GL<1>":   PN = "41"  !CDS_PN = "41";
"IOUT":   PN = "38"  !CDS_PN = "38";
"LGND":   PN = "2"  !CDS_PN = "2";
"NC":   PN = "31"  !CDS_PN = "31";
"OCSET":   PN = "37"  !CDS_PN = "37";
"PGND<0>":   PN = "5"  !CDS_PN = "5";
"PGND<1>":   PN = "7"  !CDS_PN = "7";
"PGND<2>":   PN = "40"  !CDS_PN = "40";
"PHASE":   PN = "32"  !CDS_PN = "32";
"PWM":   PN = "34"  !CDS_PN = "34";
"REFIN":   PN = "39"  !CDS_PN = "39";
"SW":   PN = "10"  !CDS_PN = "10";
"TOUT_FLT":   PN = "36"  !CDS_PN = "36";
"VCC":   PN = "3"  !CDS_PN = "3";
"VDRV":   PN = "4"  !CDS_PN = "4";
"VIN<0>":   PN = "25"  !CDS_PN = "25";
"VIN<1>":   PN = "30"  !CDS_PN = "30";
"VOS":   PN = "1"  !CDS_PN = "1";
BODY = "CAPP","I28": #LOCATION = "C9P23" !CDS_LOCATION = "C9P23" #SEC = "1" !CDS_SEC = "1";
"A":   PN = "1"  !CDS_PN = "1";
"B":   PN = "2"  !CDS_PN = "2";
BODY = "CAPP","I30": #LOCATION = "C9P18" !CDS_LOCATION = "C9P18" #SEC = "1" !CDS_SEC = "1";
"A":   PN = "1"  !CDS_PN = "1";
"B":   PN = "2"  !CDS_PN = "2";
BODY = "RES","I36": #LOCATION = "R9P22" !CDS_LOCATION = "R9P22" #SEC = "1" !CDS_SEC = "1";
"A":   PN = "1"  !CDS_PN = "1";
"B":   PN = "2"  !CDS_PN = "2";
BODY = "CAP","I38": #LOCATION = "C1D16" !CDS_LOCATION = "C1D16" #SEC = "1" !CDS_SEC = "1";
"A":   PN = "1"  !CDS_PN = "1";
"B":   PN = "2"  !CDS_PN = "2";
BODY = "CAP_A","I39": #LOCATION = "C1D15" !CDS_LOCATION = "C1D15" #SEC = "1" !CDS_SEC = "1";
"A":   PN = "1"  !CDS_PN = "1";
"B":   PN = "2"  !CDS_PN = "2";
BODY = "CAP","I40": #LOCATION = "C1D20" !CDS_LOCATION = "C1D20" #SEC = "1" !CDS_SEC = "1";
"A":   PN = "1"  !CDS_PN = "1";
"B":   PN = "2"  !CDS_PN = "2";
BODY = "CAP","I43": #LOCATION = "C1D17" !CDS_LOCATION = "C1D17" #SEC = "1" !CDS_SEC = "1";
"A":   PN = "1"  !CDS_PN = "1";
"B":   PN = "2"  !CDS_PN = "2";
BODY = "CAP_A","I44": #LOCATION = "C1D28" !CDS_LOCATION = "C1D28" #SEC = "1" !CDS_SEC = "1";
"A":   PN = "1"  !CDS_PN = "1";
"B":   PN = "2"  !CDS_PN = "2";
BODY = "CAP","I45": #LOCATION = "C1D23" !CDS_LOCATION = "C1D23" #SEC = "1" !CDS_SEC = "1";
"A":   PN = "1"  !CDS_PN = "1";
"B":   PN = "2"  !CDS_PN = "2";
BODY = "CAP","I46": #LOCATION = "C1D6" !CDS_LOCATION = "C1D6" #SEC = "1" !CDS_SEC = "1";
"A":   PN = "1"  !CDS_PN = "1";
"B":   PN = "2"  !CDS_PN = "2";
BODY = "CAP_A","I47": #LOCATION = "C1D5" !CDS_LOCATION = "C1D5" #SEC = "1" !CDS_SEC = "1";
"A":   PN = "1"  !CDS_PN = "1";
"B":   PN = "2"  !CDS_PN = "2";
BODY = "CAP","I48": #LOCATION = "C1D10" !CDS_LOCATION = "C1D10" #SEC = "1" !CDS_SEC = "1";
"A":   PN = "1"  !CDS_PN = "1";
"B":   PN = "2"  !CDS_PN = "2";
BODY = "RES","I49": #LOCATION = "R9P8" !CDS_LOCATION = "R9P8" #SEC = "1" !CDS_SEC = "1";
"A":   PN = "1"  !CDS_PN = "1";
"B":   PN = "2"  !CDS_PN = "2";
BODY = "CAP","I50": #LOCATION = "C1D7" !CDS_LOCATION = "C1D7" #SEC = "1" !CDS_SEC = "1";
"A":   PN = "1"  !CDS_PN = "1";
"B":   PN = "2"  !CDS_PN = "2";
BODY = "CAP_A","I51": #LOCATION = "C1D13" !CDS_LOCATION = "C1D13" #SEC = "1" !CDS_SEC = "1";
"A":   PN = "1"  !CDS_PN = "1";
"B":   PN = "2"  !CDS_PN = "2";
BODY = "CAP","I52": #LOCATION = "C1D12" !CDS_LOCATION = "C1D12" #SEC = "1" !CDS_SEC = "1";
"A":   PN = "1"  !CDS_PN = "1";
"B":   PN = "2"  !CDS_PN = "2";
BODY = "CAP","I53": #LOCATION = "C9P4" !CDS_LOCATION = "C9P4" #SEC = "1" !CDS_SEC = "1";
"A":   PN = "1"  !CDS_PN = "1";
"B":   PN = "2"  !CDS_PN = "2";
BODY = "CAP","I54": #LOCATION = "C9P7" !CDS_LOCATION = "C9P7" #SEC = "1" !CDS_SEC = "1";
"A":   PN = "1"  !CDS_PN = "1";
"B":   PN = "2"  !CDS_PN = "2";
BODY = "CAP","I55": #LOCATION = "C9P9" !CDS_LOCATION = "C9P9" #SEC = "1" !CDS_SEC = "1";
"A":   PN = "1"  !CDS_PN = "1";
"B":   PN = "2"  !CDS_PN = "2";
BODY = "CAP","I58": #LOCATION = "C9P24" !CDS_LOCATION = "C9P24" #SEC = "1" !CDS_SEC = "1";
"A":   PN = "1"  !CDS_PN = "1";
"B":   PN = "2"  !CDS_PN = "2";
BODY = "CAP","I59": #LOCATION = "C9P1" !CDS_LOCATION = "C9P1" #SEC = "1" !CDS_SEC = "1";
"A":   PN = "1"  !CDS_PN = "1";
"B":   PN = "2"  !CDS_PN = "2";
BODY = "CAP","I60": #LOCATION = "C9P2" !CDS_LOCATION = "C9P2" #SEC = "1" !CDS_SEC = "1";
"A":   PN = "1"  !CDS_PN = "1";
"B":   PN = "2"  !CDS_PN = "2";
BODY = "CAP_A","I66": #LOCATION = "C9P10" !CDS_LOCATION = "C9P10" #SEC = "1" !CDS_SEC = "1";
"A":   PN = "1"  !CDS_PN = "1";
"B":   PN = "2"  !CDS_PN = "2";
BODY = "CAP_A","I67": #LOCATION = "C9R2" !CDS_LOCATION = "C9R2" #SEC = "1" !CDS_SEC = "1";
"A":   PN = "1"  !CDS_PN = "1";
"B":   PN = "2"  !CDS_PN = "2";
BODY = "IR354XX","I71": #LOCATION = "EU1D1" !CDS_LOCATION = "EU1D1" #SEC = "1" !CDS_SEC = "1";
"BOOST":   PN = "33"  !CDS_PN = "33";
"EN":   PN = "35"  !CDS_PN = "35";
"GL<0>":   PN = "6"  !CDS_PN = "6";
"GL<1>":   PN = "41"  !CDS_PN = "41";
"IOUT":   PN = "38"  !CDS_PN = "38";
"LGND":   PN = "2"  !CDS_PN = "2";
"NC":   PN = "31"  !CDS_PN = "31";
"OCSET":   PN = "37"  !CDS_PN = "37";
"PGND<0>":   PN = "5"  !CDS_PN = "5";
"PGND<1>":   PN = "7"  !CDS_PN = "7";
"PGND<2>":   PN = "40"  !CDS_PN = "40";
"PHASE":   PN = "32"  !CDS_PN = "32";
"PWM":   PN = "34"  !CDS_PN = "34";
"REFIN":   PN = "39"  !CDS_PN = "39";
"SW":   PN = "10"  !CDS_PN = "10";
"TOUT_FLT":   PN = "36"  !CDS_PN = "36";
"VCC":   PN = "3"  !CDS_PN = "3";
"VDRV":   PN = "4"  !CDS_PN = "4";
"VIN<0>":   PN = "25"  !CDS_PN = "25";
"VIN<1>":   PN = "30"  !CDS_PN = "30";
"VOS":   PN = "1"  !CDS_PN = "1";
BODY = "RES","I75": #LOCATION = "R1D54" !CDS_LOCATION = "R1D54" &SEC = "1" #&CDS_SEC = "1";
"A":   PN = "1"  !CDS_PN = "1";
"B":   PN = "2"  !CDS_PN = "2";
BODY = "RES","I76": #LOCATION = "R1D55" !CDS_LOCATION = "R1D55" &SEC = "1" #&CDS_SEC = "1";
"A":   PN = "1"  !CDS_PN = "1";
"B":   PN = "2"  !CDS_PN = "2";
BODY = "CAP_A","I80": #LOCATION = "CT16" !CDS_LOCATION = "CT16" &SEC = "1" #&CDS_SEC = "1";
"A":   PN = "1"  !CDS_PN = "1";
"B":   PN = "2"  !CDS_PN = "2";
BODY = "CAP","I82": #LOCATION = "CTI7" !CDS_LOCATION = "CTI7" &SEC = "1" #&CDS_SEC = "1";
"A":   PN = "1"  !CDS_PN = "1";
"B":   PN = "2"  !CDS_PN = "2";
BODY = "SC2K2P50V3KX-GP","I84": #LOCATION = "CT18" !CDS_LOCATION = "CT18" &SEC = "1" #&CDS_SEC = "1";
"1":   PN = "1"  !CDS_PN = "1";
"2":   PN = "2"  !CDS_PN = "2";
BODY = "CAP_A","I87": #LOCATION = "CT21" !CDS_LOCATION = "CT21" &SEC = "1" #&CDS_SEC = "1";
"A":   PN = "1"  !CDS_PN = "1";
"B":   PN = "2"  !CDS_PN = "2";
BODY = "CAP","I90": #LOCATION = "CT19" !CDS_LOCATION = "CT19" &SEC = "1" #&CDS_SEC = "1";
"A":   PN = "1"  !CDS_PN = "1";
"B":   PN = "2"  !CDS_PN = "2";
BODY = "SC2K2P50V3KX-GP","I92": #LOCATION = "CT20" !CDS_LOCATION = "CT20" &SEC = "1" #&CDS_SEC = "1";
"1":   PN = "1"  !CDS_PN = "1";
"2":   PN = "2"  !CDS_PN = "2";
BODY = "3D01R5F-GP","I94": #LOCATION = "RT13" !CDS_LOCATION = "RT13" &SEC = "1" #&CDS_SEC = "1";
"1":   PN = "1"  !CDS_PN = "1";
"2":   PN = "2"  !CDS_PN = "2";
BODY = "3D01R5F-GP","I86": #LOCATION = "RT12" !CDS_LOCATION = "RT12" &SEC = "1" #&CDS_SEC = "1";
"1":   PN = "1"  !CDS_PN = "1";
"2":   PN = "2"  !CDS_PN = "2";
BODY = "RES","I96": #LOCATION = "RT11" !CDS_LOCATION = "RT11" &SEC = "1" #&CDS_SEC = "1";
"A":   PN = "1"  !CDS_PN = "1";
"B":   PN = "2"  !CDS_PN = "2";
BODY = "RES","I97": #LOCATION = "RT14" !CDS_LOCATION = "RT14" &SEC = "1" #&CDS_SEC = "1";
"A":   PN = "1"  !CDS_PN = "1";
"B":   PN = "2"  !CDS_PN = "2";
DRAWING = "@baseboard_fab2_lib.baseboard_fab2(sch_1):page207";
BODY = "CAP_A","I8": #LOCATION = "C9R8" !CDS_LOCATION = "C9R8" #SEC = "1" !CDS_SEC = "1";
"A":   PN = "1"  !CDS_PN = "1";
"B":   PN = "2"  !CDS_PN = "2";
BODY = "INDUCTOR","I10": #LOCATION = "L1E1" !CDS_LOCATION = "L1E1" &SEC = "1" #&CDS_SEC = "1";
"INA":   PN = "1"  !CDS_PN = "1";
"INB":   PN = "2"  !CDS_PN = "2";
BODY = "INDUCTOR","I16": #LOCATION = "L1D3" !CDS_LOCATION = "L1D3" &SEC = "1" #&CDS_SEC = "1";
"INA":   PN = "1"  !CDS_PN = "1";
"INB":   PN = "2"  !CDS_PN = "2";
BODY = "CAP_A","I18": #LOCATION = "C1E3" !CDS_LOCATION = "C1E3" #SEC = "1" !CDS_SEC = "1";
"A":   PN = "1"  !CDS_PN = "1";
"B":   PN = "2"  !CDS_PN = "2";
BODY = "IR354XX","I20": #LOCATION = "EU1E2" !CDS_LOCATION = "EU1E2" #SEC = "1" !CDS_SEC = "1";
"BOOST":   PN = "33"  !CDS_PN = "33";
"EN":   PN = "35"  !CDS_PN = "35";
"GL<0>":   PN = "6"  !CDS_PN = "6";
"GL<1>":   PN = "41"  !CDS_PN = "41";
"IOUT":   PN = "38"  !CDS_PN = "38";
"LGND":   PN = "2"  !CDS_PN = "2";
"NC":   PN = "31"  !CDS_PN = "31";
"OCSET":   PN = "37"  !CDS_PN = "37";
"PGND<0>":   PN = "5"  !CDS_PN = "5";
"PGND<1>":   PN = "7"  !CDS_PN = "7";
"PGND<2>":   PN = "40"  !CDS_PN = "40";
"PHASE":   PN = "32"  !CDS_PN = "32";
"PWM":   PN = "34"  !CDS_PN = "34";
"REFIN":   PN = "39"  !CDS_PN = "39";
"SW":   PN = "10"  !CDS_PN = "10";
"TOUT_FLT":   PN = "36"  !CDS_PN = "36";
"VCC":   PN = "3"  !CDS_PN = "3";
"VDRV":   PN = "4"  !CDS_PN = "4";
"VIN<0>":   PN = "25"  !CDS_PN = "25";
"VIN<1>":   PN = "30"  !CDS_PN = "30";
"VOS":   PN = "1"  !CDS_PN = "1";
BODY = "IR354XX","I24": #LOCATION = "EU1D4" !CDS_LOCATION = "EU1D4" #SEC = "1" !CDS_SEC = "1";
"BOOST":   PN = "33"  !CDS_PN = "33";
"EN":   PN = "35"  !CDS_PN = "35";
"GL<0>":   PN = "6"  !CDS_PN = "6";
"GL<1>":   PN = "41"  !CDS_PN = "41";
"IOUT":   PN = "38"  !CDS_PN = "38";
"LGND":   PN = "2"  !CDS_PN = "2";
"NC":   PN = "31"  !CDS_PN = "31";
"OCSET":   PN = "37"  !CDS_PN = "37";
"PGND<0>":   PN = "5"  !CDS_PN = "5";
"PGND<1>":   PN = "7"  !CDS_PN = "7";
"PGND<2>":   PN = "40"  !CDS_PN = "40";
"PHASE":   PN = "32"  !CDS_PN = "32";
"PWM":   PN = "34"  !CDS_PN = "34";
"REFIN":   PN = "39"  !CDS_PN = "39";
"SW":   PN = "10"  !CDS_PN = "10";
"TOUT_FLT":   PN = "36"  !CDS_PN = "36";
"VCC":   PN = "3"  !CDS_PN = "3";
"VDRV":   PN = "4"  !CDS_PN = "4";
"VIN<0>":   PN = "25"  !CDS_PN = "25";
"VIN<1>":   PN = "30"  !CDS_PN = "30";
"VOS":   PN = "1"  !CDS_PN = "1";
BODY = "RES","I26": #LOCATION = "R9R2" !CDS_LOCATION = "R9R2" #SEC = "1" !CDS_SEC = "1";
"A":   PN = "1"  !CDS_PN = "1";
"B":   PN = "2"  !CDS_PN = "2";
BODY = "CAP","I28": #LOCATION = "C1E7" !CDS_LOCATION = "C1E7" #SEC = "1" !CDS_SEC = "1";
"A":   PN = "1"  !CDS_PN = "1";
"B":   PN = "2"  !CDS_PN = "2";
BODY = "CAP_A","I29": #LOCATION = "C1E6" !CDS_LOCATION = "C1E6" #SEC = "1" !CDS_SEC = "1";
"A":   PN = "1"  !CDS_PN = "1";
"B":   PN = "2"  !CDS_PN = "2";
BODY = "CAP","I30": #LOCATION = "C1E11" !CDS_LOCATION = "C1E11" #SEC = "1" !CDS_SEC = "1";
"A":   PN = "1"  !CDS_PN = "1";
"B":   PN = "2"  !CDS_PN = "2";
BODY = "CAP","I32": #LOCATION = "C1E8" !CDS_LOCATION = "C1E8" #SEC = "1" !CDS_SEC = "1";
"A":   PN = "1"  !CDS_PN = "1";
"B":   PN = "2"  !CDS_PN = "2";
BODY = "CAP_A","I33": #LOCATION = "C1E14" !CDS_LOCATION = "C1E14" #SEC = "1" !CDS_SEC = "1";
"A":   PN = "1"  !CDS_PN = "1";
"B":   PN = "2"  !CDS_PN = "2";
BODY = "CAP","I34": #LOCATION = "C1E13" !CDS_LOCATION = "C1E13" #SEC = "1" !CDS_SEC = "1";
"A":   PN = "1"  !CDS_PN = "1";
"B":   PN = "2"  !CDS_PN = "2";
BODY = "CAP","I36": #LOCATION = "C1E25" !CDS_LOCATION = "C1E25" #SEC = "1" !CDS_SEC = "1";
"A":   PN = "1"  !CDS_PN = "1";
"B":   PN = "2"  !CDS_PN = "2";
BODY = "CAP_A","I37": #LOCATION = "C1E23" !CDS_LOCATION = "C1E23" #SEC = "1" !CDS_SEC = "1";
"A":   PN = "1"  !CDS_PN = "1";
"B":   PN = "2"  !CDS_PN = "2";
BODY = "CAP","I38": #LOCATION = "C1D36" !CDS_LOCATION = "C1D36" #SEC = "1" !CDS_SEC = "1";
"A":   PN = "1"  !CDS_PN = "1";
"B":   PN = "2"  !CDS_PN = "2";
BODY = "RES","I39": #LOCATION = "R9R11" !CDS_LOCATION = "R9R11" #SEC = "1" !CDS_SEC = "1";
"A":   PN = "1"  !CDS_PN = "1";
"B":   PN = "2"  !CDS_PN = "2";
BODY = "CAP","I40": #LOCATION = "C1E24" !CDS_LOCATION = "C1E24" #SEC = "1" !CDS_SEC = "1";
"A":   PN = "1"  !CDS_PN = "1";
"B":   PN = "2"  !CDS_PN = "2";
BODY = "CAP_A","I41": #LOCATION = "C1D34" !CDS_LOCATION = "C1D34" #SEC = "1" !CDS_SEC = "1";
"A":   PN = "1"  !CDS_PN = "1";
"B":   PN = "2"  !CDS_PN = "2";
BODY = "CAP","I42": #LOCATION = "C1D35" !CDS_LOCATION = "C1D35" #SEC = "1" !CDS_SEC = "1";
"A":   PN = "1"  !CDS_PN = "1";
"B":   PN = "2"  !CDS_PN = "2";
BODY = "CAP","I43": #LOCATION = "C9R7" !CDS_LOCATION = "C9R7" #SEC = "1" !CDS_SEC = "1";
"A":   PN = "1"  !CDS_PN = "1";
"B":   PN = "2"  !CDS_PN = "2";
BODY = "CAP","I44": #LOCATION = "C9R10" !CDS_LOCATION = "C9R10" #SEC = "1" !CDS_SEC = "1";
"A":   PN = "1"  !CDS_PN = "1";
"B":   PN = "2"  !CDS_PN = "2";
BODY = "CAP","I48": #LOCATION = "C9R11" !CDS_LOCATION = "C9R11" #SEC = "1" !CDS_SEC = "1";
"A":   PN = "1"  !CDS_PN = "1";
"B":   PN = "2"  !CDS_PN = "2";
BODY = "CAP","I50": #LOCATION = "C9P22" !CDS_LOCATION = "C9P22" #SEC = "1" !CDS_SEC = "1";
"A":   PN = "1"  !CDS_PN = "1";
"B":   PN = "2"  !CDS_PN = "2";
BODY = "CAP","I51": #LOCATION = "C9P25" !CDS_LOCATION = "C9P25" #SEC = "1" !CDS_SEC = "1";
"A":   PN = "1"  !CDS_PN = "1";
"B":   PN = "2"  !CDS_PN = "2";
BODY = "CAP","I54": #LOCATION = "C9P26" !CDS_LOCATION = "C9P26" #SEC = "1" !CDS_SEC = "1";
"A":   PN = "1"  !CDS_PN = "1";
"B":   PN = "2"  !CDS_PN = "2";
BODY = "CAP_A","I58": #LOCATION = "C1E9" !CDS_LOCATION = "C1E9" #SEC = "1" !CDS_SEC = "1";
"A":   PN = "1"  !CDS_PN = "1";
"B":   PN = "2"  !CDS_PN = "2";
BODY = "CAP_A","I59": #LOCATION = "C9P3" !CDS_LOCATION = "C9P3" #SEC = "1" !CDS_SEC = "1";
"A":   PN = "1"  !CDS_PN = "1";
"B":   PN = "2"  !CDS_PN = "2";
BODY = "RES","I67": #LOCATION = "R1E13" !CDS_LOCATION = "R1E13" &SEC = "1" #&CDS_SEC = "1";
"A":   PN = "1"  !CDS_PN = "1";
"B":   PN = "2"  !CDS_PN = "2";
BODY = "RES","I68": #LOCATION = "R1E14" !CDS_LOCATION = "R1E14" &SEC = "1" #&CDS_SEC = "1";
"A":   PN = "1"  !CDS_PN = "1";
"B":   PN = "2"  !CDS_PN = "2";
BODY = "CAP_A","I71": #LOCATION = "CT24" !CDS_LOCATION = "CT24" &SEC = "1" #&CDS_SEC = "1";
"A":   PN = "1"  !CDS_PN = "1";
"B":   PN = "2"  !CDS_PN = "2";
BODY = "CAP","I74": #LOCATION = "CT22" !CDS_LOCATION = "CT22" &SEC = "1" #&CDS_SEC = "1";
"A":   PN = "1"  !CDS_PN = "1";
"B":   PN = "2"  !CDS_PN = "2";
BODY = "SC2K2P50V3KX-GP","I77": #LOCATION = "CT23" !CDS_LOCATION = "CT23" &SEC = "1" #&CDS_SEC = "1";
"1":   PN = "1"  !CDS_PN = "1";
"2":   PN = "2"  !CDS_PN = "2";
BODY = "CAP_A","I81": #LOCATION = "CT25" !CDS_LOCATION = "CT25" &SEC = "1" #&CDS_SEC = "1";
"A":   PN = "1"  !CDS_PN = "1";
"B":   PN = "2"  !CDS_PN = "2";
BODY = "CAP","I82": #LOCATION = "CT26" !CDS_LOCATION = "CT26" &SEC = "1" #&CDS_SEC = "1";
"A":   PN = "1"  !CDS_PN = "1";
"B":   PN = "2"  !CDS_PN = "2";
BODY = "SC2K2P50V3KX-GP","I84": #LOCATION = "CT27" !CDS_LOCATION = "CT27" &SEC = "1" #&CDS_SEC = "1";
"1":   PN = "1"  !CDS_PN = "1";
"2":   PN = "2"  !CDS_PN = "2";
BODY = "3D01R5F-GP","I85": #LOCATION = "RT18" !CDS_LOCATION = "RT18" &SEC = "1" #&CDS_SEC = "1";
"1":   PN = "1"  !CDS_PN = "1";
"2":   PN = "2"  !CDS_PN = "2";
BODY = "3D01R5F-GP","I76": #LOCATION = "RT16" !CDS_LOCATION = "RT16" &SEC = "1" #&CDS_SEC = "1";
"1":   PN = "1"  !CDS_PN = "1";
"2":   PN = "2"  !CDS_PN = "2";
BODY = "RES","I87": #LOCATION = "RT15" !CDS_LOCATION = "RT15" &SEC = "1" #&CDS_SEC = "1";
"A":   PN = "1"  !CDS_PN = "1";
"B":   PN = "2"  !CDS_PN = "2";
BODY = "RES","I88": #LOCATION = "RT17" !CDS_LOCATION = "RT17" &SEC = "1" #&CDS_SEC = "1";
"A":   PN = "1"  !CDS_PN = "1";
"B":   PN = "2"  !CDS_PN = "2";
DRAWING = "@baseboard_fab2_lib.baseboard_fab2(sch_1):page224";
BODY = "CAP","I6": #LOCATION = "C1G17" !CDS_LOCATION = "C1G17" #SEC = "1" !CDS_SEC = "1";
"A":   PN = "1"  !CDS_PN = "1";
"B":   PN = "2"  !CDS_PN = "2";
BODY = "CAP","I44": #LOCATION = "C1G11" !CDS_LOCATION = "C1G11" #SEC = "1" !CDS_SEC = "1";
"A":   PN = "1"  !CDS_PN = "1";
"B":   PN = "2"  !CDS_PN = "2";
BODY = "CAP","I45": #LOCATION = "C9U6" !CDS_LOCATION = "C9U6" #SEC = "1" !CDS_SEC = "1";
"A":   PN = "1"  !CDS_PN = "1";
"B":   PN = "2"  !CDS_PN = "2";
BODY = "CAP","I46": #LOCATION = "C9U4" !CDS_LOCATION = "C9U4" #SEC = "1" !CDS_SEC = "1";
"A":   PN = "1"  !CDS_PN = "1";
"B":   PN = "2"  !CDS_PN = "2";
BODY = "CAP","I47": #LOCATION = "C9T4" !CDS_LOCATION = "C9T4" #SEC = "1" !CDS_SEC = "1";
"A":   PN = "1"  !CDS_PN = "1";
"B":   PN = "2"  !CDS_PN = "2";
BODY = "CAP","I48": #LOCATION = "C1F27" !CDS_LOCATION = "C1F27" #SEC = "1" !CDS_SEC = "1";
"A":   PN = "1"  !CDS_PN = "1";
"B":   PN = "2"  !CDS_PN = "2";
BODY = "CAP","I50": #LOCATION = "C1G6" !CDS_LOCATION = "C1G6" #SEC = "1" !CDS_SEC = "1";
"A":   PN = "1"  !CDS_PN = "1";
"B":   PN = "2"  !CDS_PN = "2";
BODY = "CAP_A","I51": #LOCATION = "C1G14" !CDS_LOCATION = "C1G14" #SEC = "1" !CDS_SEC = "1";
"A":   PN = "1"  !CDS_PN = "1";
"B":   PN = "2"  !CDS_PN = "2";
BODY = "RES","I52": #LOCATION = "R9U1" !CDS_LOCATION = "R9U1" #SEC = "1" !CDS_SEC = "1";
"A":   PN = "1"  !CDS_PN = "1";
"B":   PN = "2"  !CDS_PN = "2";
BODY = "CAP_A","I53": #LOCATION = "C1G4" !CDS_LOCATION = "C1G4" #SEC = "1" !CDS_SEC = "1";
"A":   PN = "1"  !CDS_PN = "1";
"B":   PN = "2"  !CDS_PN = "2";
BODY = "CAP","I54": #LOCATION = "C1G5" !CDS_LOCATION = "C1G5" #SEC = "1" !CDS_SEC = "1";
"A":   PN = "1"  !CDS_PN = "1";
"B":   PN = "2"  !CDS_PN = "2";
BODY = "INDUCTOR","I55": #LOCATION = "L1G1" !CDS_LOCATION = "L1G1" #SEC = "1" !CDS_SEC = "1";
"INA":   PN = "1"  !CDS_PN = "1";
"INB":   PN = "2"  !CDS_PN = "2";
BODY = "INDUCTOR","I65": #LOCATION = "L1F2" !CDS_LOCATION = "L1F2" #SEC = "1" !CDS_SEC = "1";
"INA":   PN = "1"  !CDS_PN = "1";
"INB":   PN = "2"  !CDS_PN = "2";
BODY = "CAP","I68": #LOCATION = "C1G20" !CDS_LOCATION = "C1G20" #SEC = "1" !CDS_SEC = "1";
"A":   PN = "1"  !CDS_PN = "1";
"B":   PN = "2"  !CDS_PN = "2";
BODY = "CAP","I72": #LOCATION = "C1G29" !CDS_LOCATION = "C1G29" #SEC = "1" !CDS_SEC = "1";
"A":   PN = "1"  !CDS_PN = "1";
"B":   PN = "2"  !CDS_PN = "2";
BODY = "CAP_A","I73": #LOCATION = "C1F21" !CDS_LOCATION = "C1F21" #SEC = "1" !CDS_SEC = "1";
"A":   PN = "1"  !CDS_PN = "1";
"B":   PN = "2"  !CDS_PN = "2";
BODY = "CAP","I75": #LOCATION = "C1F26" !CDS_LOCATION = "C1F26" #SEC = "1" !CDS_SEC = "1";
"A":   PN = "1"  !CDS_PN = "1";
"B":   PN = "2"  !CDS_PN = "2";
BODY = "RES","I76": #LOCATION = "R9U12" !CDS_LOCATION = "R9U12" #SEC = "1" !CDS_SEC = "1";
"A":   PN = "1"  !CDS_PN = "1";
"B":   PN = "2"  !CDS_PN = "2";
BODY = "CAP","I77": #LOCATION = "C1G28" !CDS_LOCATION = "C1G28" #SEC = "1" !CDS_SEC = "1";
"A":   PN = "1"  !CDS_PN = "1";
"B":   PN = "2"  !CDS_PN = "2";
BODY = "CAP_A","I78": #LOCATION = "C1F28" !CDS_LOCATION = "C1F28" #SEC = "1" !CDS_SEC = "1";
"A":   PN = "1"  !CDS_PN = "1";
"B":   PN = "2"  !CDS_PN = "2";
BODY = "CAP","I79": #LOCATION = "C1G13" !CDS_LOCATION = "C1G13" #SEC = "1" !CDS_SEC = "1";
"A":   PN = "1"  !CDS_PN = "1";
"B":   PN = "2"  !CDS_PN = "2";
BODY = "CAP","I80": #LOCATION = "C9U3" !CDS_LOCATION = "C9U3" #SEC = "1" !CDS_SEC = "1";
"A":   PN = "1"  !CDS_PN = "1";
"B":   PN = "2"  !CDS_PN = "2";
BODY = "CAP","I81": #LOCATION = "C9T6" !CDS_LOCATION = "C9T6" #SEC = "1" !CDS_SEC = "1";
"A":   PN = "1"  !CDS_PN = "1";
"B":   PN = "2"  !CDS_PN = "2";
BODY = "CAP","I84": #LOCATION = "C9T9" !CDS_LOCATION = "C9T9" #SEC = "1" !CDS_SEC = "1";
"A":   PN = "1"  !CDS_PN = "1";
"B":   PN = "2"  !CDS_PN = "2";
BODY = "IR354XX","I110": #LOCATION = "EU1G1" !CDS_LOCATION = "EU1G1" #SEC = "1" !CDS_SEC = "1";
"BOOST":   PN = "33"  !CDS_PN = "33";
"EN":   PN = "35"  !CDS_PN = "35";
"GL<0>":   PN = "6"  !CDS_PN = "6";
"GL<1>":   PN = "41"  !CDS_PN = "41";
"IOUT":   PN = "38"  !CDS_PN = "38";
"LGND":   PN = "2"  !CDS_PN = "2";
"NC":   PN = "31"  !CDS_PN = "31";
"OCSET":   PN = "37"  !CDS_PN = "37";
"PGND<0>":   PN = "5"  !CDS_PN = "5";
"PGND<1>":   PN = "7"  !CDS_PN = "7";
"PGND<2>":   PN = "40"  !CDS_PN = "40";
"PHASE":   PN = "32"  !CDS_PN = "32";
"PWM":   PN = "34"  !CDS_PN = "34";
"REFIN":   PN = "39"  !CDS_PN = "39";
"SW":   PN = "10"  !CDS_PN = "10";
"TOUT_FLT":   PN = "36"  !CDS_PN = "36";
"VCC":   PN = "3"  !CDS_PN = "3";
"VDRV":   PN = "4"  !CDS_PN = "4";
"VIN<0>":   PN = "25"  !CDS_PN = "25";
"VIN<1>":   PN = "30"  !CDS_PN = "30";
"VOS":   PN = "1"  !CDS_PN = "1";
BODY = "IR354XX","I111": #LOCATION = "EU1F1" !CDS_LOCATION = "EU1F1" #SEC = "1" !CDS_SEC = "1";
"BOOST":   PN = "33"  !CDS_PN = "33";
"EN":   PN = "35"  !CDS_PN = "35";
"GL<0>":   PN = "6"  !CDS_PN = "6";
"GL<1>":   PN = "41"  !CDS_PN = "41";
"IOUT":   PN = "38"  !CDS_PN = "38";
"LGND":   PN = "2"  !CDS_PN = "2";
"NC":   PN = "31"  !CDS_PN = "31";
"OCSET":   PN = "37"  !CDS_PN = "37";
"PGND<0>":   PN = "5"  !CDS_PN = "5";
"PGND<1>":   PN = "7"  !CDS_PN = "7";
"PGND<2>":   PN = "40"  !CDS_PN = "40";
"PHASE":   PN = "32"  !CDS_PN = "32";
"PWM":   PN = "34"  !CDS_PN = "34";
"REFIN":   PN = "39"  !CDS_PN = "39";
"SW":   PN = "10"  !CDS_PN = "10";
"TOUT_FLT":   PN = "36"  !CDS_PN = "36";
"VCC":   PN = "3"  !CDS_PN = "3";
"VDRV":   PN = "4"  !CDS_PN = "4";
"VIN<0>":   PN = "25"  !CDS_PN = "25";
"VIN<1>":   PN = "30"  !CDS_PN = "30";
"VOS":   PN = "1"  !CDS_PN = "1";
BODY = "RES","I112": #LOCATION = "R1G26" !CDS_LOCATION = "R1G26" &SEC = "1" #&CDS_SEC = "1";
"A":   PN = "1"  !CDS_PN = "1";
"B":   PN = "2"  !CDS_PN = "2";
BODY = "RES","I114": #LOCATION = "R1G25" !CDS_LOCATION = "R1G25" &SEC = "1" #&CDS_SEC = "1";
"A":   PN = "1"  !CDS_PN = "1";
"B":   PN = "2"  !CDS_PN = "2";
BODY = "CAP_A","I117": #LOCATION = "CT30" !CDS_LOCATION = "CT30" &SEC = "1" #&CDS_SEC = "1";
"A":   PN = "1"  !CDS_PN = "1";
"B":   PN = "2"  !CDS_PN = "2";
BODY = "SC2K2P50V3KX-GP","I121": #LOCATION = "CT29" !CDS_LOCATION = "CT29" &SEC = "1" #&CDS_SEC = "1";
"1":   PN = "1"  !CDS_PN = "1";
"2":   PN = "2"  !CDS_PN = "2";
BODY = "CAP","I122": #LOCATION = "CT28" !CDS_LOCATION = "CT28" &SEC = "1" #&CDS_SEC = "1";
"A":   PN = "1"  !CDS_PN = "1";
"B":   PN = "2"  !CDS_PN = "2";
BODY = "CAP_A","I124": #LOCATION = "CT31" !CDS_LOCATION = "CT31" &SEC = "1" #&CDS_SEC = "1";
"A":   PN = "1"  !CDS_PN = "1";
"B":   PN = "2"  !CDS_PN = "2";
BODY = "SC2K2P50V3KX-GP","I127": #LOCATION = "CT33" !CDS_LOCATION = "CT33" &SEC = "1" #&CDS_SEC = "1";
"1":   PN = "1"  !CDS_PN = "1";
"2":   PN = "2"  !CDS_PN = "2";
BODY = "CAP","I130": #LOCATION = "CT32" !CDS_LOCATION = "CT32" &SEC = "1" #&CDS_SEC = "1";
"A":   PN = "1"  !CDS_PN = "1";
"B":   PN = "2"  !CDS_PN = "2";
BODY = "3D01R5F-GP","I129": #LOCATION = "RT22" !CDS_LOCATION = "RT22" &SEC = "1" #&CDS_SEC = "1";
"1":   PN = "1"  !CDS_PN = "1";
"2":   PN = "2"  !CDS_PN = "2";
BODY = "3D01R5F-GP","I119": #LOCATION = "RT20" !CDS_LOCATION = "RT20" &SEC = "1" #&CDS_SEC = "1";
"1":   PN = "1"  !CDS_PN = "1";
"2":   PN = "2"  !CDS_PN = "2";
BODY = "RES","I132": #LOCATION = "RT19" !CDS_LOCATION = "RT19" &SEC = "1" #&CDS_SEC = "1";
"A":   PN = "1"  !CDS_PN = "1";
"B":   PN = "2"  !CDS_PN = "2";
BODY = "RES","I133": #LOCATION = "RT21" !CDS_LOCATION = "RT21" &SEC = "1" #&CDS_SEC = "1";
"A":   PN = "1"  !CDS_PN = "1";
"B":   PN = "2"  !CDS_PN = "2";
DRAWING = "@baseboard_fab2_lib.baseboard_fab2(sch_1):page204";
BODY = "INDUCTOR","I5": #LOCATION = "L4C3" !CDS_LOCATION = "L4C3" &SEC = "1" #&CDS_SEC = "1";
"INA":   PN = "1"  !CDS_PN = "1";
"INB":   PN = "2"  !CDS_PN = "2";
BODY = "CAP_A","I9": #LOCATION = "C4D12" !CDS_LOCATION = "C4D12" #SEC = "1" !CDS_SEC = "1";
"A":   PN = "1"  !CDS_PN = "1";
"B":   PN = "2"  !CDS_PN = "2";
BODY = "CAP","I18": #LOCATION = "C4D47" !CDS_LOCATION = "C4D47" #SEC = "1" !CDS_SEC = "1";
"A":   PN = "1"  !CDS_PN = "1";
"B":   PN = "2"  !CDS_PN = "2";
BODY = "CAP_A","I19": #LOCATION = "C4C14" !CDS_LOCATION = "C4C14" #SEC = "1" !CDS_SEC = "1";
"A":   PN = "1"  !CDS_PN = "1";
"B":   PN = "2"  !CDS_PN = "2";
BODY = "CAP","I22": #LOCATION = "C4C17" !CDS_LOCATION = "C4C17" #SEC = "1" !CDS_SEC = "1";
"A":   PN = "1"  !CDS_PN = "1";
"B":   PN = "2"  !CDS_PN = "2";
BODY = "RES","I33": #LOCATION = "R6P47" !CDS_LOCATION = "R6P47" #SEC = "1" !CDS_SEC = "1";
"A":   PN = "1"  !CDS_PN = "1";
"B":   PN = "2"  !CDS_PN = "2";
BODY = "CAP","I34": #LOCATION = "C4D46" !CDS_LOCATION = "C4D46" #SEC = "1" !CDS_SEC = "1";
"A":   PN = "1"  !CDS_PN = "1";
"B":   PN = "2"  !CDS_PN = "2";
BODY = "CAP_A","I35": #LOCATION = "C4C19" !CDS_LOCATION = "C4C19" #SEC = "1" !CDS_SEC = "1";
"A":   PN = "1"  !CDS_PN = "1";
"B":   PN = "2"  !CDS_PN = "2";
BODY = "CAP","I36": #LOCATION = "C4C18" !CDS_LOCATION = "C4C18" #SEC = "1" !CDS_SEC = "1";
"A":   PN = "1"  !CDS_PN = "1";
"B":   PN = "2"  !CDS_PN = "2";
BODY = "CAP","I37": #LOCATION = "C6N10" !CDS_LOCATION = "C6N10" #SEC = "1" !CDS_SEC = "1";
"A":   PN = "1"  !CDS_PN = "1";
"B":   PN = "2"  !CDS_PN = "2";
BODY = "CAP","I38": #LOCATION = "C6P17" !CDS_LOCATION = "C6P17" #SEC = "1" !CDS_SEC = "1";
"A":   PN = "1"  !CDS_PN = "1";
"B":   PN = "2"  !CDS_PN = "2";
BODY = "CAP","I42": #LOCATION = "C6N11" !CDS_LOCATION = "C6N11" #SEC = "1" !CDS_SEC = "1";
"A":   PN = "1"  !CDS_PN = "1";
"B":   PN = "2"  !CDS_PN = "2";
BODY = "RES","I45": #LOCATION = "R4C6" !CDS_LOCATION = "R4C6" #SEC = "1" !CDS_SEC = "1";
"A":   PN = "1"  !CDS_PN = "1";
"B":   PN = "2"  !CDS_PN = "2";
BODY = "INDUCTOR","I46": #LOCATION = "L4C1" !CDS_LOCATION = "L4C1" #SEC = "1" !CDS_SEC = "1";
"INA":   PN = "1"  !CDS_PN = "1";
"INB":   PN = "2"  !CDS_PN = "2";
BODY = "CAPP","I48": #LOCATION = "C4D2" !CDS_LOCATION = "C4D2" #SEC = "1" !CDS_SEC = "1";
"A":   PN = "1"  !CDS_PN = "1";
"B":   PN = "2"  !CDS_PN = "2";
BODY = "CAPP","I50": #LOCATION = "C4E16" !CDS_LOCATION = "C4E16" #SEC = "1" !CDS_SEC = "1";
"A":   PN = "1"  !CDS_PN = "1";
"B":   PN = "2"  !CDS_PN = "2";
BODY = "CAP_A","I51": #LOCATION = "C4C2" !CDS_LOCATION = "C4C2" &SEC = "1" #&CDS_SEC = "1";
"A":   PN = "1"  !CDS_PN = "1";
"B":   PN = "2"  !CDS_PN = "2";
BODY = "ADM4073","I53": #LOCATION = "U4C1" !CDS_LOCATION = "U4C1" #SEC = "1" !CDS_SEC = "1";
"GND<0>":   PN = "1"  !CDS_PN = "1";
"GND<1>":   PN = "2"  !CDS_PN = "2";
"OUT":   PN = "6"  !CDS_PN = "6";
"RSN":   PN = "5"  !CDS_PN = "5";
"RSP":   PN = "4"  !CDS_PN = "4";
"VCC":   PN = "3"  !CDS_PN = "3";
BODY = "RES","I60": #LOCATION = "R4E14" !CDS_LOCATION = "R4E14" &SEC = "1" #&CDS_SEC = "1";
"A":   PN = "1"  !CDS_PN = "1";
"B":   PN = "2"  !CDS_PN = "2";
BODY = "RES","I61": #LOCATION = "R4E16" !CDS_LOCATION = "R4E16" &SEC = "1" #&CDS_SEC = "1";
"A":   PN = "1"  !CDS_PN = "1";
"B":   PN = "2"  !CDS_PN = "2";
BODY = "RES","I62": #LOCATION = "R4E17" !CDS_LOCATION = "R4E17" &SEC = "1" #&CDS_SEC = "1";
"A":   PN = "1"  !CDS_PN = "1";
"B":   PN = "2"  !CDS_PN = "2";
BODY = "RES","I63": #LOCATION = "R4E15" !CDS_LOCATION = "R4E15" &SEC = "1" #&CDS_SEC = "1";
"A":   PN = "1"  !CDS_PN = "1";
"B":   PN = "2"  !CDS_PN = "2";
BODY = "RES","I64": #LOCATION = "R4E18" !CDS_LOCATION = "R4E18" &SEC = "1" #&CDS_SEC = "1";
"A":   PN = "1"  !CDS_PN = "1";
"B":   PN = "2"  !CDS_PN = "2";
BODY = "CAPP","I67": #LOCATION = "C4C12" !CDS_LOCATION = "C4C12" #SEC = "1" !CDS_SEC = "1";
"A":   PN = "1"  !CDS_PN = "1";
"B":   PN = "2"  !CDS_PN = "2";
BODY = "CAP_A","I70": #LOCATION = "C6R2" !CDS_LOCATION = "C6R2" #SEC = "1" !CDS_SEC = "1";
"A":   PN = "1"  !CDS_PN = "1";
"B":   PN = "2"  !CDS_PN = "2";
BODY = "IR354XX","I71": #LOCATION = "EU4C2" !CDS_LOCATION = "EU4C2" &SEC = "1" #&CDS_SEC = "1";
"BOOST":   PN = "33"  !CDS_PN = "33";
"EN":   PN = "35"  !CDS_PN = "35";
"GL<0>":   PN = "6"  !CDS_PN = "6";
"GL<1>":   PN = "41"  !CDS_PN = "41";
"IOUT":   PN = "38"  !CDS_PN = "38";
"LGND":   PN = "2"  !CDS_PN = "2";
"NC":   PN = "31"  !CDS_PN = "31";
"OCSET":   PN = "37"  !CDS_PN = "37";
"PGND<0>":   PN = "5"  !CDS_PN = "5";
"PGND<1>":   PN = "7"  !CDS_PN = "7";
"PGND<2>":   PN = "40"  !CDS_PN = "40";
"PHASE":   PN = "32"  !CDS_PN = "32";
"PWM":   PN = "34"  !CDS_PN = "34";
"REFIN":   PN = "39"  !CDS_PN = "39";
"SW":   PN = "10"  !CDS_PN = "10";
"TOUT_FLT":   PN = "36"  !CDS_PN = "36";
"VCC":   PN = "3"  !CDS_PN = "3";
"VDRV":   PN = "4"  !CDS_PN = "4";
"VIN<0>":   PN = "25"  !CDS_PN = "25";
"VIN<1>":   PN = "30"  !CDS_PN = "30";
"VOS":   PN = "1"  !CDS_PN = "1";
BODY = "RES","I83": #LOCATION = "R4D68" !CDS_LOCATION = "R4D68" #SEC = "1" !CDS_SEC = "1";
"A":   PN = "1"  !CDS_PN = "1";
"B":   PN = "2"  !CDS_PN = "2";
BODY = "CAP_A","I85": #LOCATION = "CT36" !CDS_LOCATION = "CT36" &SEC = "1" #&CDS_SEC = "1";
"A":   PN = "1"  !CDS_PN = "1";
"B":   PN = "2"  !CDS_PN = "2";
BODY = "CAP","I88": #LOCATION = "CT34" !CDS_LOCATION = "CT34" &SEC = "1" #&CDS_SEC = "1";
"A":   PN = "1"  !CDS_PN = "1";
"B":   PN = "2"  !CDS_PN = "2";
BODY = "SC2K2P50V3KX-GP","I90": #LOCATION = "CT35" !CDS_LOCATION = "CT35" &SEC = "1" #&CDS_SEC = "1";
"1":   PN = "1"  !CDS_PN = "1";
"2":   PN = "2"  !CDS_PN = "2";
BODY = "3D01R5F-GP","I91": #LOCATION = "RT24" !CDS_LOCATION = "RT24" &SEC = "1" #&CDS_SEC = "1";
"1":   PN = "1"  !CDS_PN = "1";
"2":   PN = "2"  !CDS_PN = "2";
BODY = "RES","I93": #LOCATION = "RT23" !CDS_LOCATION = "RT23" &SEC = "1" #&CDS_SEC = "1";
"A":   PN = "1"  !CDS_PN = "1";
"B":   PN = "2"  !CDS_PN = "2";
DRAWING = "@baseboard_fab2_lib.baseboard_fab2(sch_1):page203";
BODY = "CAP","I1": #LOCATION = "C6P24" !CDS_LOCATION = "C6P24" #SEC = "1" !CDS_SEC = "1";
"A":   PN = "1"  !CDS_PN = "1";
"B":   PN = "2"  !CDS_PN = "2";
BODY = "CAP","I2": #LOCATION = "C6R6" !CDS_LOCATION = "C6R6" #SEC = "1" !CDS_SEC = "1";
"A":   PN = "1"  !CDS_PN = "1";
"B":   PN = "2"  !CDS_PN = "2";
BODY = "CAP","I3": #LOCATION = "C4D9" !CDS_LOCATION = "C4D9" #SEC = "1" !CDS_SEC = "1";
"A":   PN = "1"  !CDS_PN = "1";
"B":   PN = "2"  !CDS_PN = "2";
BODY = "INDUCTOR","I15": #LOCATION = "L4D2" !CDS_LOCATION = "L4D2" &SEC = "1" #&CDS_SEC = "1";
"INA":   PN = "1"  !CDS_PN = "1";
"INB":   PN = "2"  !CDS_PN = "2";
BODY = "CAPP","I16": #LOCATION = "C6R3" !CDS_LOCATION = "C6R3" #SEC = "1" !CDS_SEC = "1";
"A":   PN = "1"  !CDS_PN = "1";
"B":   PN = "2"  !CDS_PN = "2";
BODY = "CAPP","I18": #LOCATION = "C6R9" !CDS_LOCATION = "C6R9" #SEC = "1" !CDS_SEC = "1";
"A":   PN = "1"  !CDS_PN = "1";
"B":   PN = "2"  !CDS_PN = "2";
BODY = "INDUCTOR","I24": #LOCATION = "L4D1" !CDS_LOCATION = "L4D1" &SEC = "1" #&CDS_SEC = "1";
"INA":   PN = "1"  !CDS_PN = "1";
"INB":   PN = "2"  !CDS_PN = "2";
BODY = "CAP_A","I25": #LOCATION = "C6P3" !CDS_LOCATION = "C6P3" #SEC = "1" !CDS_SEC = "1";
"A":   PN = "1"  !CDS_PN = "1";
"B":   PN = "2"  !CDS_PN = "2";
BODY = "CAPP","I28": #LOCATION = "C6P23" !CDS_LOCATION = "C6P23" #SEC = "1" !CDS_SEC = "1";
"A":   PN = "1"  !CDS_PN = "1";
"B":   PN = "2"  !CDS_PN = "2";
BODY = "CAPP","I29": #LOCATION = "C6P14" !CDS_LOCATION = "C6P14" #SEC = "1" !CDS_SEC = "1";
"A":   PN = "1"  !CDS_PN = "1";
"B":   PN = "2"  !CDS_PN = "2";
BODY = "CAPP","I30": #LOCATION = "C6P18" !CDS_LOCATION = "C6P18" #SEC = "1" !CDS_SEC = "1";
"A":   PN = "1"  !CDS_PN = "1";
"B":   PN = "2"  !CDS_PN = "2";
BODY = "CAPP","I32": #LOCATION = "C6P8" !CDS_LOCATION = "C6P8" #SEC = "1" !CDS_SEC = "1";
"A":   PN = "1"  !CDS_PN = "1";
"B":   PN = "2"  !CDS_PN = "2";
BODY = "CAPP","I34": #LOCATION = "C6N9" !CDS_LOCATION = "C6N9" #SEC = "1" !CDS_SEC = "1";
"A":   PN = "1"  !CDS_PN = "1";
"B":   PN = "2"  !CDS_PN = "2";
BODY = "RES","I38": #LOCATION = "R6P19" !CDS_LOCATION = "R6P19" #SEC = "1" !CDS_SEC = "1";
"A":   PN = "1"  !CDS_PN = "1";
"B":   PN = "2"  !CDS_PN = "2";
BODY = "CAP","I40": #LOCATION = "C4D13" !CDS_LOCATION = "C4D13" #SEC = "1" !CDS_SEC = "1";
"A":   PN = "1"  !CDS_PN = "1";
"B":   PN = "2"  !CDS_PN = "2";
BODY = "CAP_A","I41": #LOCATION = "C4D14" !CDS_LOCATION = "C4D14" #SEC = "1" !CDS_SEC = "1";
"A":   PN = "1"  !CDS_PN = "1";
"B":   PN = "2"  !CDS_PN = "2";
BODY = "CAP","I42": #LOCATION = "C4D28" !CDS_LOCATION = "C4D28" #SEC = "1" !CDS_SEC = "1";
"A":   PN = "1"  !CDS_PN = "1";
"B":   PN = "2"  !CDS_PN = "2";
BODY = "CAP","I45": #LOCATION = "C4D16" !CDS_LOCATION = "C4D16" #SEC = "1" !CDS_SEC = "1";
"A":   PN = "1"  !CDS_PN = "1";
"B":   PN = "2"  !CDS_PN = "2";
BODY = "CAP_A","I46": #LOCATION = "C4D35" !CDS_LOCATION = "C4D35" #SEC = "1" !CDS_SEC = "1";
"A":   PN = "1"  !CDS_PN = "1";
"B":   PN = "2"  !CDS_PN = "2";
BODY = "CAP","I47": #LOCATION = "C4D30" !CDS_LOCATION = "C4D30" #SEC = "1" !CDS_SEC = "1";
"A":   PN = "1"  !CDS_PN = "1";
"B":   PN = "2"  !CDS_PN = "2";
BODY = "CAP","I48": #LOCATION = "C4D5" !CDS_LOCATION = "C4D5" #SEC = "1" !CDS_SEC = "1";
"A":   PN = "1"  !CDS_PN = "1";
"B":   PN = "2"  !CDS_PN = "2";
BODY = "CAP_A","I49": #LOCATION = "C4D6" !CDS_LOCATION = "C4D6" #SEC = "1" !CDS_SEC = "1";
"A":   PN = "1"  !CDS_PN = "1";
"B":   PN = "2"  !CDS_PN = "2";
BODY = "RES","I50": #LOCATION = "R6P10" !CDS_LOCATION = "R6P10" #SEC = "1" !CDS_SEC = "1";
"A":   PN = "1"  !CDS_PN = "1";
"B":   PN = "2"  !CDS_PN = "2";
BODY = "CAP","I51": #LOCATION = "C4D7" !CDS_LOCATION = "C4D7" #SEC = "1" !CDS_SEC = "1";
"A":   PN = "1"  !CDS_PN = "1";
"B":   PN = "2"  !CDS_PN = "2";
BODY = "CAP_A","I52": #LOCATION = "C4D11" !CDS_LOCATION = "C4D11" #SEC = "1" !CDS_SEC = "1";
"A":   PN = "1"  !CDS_PN = "1";
"B":   PN = "2"  !CDS_PN = "2";
BODY = "CAP","I53": #LOCATION = "C4D10" !CDS_LOCATION = "C4D10" #SEC = "1" !CDS_SEC = "1";
"A":   PN = "1"  !CDS_PN = "1";
"B":   PN = "2"  !CDS_PN = "2";
BODY = "CAP","I54": #LOCATION = "C6P19" !CDS_LOCATION = "C6P19" #SEC = "1" !CDS_SEC = "1";
"A":   PN = "1"  !CDS_PN = "1";
"B":   PN = "2"  !CDS_PN = "2";
BODY = "CAP","I57": #LOCATION = "C6P20" !CDS_LOCATION = "C6P20" #SEC = "1" !CDS_SEC = "1";
"A":   PN = "1"  !CDS_PN = "1";
"B":   PN = "2"  !CDS_PN = "2";
BODY = "CAP","I58": #LOCATION = "C6P15" !CDS_LOCATION = "C6P15" #SEC = "1" !CDS_SEC = "1";
"A":   PN = "1"  !CDS_PN = "1";
"B":   PN = "2"  !CDS_PN = "2";
BODY = "CAP","I59": #LOCATION = "C6P7" !CDS_LOCATION = "C6P7" #SEC = "1" !CDS_SEC = "1";
"A":   PN = "1"  !CDS_PN = "1";
"B":   PN = "2"  !CDS_PN = "2";
BODY = "CAP_A","I66": #LOCATION = "C6P21" !CDS_LOCATION = "C6P21" #SEC = "1" !CDS_SEC = "1";
"A":   PN = "1"  !CDS_PN = "1";
"B":   PN = "2"  !CDS_PN = "2";
BODY = "RES","I67": #LOCATION = "R4E13" !CDS_LOCATION = "R4E13" #SEC = "1" !CDS_SEC = "1";
"A":   PN = "1"  !CDS_PN = "1";
"B":   PN = "2"  !CDS_PN = "2";
BODY = "CAP_A","I68": #LOCATION = "C4D34" !CDS_LOCATION = "C4D34" #SEC = "1" !CDS_SEC = "1";
"A":   PN = "1"  !CDS_PN = "1";
"B":   PN = "2"  !CDS_PN = "2";
BODY = "CAP_A","I69": #LOCATION = "C4D4" !CDS_LOCATION = "C4D4" #SEC = "1" !CDS_SEC = "1";
"A":   PN = "1"  !CDS_PN = "1";
"B":   PN = "2"  !CDS_PN = "2";
BODY = "IR354XX","I70": #LOCATION = "EU4D3" !CDS_LOCATION = "EU4D3" #SEC = "1" !CDS_SEC = "1";
"BOOST":   PN = "33"  !CDS_PN = "33";
"EN":   PN = "35"  !CDS_PN = "35";
"GL<0>":   PN = "6"  !CDS_PN = "6";
"GL<1>":   PN = "41"  !CDS_PN = "41";
"IOUT":   PN = "38"  !CDS_PN = "38";
"LGND":   PN = "2"  !CDS_PN = "2";
"NC":   PN = "31"  !CDS_PN = "31";
"OCSET":   PN = "37"  !CDS_PN = "37";
"PGND<0>":   PN = "5"  !CDS_PN = "5";
"PGND<1>":   PN = "7"  !CDS_PN = "7";
"PGND<2>":   PN = "40"  !CDS_PN = "40";
"PHASE":   PN = "32"  !CDS_PN = "32";
"PWM":   PN = "34"  !CDS_PN = "34";
"REFIN":   PN = "39"  !CDS_PN = "39";
"SW":   PN = "10"  !CDS_PN = "10";
"TOUT_FLT":   PN = "36"  !CDS_PN = "36";
"VCC":   PN = "3"  !CDS_PN = "3";
"VDRV":   PN = "4"  !CDS_PN = "4";
"VIN<0>":   PN = "25"  !CDS_PN = "25";
"VIN<1>":   PN = "30"  !CDS_PN = "30";
"VOS":   PN = "1"  !CDS_PN = "1";
BODY = "IR354XX","I71": #LOCATION = "EU4D1" !CDS_LOCATION = "EU4D1" &SEC = "1" #&CDS_SEC = "1";
"BOOST":   PN = "33"  !CDS_PN = "33";
"EN":   PN = "35"  !CDS_PN = "35";
"GL<0>":   PN = "6"  !CDS_PN = "6";
"GL<1>":   PN = "41"  !CDS_PN = "41";
"IOUT":   PN = "38"  !CDS_PN = "38";
"LGND":   PN = "2"  !CDS_PN = "2";
"NC":   PN = "31"  !CDS_PN = "31";
"OCSET":   PN = "37"  !CDS_PN = "37";
"PGND<0>":   PN = "5"  !CDS_PN = "5";
"PGND<1>":   PN = "7"  !CDS_PN = "7";
"PGND<2>":   PN = "40"  !CDS_PN = "40";
"PHASE":   PN = "32"  !CDS_PN = "32";
"PWM":   PN = "34"  !CDS_PN = "34";
"REFIN":   PN = "39"  !CDS_PN = "39";
"SW":   PN = "10"  !CDS_PN = "10";
"TOUT_FLT":   PN = "36"  !CDS_PN = "36";
"VCC":   PN = "3"  !CDS_PN = "3";
"VDRV":   PN = "4"  !CDS_PN = "4";
"VIN<0>":   PN = "25"  !CDS_PN = "25";
"VIN<1>":   PN = "30"  !CDS_PN = "30";
"VOS":   PN = "1"  !CDS_PN = "1";
BODY = "RES","I89": #LOCATION = "R4D72" !CDS_LOCATION = "R4D72" &SEC = "1" #&CDS_SEC = "1";
"A":   PN = "1"  !CDS_PN = "1";
"B":   PN = "2"  !CDS_PN = "2";
BODY = "RES","I91": #LOCATION = "R4D71" !CDS_LOCATION = "R4D71" &SEC = "1" #&CDS_SEC = "1";
"A":   PN = "1"  !CDS_PN = "1";
"B":   PN = "2"  !CDS_PN = "2";
BODY = "CAP_A","I93": #LOCATION = "CT40" !CDS_LOCATION = "CT40" &SEC = "1" #&CDS_SEC = "1";
"A":   PN = "1"  !CDS_PN = "1";
"B":   PN = "2"  !CDS_PN = "2";
BODY = "CAP_A","I96": #LOCATION = "CT39" !CDS_LOCATION = "CT39" &SEC = "1" #&CDS_SEC = "1";
"A":   PN = "1"  !CDS_PN = "1";
"B":   PN = "2"  !CDS_PN = "2";
BODY = "CAP","I99": #LOCATION = "CT37" !CDS_LOCATION = "CT37" &SEC = "1" #&CDS_SEC = "1";
"A":   PN = "1"  !CDS_PN = "1";
"B":   PN = "2"  !CDS_PN = "2";
BODY = "SC2K2P50V3KX-GP","I101": #LOCATION = "CT38" !CDS_LOCATION = "CT38" &SEC = "1" #&CDS_SEC = "1";
"1":   PN = "1"  !CDS_PN = "1";
"2":   PN = "2"  !CDS_PN = "2";
BODY = "SC2K2P50V3KX-GP","I106": #LOCATION = "CT41" !CDS_LOCATION = "CT41" &SEC = "1" #&CDS_SEC = "1";
"1":   PN = "1"  !CDS_PN = "1";
"2":   PN = "2"  !CDS_PN = "2";
BODY = "CAP","I108": #LOCATION = "CT42" !CDS_LOCATION = "CT42" &SEC = "1" #&CDS_SEC = "1";
"A":   PN = "1"  !CDS_PN = "1";
"B":   PN = "2"  !CDS_PN = "2";
BODY = "3D01R5F-GP","I105": #LOCATION = "RT27" !CDS_LOCATION = "RT27" &SEC = "1" #&CDS_SEC = "1";
"1":   PN = "1"  !CDS_PN = "1";
"2":   PN = "2"  !CDS_PN = "2";
BODY = "3D01R5F-GP","I102": #LOCATION = "RT26" !CDS_LOCATION = "RT26" &SEC = "1" #&CDS_SEC = "1";
"1":   PN = "1"  !CDS_PN = "1";
"2":   PN = "2"  !CDS_PN = "2";
BODY = "RES","I110": #LOCATION = "RT25" !CDS_LOCATION = "RT25" &SEC = "1" #&CDS_SEC = "1";
"A":   PN = "1"  !CDS_PN = "1";
"B":   PN = "2"  !CDS_PN = "2";
BODY = "RES","I111": #LOCATION = "RT28" !CDS_LOCATION = "RT28" &SEC = "1" #&CDS_SEC = "1";
"A":   PN = "1"  !CDS_PN = "1";
"B":   PN = "2"  !CDS_PN = "2";
DRAWING = "@baseboard_fab2_lib.baseboard_fab2(sch_1):page202";
BODY = "INDUCTOR","I5": #LOCATION = "L4E1" !CDS_LOCATION = "L4E1" &SEC = "1" #&CDS_SEC = "1";
"INA":   PN = "1"  !CDS_PN = "1";
"INB":   PN = "2"  !CDS_PN = "2";
BODY = "CAP_A","I9": #LOCATION = "C6R7" !CDS_LOCATION = "C6R7" #SEC = "1" !CDS_SEC = "1";
"A":   PN = "1"  !CDS_PN = "1";
"B":   PN = "2"  !CDS_PN = "2";
BODY = "CAP","I18": #LOCATION = "C4E5" !CDS_LOCATION = "C4E5" #SEC = "1" !CDS_SEC = "1";
"A":   PN = "1"  !CDS_PN = "1";
"B":   PN = "2"  !CDS_PN = "2";
BODY = "CAP_A","I19": #LOCATION = "C4E6" !CDS_LOCATION = "C4E6" #SEC = "1" !CDS_SEC = "1";
"A":   PN = "1"  !CDS_PN = "1";
"B":   PN = "2"  !CDS_PN = "2";
BODY = "CAP","I22": #LOCATION = "C4E17" !CDS_LOCATION = "C4E17" #SEC = "1" !CDS_SEC = "1";
"A":   PN = "1"  !CDS_PN = "1";
"B":   PN = "2"  !CDS_PN = "2";
BODY = "CAP","I24": #LOCATION = "C4E27" !CDS_LOCATION = "C4E27" #SEC = "1" !CDS_SEC = "1";
"A":   PN = "1"  !CDS_PN = "1";
"B":   PN = "2"  !CDS_PN = "2";
BODY = "CAP_A","I25": #LOCATION = "C4E25" !CDS_LOCATION = "C4E25" #SEC = "1" !CDS_SEC = "1";
"A":   PN = "1"  !CDS_PN = "1";
"B":   PN = "2"  !CDS_PN = "2";
BODY = "CAP_A","I27": #LOCATION = "C4E11" !CDS_LOCATION = "C4E11" #SEC = "1" !CDS_SEC = "1";
"A":   PN = "1"  !CDS_PN = "1";
"B":   PN = "2"  !CDS_PN = "2";
BODY = "INDUCTOR","I29": #LOCATION = "L4D3" !CDS_LOCATION = "L4D3" &SEC = "1" #&CDS_SEC = "1";
"INA":   PN = "1"  !CDS_PN = "1";
"INB":   PN = "2"  !CDS_PN = "2";
BODY = "CAP","I32": #LOCATION = "C4D50" !CDS_LOCATION = "C4D50" #SEC = "1" !CDS_SEC = "1";
"A":   PN = "1"  !CDS_PN = "1";
"B":   PN = "2"  !CDS_PN = "2";
BODY = "RES","I33": #LOCATION = "R6R2" !CDS_LOCATION = "R6R2" #SEC = "1" !CDS_SEC = "1";
"A":   PN = "1"  !CDS_PN = "1";
"B":   PN = "2"  !CDS_PN = "2";
BODY = "CAP","I34": #LOCATION = "C4E10" !CDS_LOCATION = "C4E10" #SEC = "1" !CDS_SEC = "1";
"A":   PN = "1"  !CDS_PN = "1";
"B":   PN = "2"  !CDS_PN = "2";
BODY = "CAP_A","I35": #LOCATION = "C4E20" !CDS_LOCATION = "C4E20" #SEC = "1" !CDS_SEC = "1";
"A":   PN = "1"  !CDS_PN = "1";
"B":   PN = "2"  !CDS_PN = "2";
BODY = "CAP","I36": #LOCATION = "C4E19" !CDS_LOCATION = "C4E19" #SEC = "1" !CDS_SEC = "1";
"A":   PN = "1"  !CDS_PN = "1";
"B":   PN = "2"  !CDS_PN = "2";
BODY = "CAP","I37": #LOCATION = "C6R11" !CDS_LOCATION = "C6R11" #SEC = "1" !CDS_SEC = "1";
"A":   PN = "1"  !CDS_PN = "1";
"B":   PN = "2"  !CDS_PN = "2";
BODY = "CAP","I38": #LOCATION = "C6P13" !CDS_LOCATION = "C6P13" #SEC = "1" !CDS_SEC = "1";
"A":   PN = "1"  !CDS_PN = "1";
"B":   PN = "2"  !CDS_PN = "2";
BODY = "RES","I39": #LOCATION = "R6R6" !CDS_LOCATION = "R6R6" #SEC = "1" !CDS_SEC = "1";
"A":   PN = "1"  !CDS_PN = "1";
"B":   PN = "2"  !CDS_PN = "2";
BODY = "CAP","I42": #LOCATION = "C6R13" !CDS_LOCATION = "C6R13" #SEC = "1" !CDS_SEC = "1";
"A":   PN = "1"  !CDS_PN = "1";
"B":   PN = "2"  !CDS_PN = "2";
BODY = "CAP","I45": #LOCATION = "C4E26" !CDS_LOCATION = "C4E26" #SEC = "1" !CDS_SEC = "1";
"A":   PN = "1"  !CDS_PN = "1";
"B":   PN = "2"  !CDS_PN = "2";
BODY = "CAP_A","I46": #LOCATION = "C4D49" !CDS_LOCATION = "C4D49" #SEC = "1" !CDS_SEC = "1";
"A":   PN = "1"  !CDS_PN = "1";
"B":   PN = "2"  !CDS_PN = "2";
BODY = "CAP","I47": #LOCATION = "C4D48" !CDS_LOCATION = "C4D48" #SEC = "1" !CDS_SEC = "1";
"A":   PN = "1"  !CDS_PN = "1";
"B":   PN = "2"  !CDS_PN = "2";
BODY = "CAP","I48": #LOCATION = "C6R4" !CDS_LOCATION = "C6R4" #SEC = "1" !CDS_SEC = "1";
"A":   PN = "1"  !CDS_PN = "1";
"B":   PN = "2"  !CDS_PN = "2";
BODY = "CAP","I49": #LOCATION = "C6P22" !CDS_LOCATION = "C6P22" #SEC = "1" !CDS_SEC = "1";
"A":   PN = "1"  !CDS_PN = "1";
"B":   PN = "2"  !CDS_PN = "2";
BODY = "CAP","I51": #LOCATION = "C6N8" !CDS_LOCATION = "C6N8" #SEC = "1" !CDS_SEC = "1";
"A":   PN = "1"  !CDS_PN = "1";
"B":   PN = "2"  !CDS_PN = "2";
BODY = "CAP_A","I61": #LOCATION = "C4E3" !CDS_LOCATION = "C4E3" #SEC = "1" !CDS_SEC = "1";
"A":   PN = "1"  !CDS_PN = "1";
"B":   PN = "2"  !CDS_PN = "2";
BODY = "CAP_A","I62": #LOCATION = "C6P16" !CDS_LOCATION = "C6P16" #SEC = "1" !CDS_SEC = "1";
"A":   PN = "1"  !CDS_PN = "1";
"B":   PN = "2"  !CDS_PN = "2";
BODY = "IR354XX","I63": #LOCATION = "EU4E1" !CDS_LOCATION = "EU4E1" &SEC = "1" #&CDS_SEC = "1";
"BOOST":   PN = "33"  !CDS_PN = "33";
"EN":   PN = "35"  !CDS_PN = "35";
"GL<0>":   PN = "6"  !CDS_PN = "6";
"GL<1>":   PN = "41"  !CDS_PN = "41";
"IOUT":   PN = "38"  !CDS_PN = "38";
"LGND":   PN = "2"  !CDS_PN = "2";
"NC":   PN = "31"  !CDS_PN = "31";
"OCSET":   PN = "37"  !CDS_PN = "37";
"PGND<0>":   PN = "5"  !CDS_PN = "5";
"PGND<1>":   PN = "7"  !CDS_PN = "7";
"PGND<2>":   PN = "40"  !CDS_PN = "40";
"PHASE":   PN = "32"  !CDS_PN = "32";
"PWM":   PN = "34"  !CDS_PN = "34";
"REFIN":   PN = "39"  !CDS_PN = "39";
"SW":   PN = "10"  !CDS_PN = "10";
"TOUT_FLT":   PN = "36"  !CDS_PN = "36";
"VCC":   PN = "3"  !CDS_PN = "3";
"VDRV":   PN = "4"  !CDS_PN = "4";
"VIN<0>":   PN = "25"  !CDS_PN = "25";
"VIN<1>":   PN = "30"  !CDS_PN = "30";
"VOS":   PN = "1"  !CDS_PN = "1";
BODY = "IR354XX","I64": #LOCATION = "EU4D6" !CDS_LOCATION = "EU4D6" &SEC = "1" #&CDS_SEC = "1";
"BOOST":   PN = "33"  !CDS_PN = "33";
"EN":   PN = "35"  !CDS_PN = "35";
"GL<0>":   PN = "6"  !CDS_PN = "6";
"GL<1>":   PN = "41"  !CDS_PN = "41";
"IOUT":   PN = "38"  !CDS_PN = "38";
"LGND":   PN = "2"  !CDS_PN = "2";
"NC":   PN = "31"  !CDS_PN = "31";
"OCSET":   PN = "37"  !CDS_PN = "37";
"PGND<0>":   PN = "5"  !CDS_PN = "5";
"PGND<1>":   PN = "7"  !CDS_PN = "7";
"PGND<2>":   PN = "40"  !CDS_PN = "40";
"PHASE":   PN = "32"  !CDS_PN = "32";
"PWM":   PN = "34"  !CDS_PN = "34";
"REFIN":   PN = "39"  !CDS_PN = "39";
"SW":   PN = "10"  !CDS_PN = "10";
"TOUT_FLT":   PN = "36"  !CDS_PN = "36";
"VCC":   PN = "3"  !CDS_PN = "3";
"VDRV":   PN = "4"  !CDS_PN = "4";
"VIN<0>":   PN = "25"  !CDS_PN = "25";
"VIN<1>":   PN = "30"  !CDS_PN = "30";
"VOS":   PN = "1"  !CDS_PN = "1";
BODY = "RES","I65": #LOCATION = "R4E22" !CDS_LOCATION = "R4E22" &SEC = "1" #&CDS_SEC = "1";
"A":   PN = "1"  !CDS_PN = "1";
"B":   PN = "2"  !CDS_PN = "2";
BODY = "RES","I67": #LOCATION = "R4E19" !CDS_LOCATION = "R4E19" &SEC = "1" #&CDS_SEC = "1";
"A":   PN = "1"  !CDS_PN = "1";
"B":   PN = "2"  !CDS_PN = "2";
BODY = "CAP_A","I70": #LOCATION = "CT1" !CDS_LOCATION = "CT1" &SEC = "1" #&CDS_SEC = "1";
"A":   PN = "1"  !CDS_PN = "1";
"B":   PN = "2"  !CDS_PN = "2";
BODY = "SC2K2P50V3KX-GP","I76": #LOCATION = "CT3" !CDS_LOCATION = "CT3" &SEC = "1" #&CDS_SEC = "1";
"1":   PN = "1"  !CDS_PN = "1";
"2":   PN = "2"  !CDS_PN = "2";
BODY = "CAP","I78": #LOCATION = "CT2" !CDS_LOCATION = "CT2" #SEC = "1" !CDS_SEC = "1";
"A":   PN = "1"  !CDS_PN = "1";
"B":   PN = "2"  !CDS_PN = "2";
BODY = "CAP_A","I81": #LOCATION = "CT6" !CDS_LOCATION = "CT6" &SEC = "1" #&CDS_SEC = "1";
"A":   PN = "1"  !CDS_PN = "1";
"B":   PN = "2"  !CDS_PN = "2";
BODY = "SC2K2P50V3KX-GP","I82": #LOCATION = "CT5" !CDS_LOCATION = "CT5" &SEC = "1" #&CDS_SEC = "1";
"1":   PN = "1"  !CDS_PN = "1";
"2":   PN = "2"  !CDS_PN = "2";
BODY = "3D01R5F-GP","I83": #LOCATION = "RT4" !CDS_LOCATION = "RT4" &SEC = "1" #&CDS_SEC = "1";
"1":   PN = "1"  !CDS_PN = "1";
"2":   PN = "2"  !CDS_PN = "2";
BODY = "3D01R5F-GP","I75": #LOCATION = "RT2" !CDS_LOCATION = "RT2" &SEC = "1" #&CDS_SEC = "1";
"1":   PN = "1"  !CDS_PN = "1";
"2":   PN = "2"  !CDS_PN = "2";
BODY = "CAP","I87": #LOCATION = "CT4" !CDS_LOCATION = "CT4" &SEC = "1" #&CDS_SEC = "1";
"A":   PN = "1"  !CDS_PN = "1";
"B":   PN = "2"  !CDS_PN = "2";
BODY = "RES","I88": #LOCATION = "RT1" !CDS_LOCATION = "RT1" &SEC = "1" #&CDS_SEC = "1";
"A":   PN = "1"  !CDS_PN = "1";
"B":   PN = "2"  !CDS_PN = "2";
BODY = "RES","I89": #LOCATION = "RT3" !CDS_LOCATION = "RT3" &SEC = "1" #&CDS_SEC = "1";
"A":   PN = "1"  !CDS_PN = "1";
"B":   PN = "2"  !CDS_PN = "2";
DRAWING = "@baseboard_fab2_lib.baseboard_fab2(sch_1):page219";
BODY = "CAP","I44": #LOCATION = "C7A12" !CDS_LOCATION = "C7A12" &SEC = "1" #&CDS_SEC = "1";
"A":   PN = "1"  !CDS_PN = "1";
"B":   PN = "2"  !CDS_PN = "2";
BODY = "CAP","I45": #LOCATION = "C3L2" !CDS_LOCATION = "C3L2" &SEC = "1" #&CDS_SEC = "1";
"A":   PN = "1"  !CDS_PN = "1";
"B":   PN = "2"  !CDS_PN = "2";
BODY = "CAP","I46": #LOCATION = "C3L4" !CDS_LOCATION = "C3L4" &SEC = "1" #&CDS_SEC = "1";
"A":   PN = "1"  !CDS_PN = "1";
"B":   PN = "2"  !CDS_PN = "2";
BODY = "CAP","I47": #LOCATION = "C3L13" !CDS_LOCATION = "C3L13" &SEC = "1" #&CDS_SEC = "1";
"A":   PN = "1"  !CDS_PN = "1";
"B":   PN = "2"  !CDS_PN = "2";
BODY = "CAP","I48": #LOCATION = "C7A11" !CDS_LOCATION = "C7A11" &SEC = "1" #&CDS_SEC = "1";
"A":   PN = "1"  !CDS_PN = "1";
"B":   PN = "2"  !CDS_PN = "2";
BODY = "CAP","I50": #LOCATION = "C7A16" !CDS_LOCATION = "C7A16" &SEC = "1" #&CDS_SEC = "1";
"A":   PN = "1"  !CDS_PN = "1";
"B":   PN = "2"  !CDS_PN = "2";
BODY = "CAP_A","I51": #LOCATION = "C7A5" !CDS_LOCATION = "C7A5" &SEC = "1" #&CDS_SEC = "1";
"A":   PN = "1"  !CDS_PN = "1";
"B":   PN = "2"  !CDS_PN = "2";
BODY = "RES","I52": #LOCATION = "R3L6" !CDS_LOCATION = "R3L6" &SEC = "1" #&CDS_SEC = "1";
"A":   PN = "1"  !CDS_PN = "1";
"B":   PN = "2"  !CDS_PN = "2";
BODY = "CAP_A","I53": #LOCATION = "C7A18" !CDS_LOCATION = "C7A18" &SEC = "1" #&CDS_SEC = "1";
"A":   PN = "1"  !CDS_PN = "1";
"B":   PN = "2"  !CDS_PN = "2";
BODY = "CAP","I54": #LOCATION = "C7A17" !CDS_LOCATION = "C7A17" &SEC = "1" #&CDS_SEC = "1";
"A":   PN = "1"  !CDS_PN = "1";
"B":   PN = "2"  !CDS_PN = "2";
BODY = "INDUCTOR","I55": #LOCATION = "L7A1" !CDS_LOCATION = "L7A1" &SEC = "1" #&CDS_SEC = "1";
"INA":   PN = "1"  !CDS_PN = "1";
"INB":   PN = "2"  !CDS_PN = "2";
BODY = "INDUCTOR","I65": #LOCATION = "L7A3" !CDS_LOCATION = "L7A3" #SEC = "1" !CDS_SEC = "1";
"INA":   PN = "1"  !CDS_PN = "1";
"INB":   PN = "2"  !CDS_PN = "2";
BODY = "CAP","I68": #LOCATION = "C6A4" !CDS_LOCATION = "C6A4" #SEC = "1" !CDS_SEC = "1";
"A":   PN = "1"  !CDS_PN = "1";
"B":   PN = "2"  !CDS_PN = "2";
BODY = "CAP","I72": #LOCATION = "C7A25" !CDS_LOCATION = "C7A25" #SEC = "1" !CDS_SEC = "1";
"A":   PN = "1"  !CDS_PN = "1";
"B":   PN = "2"  !CDS_PN = "2";
BODY = "CAP_A","I73": #LOCATION = "C7A26" !CDS_LOCATION = "C7A26" #SEC = "1" !CDS_SEC = "1";
"A":   PN = "1"  !CDS_PN = "1";
"B":   PN = "2"  !CDS_PN = "2";
BODY = "CAP","I75": #LOCATION = "C7A22" !CDS_LOCATION = "C7A22" &SEC = "1" #&CDS_SEC = "1";
"A":   PN = "1"  !CDS_PN = "1";
"B":   PN = "2"  !CDS_PN = "2";
BODY = "RES","I76": #LOCATION = "R3L8" !CDS_LOCATION = "R3L8" #SEC = "1" !CDS_SEC = "1";
"A":   PN = "1"  !CDS_PN = "1";
"B":   PN = "2"  !CDS_PN = "2";
BODY = "CAP","I77": #LOCATION = "C7A24" !CDS_LOCATION = "C7A24" #SEC = "1" !CDS_SEC = "1";
"A":   PN = "1"  !CDS_PN = "1";
"B":   PN = "2"  !CDS_PN = "2";
BODY = "CAP_A","I78": #LOCATION = "C7A20" !CDS_LOCATION = "C7A20" #SEC = "1" !CDS_SEC = "1";
"A":   PN = "1"  !CDS_PN = "1";
"B":   PN = "2"  !CDS_PN = "2";
BODY = "CAP","I79": #LOCATION = "C7A21" !CDS_LOCATION = "C7A21" #SEC = "1" !CDS_SEC = "1";
"A":   PN = "1"  !CDS_PN = "1";
"B":   PN = "2"  !CDS_PN = "2";
BODY = "CAP","I80": #LOCATION = "C3L17" !CDS_LOCATION = "C3L17" #SEC = "1" !CDS_SEC = "1";
"A":   PN = "1"  !CDS_PN = "1";
"B":   PN = "2"  !CDS_PN = "2";
BODY = "CAP","I81": #LOCATION = "C3L16" !CDS_LOCATION = "C3L16" #SEC = "1" !CDS_SEC = "1";
"A":   PN = "1"  !CDS_PN = "1";
"B":   PN = "2"  !CDS_PN = "2";
BODY = "CAP","I84": #LOCATION = "C3L15" !CDS_LOCATION = "C3L15" #SEC = "1" !CDS_SEC = "1";
"A":   PN = "1"  !CDS_PN = "1";
"B":   PN = "2"  !CDS_PN = "2";
BODY = "CAP","I87": #LOCATION = "C6A1" !CDS_LOCATION = "C6A1" &SEC = "1" #&CDS_SEC = "1";
"A":   PN = "1"  !CDS_PN = "1";
"B":   PN = "2"  !CDS_PN = "2";
BODY = "IR354XX","I106": #LOCATION = "EU7A1" !CDS_LOCATION = "EU7A1" #SEC = "1" !CDS_SEC = "1";
"BOOST":   PN = "33"  !CDS_PN = "33";
"EN":   PN = "35"  !CDS_PN = "35";
"GL<0>":   PN = "6"  !CDS_PN = "6";
"GL<1>":   PN = "41"  !CDS_PN = "41";
"IOUT":   PN = "38"  !CDS_PN = "38";
"LGND":   PN = "2"  !CDS_PN = "2";
"NC":   PN = "31"  !CDS_PN = "31";
"OCSET":   PN = "37"  !CDS_PN = "37";
"PGND<0>":   PN = "5"  !CDS_PN = "5";
"PGND<1>":   PN = "7"  !CDS_PN = "7";
"PGND<2>":   PN = "40"  !CDS_PN = "40";
"PHASE":   PN = "32"  !CDS_PN = "32";
"PWM":   PN = "34"  !CDS_PN = "34";
"REFIN":   PN = "39"  !CDS_PN = "39";
"SW":   PN = "10"  !CDS_PN = "10";
"TOUT_FLT":   PN = "36"  !CDS_PN = "36";
"VCC":   PN = "3"  !CDS_PN = "3";
"VDRV":   PN = "4"  !CDS_PN = "4";
"VIN<0>":   PN = "25"  !CDS_PN = "25";
"VIN<1>":   PN = "30"  !CDS_PN = "30";
"VOS":   PN = "1"  !CDS_PN = "1";
BODY = "IR354XX","I107": #LOCATION = "EU7A4" !CDS_LOCATION = "EU7A4" #SEC = "1" !CDS_SEC = "1";
"BOOST":   PN = "33"  !CDS_PN = "33";
"EN":   PN = "35"  !CDS_PN = "35";
"GL<0>":   PN = "6"  !CDS_PN = "6";
"GL<1>":   PN = "41"  !CDS_PN = "41";
"IOUT":   PN = "38"  !CDS_PN = "38";
"LGND":   PN = "2"  !CDS_PN = "2";
"NC":   PN = "31"  !CDS_PN = "31";
"OCSET":   PN = "37"  !CDS_PN = "37";
"PGND<0>":   PN = "5"  !CDS_PN = "5";
"PGND<1>":   PN = "7"  !CDS_PN = "7";
"PGND<2>":   PN = "40"  !CDS_PN = "40";
"PHASE":   PN = "32"  !CDS_PN = "32";
"PWM":   PN = "34"  !CDS_PN = "34";
"REFIN":   PN = "39"  !CDS_PN = "39";
"SW":   PN = "10"  !CDS_PN = "10";
"TOUT_FLT":   PN = "36"  !CDS_PN = "36";
"VCC":   PN = "3"  !CDS_PN = "3";
"VDRV":   PN = "4"  !CDS_PN = "4";
"VIN<0>":   PN = "25"  !CDS_PN = "25";
"VIN<1>":   PN = "30"  !CDS_PN = "30";
"VOS":   PN = "1"  !CDS_PN = "1";
BODY = "RES","I108": #LOCATION = "R7A20" !CDS_LOCATION = "R7A20" &SEC = "1" #&CDS_SEC = "1";
"A":   PN = "1"  !CDS_PN = "1";
"B":   PN = "2"  !CDS_PN = "2";
BODY = "RES","I110": #LOCATION = "R7A21" !CDS_LOCATION = "R7A21" &SEC = "1" #&CDS_SEC = "1";
"A":   PN = "1"  !CDS_PN = "1";
"B":   PN = "2"  !CDS_PN = "2";
BODY = "CAP_A","I113": #LOCATION = "CT46" !CDS_LOCATION = "CT46" &SEC = "1" #&CDS_SEC = "1";
"A":   PN = "1"  !CDS_PN = "1";
"B":   PN = "2"  !CDS_PN = "2";
BODY = "CAP_A","I116": #LOCATION = "CT45" !CDS_LOCATION = "CT45" &SEC = "1" #&CDS_SEC = "1";
"A":   PN = "1"  !CDS_PN = "1";
"B":   PN = "2"  !CDS_PN = "2";
BODY = "CAP","I119": #LOCATION = "CT48" !CDS_LOCATION = "CT48" &SEC = "1" #&CDS_SEC = "1";
"A":   PN = "1"  !CDS_PN = "1";
"B":   PN = "2"  !CDS_PN = "2";
BODY = "SC2K2P50V3KX-GP","I121": #LOCATION = "CT47" !CDS_LOCATION = "CT47" &SEC = "1" #&CDS_SEC = "1";
"1":   PN = "1"  !CDS_PN = "1";
"2":   PN = "2"  !CDS_PN = "2";
BODY = "CAP","I124": #LOCATION = "CT43" !CDS_LOCATION = "CT43" &SEC = "1" #&CDS_SEC = "1";
"A":   PN = "1"  !CDS_PN = "1";
"B":   PN = "2"  !CDS_PN = "2";
BODY = "SC2K2P50V3KX-GP","I127": #LOCATION = "CT44" !CDS_LOCATION = "CT44" &SEC = "1" #&CDS_SEC = "1";
"1":   PN = "1"  !CDS_PN = "1";
"2":   PN = "2"  !CDS_PN = "2";
BODY = "3D01R5F-GP","I126": #LOCATION = "RT29" !CDS_LOCATION = "RT29" &SEC = "1" #&CDS_SEC = "1";
"1":   PN = "1"  !CDS_PN = "1";
"2":   PN = "2"  !CDS_PN = "2";
BODY = "3D01R5F-GP","I123": #LOCATION = "RT32" !CDS_LOCATION = "RT32" &SEC = "1" #&CDS_SEC = "1";
"1":   PN = "1"  !CDS_PN = "1";
"2":   PN = "2"  !CDS_PN = "2";
BODY = "RES","I129": #LOCATION = "RT30" !CDS_LOCATION = "RT30" &SEC = "1" #&CDS_SEC = "1";
"A":   PN = "1"  !CDS_PN = "1";
"B":   PN = "2"  !CDS_PN = "2";
BODY = "RES","I130": #LOCATION = "RT31" !CDS_LOCATION = "RT31" &SEC = "1" #&CDS_SEC = "1";
"A":   PN = "1"  !CDS_PN = "1";
"B":   PN = "2"  !CDS_PN = "2";
DRAWING = "@baseboard_fab2_lib.baseboard_fab2(sch_1):page216";
BODY = "CAP","I6": #LOCATION = "C6G3" !CDS_LOCATION = "C6G3" #SEC = "1" !CDS_SEC = "1";
"A":   PN = "1"  !CDS_PN = "1";
"B":   PN = "2"  !CDS_PN = "2";
BODY = "CAP","I44": #LOCATION = "C7G31" !CDS_LOCATION = "C7G31" #SEC = "1" !CDS_SEC = "1";
"A":   PN = "1"  !CDS_PN = "1";
"B":   PN = "2"  !CDS_PN = "2";
BODY = "CAP","I45": #LOCATION = "C3U2" !CDS_LOCATION = "C3U2" #SEC = "1" !CDS_SEC = "1";
"A":   PN = "1"  !CDS_PN = "1";
"B":   PN = "2"  !CDS_PN = "2";
BODY = "CAP","I46": #LOCATION = "C3U3" !CDS_LOCATION = "C3U3" #SEC = "1" !CDS_SEC = "1";
"A":   PN = "1"  !CDS_PN = "1";
"B":   PN = "2"  !CDS_PN = "2";
BODY = "CAP","I47": #LOCATION = "C3U4" !CDS_LOCATION = "C3U4" #SEC = "1" !CDS_SEC = "1";
"A":   PN = "1"  !CDS_PN = "1";
"B":   PN = "2"  !CDS_PN = "2";
BODY = "CAP","I48": #LOCATION = "C7G37" !CDS_LOCATION = "C7G37" #SEC = "1" !CDS_SEC = "1";
"A":   PN = "1"  !CDS_PN = "1";
"B":   PN = "2"  !CDS_PN = "2";
BODY = "CAP","I50": #LOCATION = "C7G33" !CDS_LOCATION = "C7G33" #SEC = "1" !CDS_SEC = "1";
"A":   PN = "1"  !CDS_PN = "1";
"B":   PN = "2"  !CDS_PN = "2";
BODY = "CAP_A","I51": #LOCATION = "C7G29" !CDS_LOCATION = "C7G29" #SEC = "1" !CDS_SEC = "1";
"A":   PN = "1"  !CDS_PN = "1";
"B":   PN = "2"  !CDS_PN = "2";
BODY = "RES","I52": #LOCATION = "R3U6" !CDS_LOCATION = "R3U6" #SEC = "1" !CDS_SEC = "1";
"A":   PN = "1"  !CDS_PN = "1";
"B":   PN = "2"  !CDS_PN = "2";
BODY = "CAP_A","I53": #LOCATION = "C7G35" !CDS_LOCATION = "C7G35" #SEC = "1" !CDS_SEC = "1";
"A":   PN = "1"  !CDS_PN = "1";
"B":   PN = "2"  !CDS_PN = "2";
BODY = "CAP","I54": #LOCATION = "C7G34" !CDS_LOCATION = "C7G34" #SEC = "1" !CDS_SEC = "1";
"A":   PN = "1"  !CDS_PN = "1";
"B":   PN = "2"  !CDS_PN = "2";
BODY = "INDUCTOR","I65": #LOCATION = "L7G2" !CDS_LOCATION = "L7G2" #SEC = "1" !CDS_SEC = "1";
"INA":   PN = "1"  !CDS_PN = "1";
"INB":   PN = "2"  !CDS_PN = "2";
BODY = "CAP","I68": #LOCATION = "C7G27" !CDS_LOCATION = "C7G27" #SEC = "1" !CDS_SEC = "1";
"A":   PN = "1"  !CDS_PN = "1";
"B":   PN = "2"  !CDS_PN = "2";
BODY = "CAP","I72": #LOCATION = "C7G41" !CDS_LOCATION = "C7G41" #SEC = "1" !CDS_SEC = "1";
"A":   PN = "1"  !CDS_PN = "1";
"B":   PN = "2"  !CDS_PN = "2";
BODY = "CAP_A","I73": #LOCATION = "C7G42" !CDS_LOCATION = "C7G42" #SEC = "1" !CDS_SEC = "1";
"A":   PN = "1"  !CDS_PN = "1";
"B":   PN = "2"  !CDS_PN = "2";
BODY = "RES","I76": #LOCATION = "R3U9" !CDS_LOCATION = "R3U9" #SEC = "1" !CDS_SEC = "1";
"A":   PN = "1"  !CDS_PN = "1";
"B":   PN = "2"  !CDS_PN = "2";
BODY = "CAP","I77": #LOCATION = "C7G40" !CDS_LOCATION = "C7G40" #SEC = "1" !CDS_SEC = "1";
"A":   PN = "1"  !CDS_PN = "1";
"B":   PN = "2"  !CDS_PN = "2";
BODY = "CAP_A","I78": #LOCATION = "C7G36" !CDS_LOCATION = "C7G36" #SEC = "1" !CDS_SEC = "1";
"A":   PN = "1"  !CDS_PN = "1";
"B":   PN = "2"  !CDS_PN = "2";
BODY = "CAP","I79": #LOCATION = "C7G30" !CDS_LOCATION = "C7G30" #SEC = "1" !CDS_SEC = "1";
"A":   PN = "1"  !CDS_PN = "1";
"B":   PN = "2"  !CDS_PN = "2";
BODY = "CAP","I80": #LOCATION = "C3U9" !CDS_LOCATION = "C3U9" #SEC = "1" !CDS_SEC = "1";
"A":   PN = "1"  !CDS_PN = "1";
"B":   PN = "2"  !CDS_PN = "2";
BODY = "CAP","I81": #LOCATION = "C3U7" !CDS_LOCATION = "C3U7" #SEC = "1" !CDS_SEC = "1";
"A":   PN = "1"  !CDS_PN = "1";
"B":   PN = "2"  !CDS_PN = "2";
BODY = "CAP","I84": #LOCATION = "C3U6" !CDS_LOCATION = "C3U6" #SEC = "1" !CDS_SEC = "1";
"A":   PN = "1"  !CDS_PN = "1";
"B":   PN = "2"  !CDS_PN = "2";
BODY = "IR354XX","I102": #LOCATION = "EU7G2" !CDS_LOCATION = "EU7G2" #SEC = "1" !CDS_SEC = "1";
"BOOST":   PN = "33"  !CDS_PN = "33";
"EN":   PN = "35"  !CDS_PN = "35";
"GL<0>":   PN = "6"  !CDS_PN = "6";
"GL<1>":   PN = "41"  !CDS_PN = "41";
"IOUT":   PN = "38"  !CDS_PN = "38";
"LGND":   PN = "2"  !CDS_PN = "2";
"NC":   PN = "31"  !CDS_PN = "31";
"OCSET":   PN = "37"  !CDS_PN = "37";
"PGND<0>":   PN = "5"  !CDS_PN = "5";
"PGND<1>":   PN = "7"  !CDS_PN = "7";
"PGND<2>":   PN = "40"  !CDS_PN = "40";
"PHASE":   PN = "32"  !CDS_PN = "32";
"PWM":   PN = "34"  !CDS_PN = "34";
"REFIN":   PN = "39"  !CDS_PN = "39";
"SW":   PN = "10"  !CDS_PN = "10";
"TOUT_FLT":   PN = "36"  !CDS_PN = "36";
"VCC":   PN = "3"  !CDS_PN = "3";
"VDRV":   PN = "4"  !CDS_PN = "4";
"VIN<0>":   PN = "25"  !CDS_PN = "25";
"VIN<1>":   PN = "30"  !CDS_PN = "30";
"VOS":   PN = "1"  !CDS_PN = "1";
BODY = "IR354XX","I103": #LOCATION = "EU7G3" !CDS_LOCATION = "EU7G3" #SEC = "1" !CDS_SEC = "1";
"BOOST":   PN = "33"  !CDS_PN = "33";
"EN":   PN = "35"  !CDS_PN = "35";
"GL<0>":   PN = "6"  !CDS_PN = "6";
"GL<1>":   PN = "41"  !CDS_PN = "41";
"IOUT":   PN = "38"  !CDS_PN = "38";
"LGND":   PN = "2"  !CDS_PN = "2";
"NC":   PN = "31"  !CDS_PN = "31";
"OCSET":   PN = "37"  !CDS_PN = "37";
"PGND<0>":   PN = "5"  !CDS_PN = "5";
"PGND<1>":   PN = "7"  !CDS_PN = "7";
"PGND<2>":   PN = "40"  !CDS_PN = "40";
"PHASE":   PN = "32"  !CDS_PN = "32";
"PWM":   PN = "34"  !CDS_PN = "34";
"REFIN":   PN = "39"  !CDS_PN = "39";
"SW":   PN = "10"  !CDS_PN = "10";
"TOUT_FLT":   PN = "36"  !CDS_PN = "36";
"VCC":   PN = "3"  !CDS_PN = "3";
"VDRV":   PN = "4"  !CDS_PN = "4";
"VIN<0>":   PN = "25"  !CDS_PN = "25";
"VIN<1>":   PN = "30"  !CDS_PN = "30";
"VOS":   PN = "1"  !CDS_PN = "1";
BODY = "RES","I104": #LOCATION = "R7G25" !CDS_LOCATION = "R7G25" #SEC = "1" !CDS_SEC = "1";
"A":   PN = "1"  !CDS_PN = "1";
"B":   PN = "2"  !CDS_PN = "2";
BODY = "RES","I106": #LOCATION = "R7G30" !CDS_LOCATION = "R7G30" #SEC = "1" !CDS_SEC = "1";
"A":   PN = "1"  !CDS_PN = "1";
"B":   PN = "2"  !CDS_PN = "2";
BODY = "CAP_A","I108": #LOCATION = "CT51" !CDS_LOCATION = "CT51" &SEC = "1" #&CDS_SEC = "1";
"A":   PN = "1"  !CDS_PN = "1";
"B":   PN = "2"  !CDS_PN = "2";
BODY = "CAP_A","I111": #LOCATION = "CT52" !CDS_LOCATION = "CT52" &SEC = "1" #&CDS_SEC = "1";
"A":   PN = "1"  !CDS_PN = "1";
"B":   PN = "2"  !CDS_PN = "2";
BODY = "CAP","I118": #LOCATION = "CT49" !CDS_LOCATION = "CT49" &SEC = "1" #&CDS_SEC = "1";
"A":   PN = "1"  !CDS_PN = "1";
"B":   PN = "2"  !CDS_PN = "2";
BODY = "SC2K2P50V3KX-GP","I119": #LOCATION = "CT53" !CDS_LOCATION = "CT53" &SEC = "1" #&CDS_SEC = "1";
"1":   PN = "1"  !CDS_PN = "1";
"2":   PN = "2"  !CDS_PN = "2";
BODY = "CAP","I121": #LOCATION = "CT54" !CDS_LOCATION = "CT54" &SEC = "1" #&CDS_SEC = "1";
"A":   PN = "1"  !CDS_PN = "1";
"B":   PN = "2"  !CDS_PN = "2";
BODY = "SC2K2P50V3KX-GP","I124": #LOCATION = "CT50" !CDS_LOCATION = "CT50" &SEC = "1" #&CDS_SEC = "1";
"1":   PN = "1"  !CDS_PN = "1";
"2":   PN = "2"  !CDS_PN = "2";
BODY = "INDUCTOR","I125": #LOCATION = "L7G1" !CDS_LOCATION = "L7G1" #SEC = "1" !CDS_SEC = "1";
"INA":   PN = "1"  !CDS_PN = "1";
"INB":   PN = "2"  !CDS_PN = "2";
BODY = "3D01R5F-GP","I114": #LOCATION = "RT34" !CDS_LOCATION = "RT34" &SEC = "1" #&CDS_SEC = "1";
"1":   PN = "1"  !CDS_PN = "1";
"2":   PN = "2"  !CDS_PN = "2";
BODY = "3D01R5F-GP","I123": #LOCATION = "RT35" !CDS_LOCATION = "RT35" &SEC = "1" #&CDS_SEC = "1";
"1":   PN = "1"  !CDS_PN = "1";
"2":   PN = "2"  !CDS_PN = "2";
BODY = "RES","I126": #LOCATION = "RT33" !CDS_LOCATION = "RT33" &SEC = "1" #&CDS_SEC = "1";
"A":   PN = "1"  !CDS_PN = "1";
"B":   PN = "2"  !CDS_PN = "2";
BODY = "RES","I127": #LOCATION = "RT36" !CDS_LOCATION = "RT36" &SEC = "1" #&CDS_SEC = "1";
"A":   PN = "1"  !CDS_PN = "1";
"B":   PN = "2"  !CDS_PN = "2";
BODY = "CAP","I128": #LOCATION = "C7G38" !CDS_LOCATION = "C7G38" #SEC = "1" !CDS_SEC = "1";
"A":   PN = "1"  !CDS_PN = "1";
"B":   PN = "2"  !CDS_PN = "2";
DRAWING = "@baseboard_fab2_lib.baseboard_fab2(sch_1):page210";
BODY = "CAP_A","I8": #LOCATION = "C1C19" !CDS_LOCATION = "C1C19" #SEC = "1" !CDS_SEC = "1";
"A":   PN = "1"  !CDS_PN = "1";
"B":   PN = "2"  !CDS_PN = "2";
BODY = "INDUCTOR","I10": #LOCATION = "L1C1" !CDS_LOCATION = "L1C1" #SEC = "1" !CDS_SEC = "1";
"INA":   PN = "1"  !CDS_PN = "1";
"INB":   PN = "2"  !CDS_PN = "2";
BODY = "CAPP","I12": #LOCATION = "C9N11" !CDS_LOCATION = "C9N11" #SEC = "1" !CDS_SEC = "1";
"A":   PN = "1"  !CDS_PN = "1";
"B":   PN = "2"  !CDS_PN = "2";
BODY = "CAPP","I14": #LOCATION = "C9N20" !CDS_LOCATION = "C9N20" #SEC = "1" !CDS_SEC = "1";
"A":   PN = "1"  !CDS_PN = "1";
"B":   PN = "2"  !CDS_PN = "2";
BODY = "RES","I20": #LOCATION = "R9N3" !CDS_LOCATION = "R9N3" #SEC = "1" !CDS_SEC = "1";
"A":   PN = "1"  !CDS_PN = "1";
"B":   PN = "2"  !CDS_PN = "2";
BODY = "CAP","I22": #LOCATION = "C1C4" !CDS_LOCATION = "C1C4" #SEC = "1" !CDS_SEC = "1";
"A":   PN = "1"  !CDS_PN = "1";
"B":   PN = "2"  !CDS_PN = "2";
BODY = "CAP_A","I23": #LOCATION = "C1C3" !CDS_LOCATION = "C1C3" #SEC = "1" !CDS_SEC = "1";
"A":   PN = "1"  !CDS_PN = "1";
"B":   PN = "2"  !CDS_PN = "2";
BODY = "CAP","I24": #LOCATION = "C1C12" !CDS_LOCATION = "C1C12" #SEC = "1" !CDS_SEC = "1";
"A":   PN = "1"  !CDS_PN = "1";
"B":   PN = "2"  !CDS_PN = "2";
BODY = "CAP","I26": #LOCATION = "C1C5" !CDS_LOCATION = "C1C5" #SEC = "1" !CDS_SEC = "1";
"A":   PN = "1"  !CDS_PN = "1";
"B":   PN = "2"  !CDS_PN = "2";
BODY = "CAP_A","I27": #LOCATION = "C1C17" !CDS_LOCATION = "C1C17" #SEC = "1" !CDS_SEC = "1";
"A":   PN = "1"  !CDS_PN = "1";
"B":   PN = "2"  !CDS_PN = "2";
BODY = "CAP","I28": #LOCATION = "C1C15" !CDS_LOCATION = "C1C15" #SEC = "1" !CDS_SEC = "1";
"A":   PN = "1"  !CDS_PN = "1";
"B":   PN = "2"  !CDS_PN = "2";
BODY = "RES","I29": #LOCATION = "R1C12" !CDS_LOCATION = "R1C12" #SEC = "1" !CDS_SEC = "1";
"A":   PN = "1"  !CDS_PN = "1";
"B":   PN = "2"  !CDS_PN = "2";
BODY = "RES","I31": #LOCATION = "R1C7" !CDS_LOCATION = "R1C7" #SEC = "1" !CDS_SEC = "1";
"A":   PN = "1"  !CDS_PN = "1";
"B":   PN = "2"  !CDS_PN = "2";
BODY = "RES","I32": #LOCATION = "R1C5" !CDS_LOCATION = "R1C5" #SEC = "1" !CDS_SEC = "1";
"A":   PN = "1"  !CDS_PN = "1";
"B":   PN = "2"  !CDS_PN = "2";
BODY = "RES","I33": #LOCATION = "R1C4" !CDS_LOCATION = "R1C4" #SEC = "1" !CDS_SEC = "1";
"A":   PN = "1"  !CDS_PN = "1";
"B":   PN = "2"  !CDS_PN = "2";
BODY = "RES","I34": #LOCATION = "R1C6" !CDS_LOCATION = "R1C6" #SEC = "1" !CDS_SEC = "1";
"A":   PN = "1"  !CDS_PN = "1";
"B":   PN = "2"  !CDS_PN = "2";
BODY = "CAP","I35": #LOCATION = "C9N13" !CDS_LOCATION = "C9N13" #SEC = "1" !CDS_SEC = "1";
"A":   PN = "1"  !CDS_PN = "1";
"B":   PN = "2"  !CDS_PN = "2";
BODY = "CAP","I36": #LOCATION = "C9N19" !CDS_LOCATION = "C9N19" #SEC = "1" !CDS_SEC = "1";
"A":   PN = "1"  !CDS_PN = "1";
"B":   PN = "2"  !CDS_PN = "2";
BODY = "CAP","I38": #LOCATION = "C9N21" !CDS_LOCATION = "C9N21" #SEC = "1" !CDS_SEC = "1";
"A":   PN = "1"  !CDS_PN = "1";
"B":   PN = "2"  !CDS_PN = "2";
BODY = "CAP_A","I44": #LOCATION = "C9N22" !CDS_LOCATION = "C9N22" #SEC = "1" !CDS_SEC = "1";
"A":   PN = "1"  !CDS_PN = "1";
"B":   PN = "2"  !CDS_PN = "2";
BODY = "RES","I45": #LOCATION = "R9N4" !CDS_LOCATION = "R9N4" &SEC = "1" #&CDS_SEC = "1";
"A":   PN = "1"  !CDS_PN = "1";
"B":   PN = "2"  !CDS_PN = "2";
BODY = "IR354XX","I51": #LOCATION = "EU1C1" !CDS_LOCATION = "EU1C1" #SEC = "1" !CDS_SEC = "1";
"BOOST":   PN = "33"  !CDS_PN = "33";
"EN":   PN = "35"  !CDS_PN = "35";
"GL<0>":   PN = "6"  !CDS_PN = "6";
"GL<1>":   PN = "41"  !CDS_PN = "41";
"IOUT":   PN = "38"  !CDS_PN = "38";
"LGND":   PN = "2"  !CDS_PN = "2";
"NC":   PN = "31"  !CDS_PN = "31";
"OCSET":   PN = "37"  !CDS_PN = "37";
"PGND<0>":   PN = "5"  !CDS_PN = "5";
"PGND<1>":   PN = "7"  !CDS_PN = "7";
"PGND<2>":   PN = "40"  !CDS_PN = "40";
"PHASE":   PN = "32"  !CDS_PN = "32";
"PWM":   PN = "34"  !CDS_PN = "34";
"REFIN":   PN = "39"  !CDS_PN = "39";
"SW":   PN = "10"  !CDS_PN = "10";
"TOUT_FLT":   PN = "36"  !CDS_PN = "36";
"VCC":   PN = "3"  !CDS_PN = "3";
"VDRV":   PN = "4"  !CDS_PN = "4";
"VIN<0>":   PN = "25"  !CDS_PN = "25";
"VIN<1>":   PN = "30"  !CDS_PN = "30";
"VOS":   PN = "1"  !CDS_PN = "1";
BODY = "RES","I52": #LOCATION = "R1C37" !CDS_LOCATION = "R1C37" &SEC = "1" #&CDS_SEC = "1";
"A":   PN = "1"  !CDS_PN = "1";
"B":   PN = "2"  !CDS_PN = "2";
BODY = "CAP_A","I55": #LOCATION = "CT57" !CDS_LOCATION = "CT57" &SEC = "1" #&CDS_SEC = "1";
"A":   PN = "1"  !CDS_PN = "1";
"B":   PN = "2"  !CDS_PN = "2";
BODY = "SC2K2P50V3KX-GP","I57": #LOCATION = "CT56" !CDS_LOCATION = "CT56" &SEC = "1" #&CDS_SEC = "1";
"1":   PN = "1"  !CDS_PN = "1";
"2":   PN = "2"  !CDS_PN = "2";
BODY = "CAP","I60": #LOCATION = "CT55" !CDS_LOCATION = "CT55" &SEC = "1" #&CDS_SEC = "1";
"A":   PN = "1"  !CDS_PN = "1";
"B":   PN = "2"  !CDS_PN = "2";
BODY = "3D01R5F-GP","I59": #LOCATION = "RT38" !CDS_LOCATION = "RT38" &SEC = "1" #&CDS_SEC = "1";
"1":   PN = "1"  !CDS_PN = "1";
"2":   PN = "2"  !CDS_PN = "2";
BODY = "RES","I62": #LOCATION = "RT37" !CDS_LOCATION = "RT37" &SEC = "1" #&CDS_SEC = "1";
"A":   PN = "1"  !CDS_PN = "1";
"B":   PN = "2"  !CDS_PN = "2";
DRAWING = "@baseboard_fab2_lib.baseboard_fab2(sch_1):page205";
BODY = "CAP_A","I5": #LOCATION = "C6N7" !CDS_LOCATION = "C6N7" #SEC = "1" !CDS_SEC = "1";
"A":   PN = "1"  !CDS_PN = "1";
"B":   PN = "2"  !CDS_PN = "2";
BODY = "INDUCTOR","I7": #LOCATION = "L4C2" !CDS_LOCATION = "L4C2" #SEC = "1" !CDS_SEC = "1";
"INA":   PN = "1"  !CDS_PN = "1";
"INB":   PN = "2"  !CDS_PN = "2";
BODY = "CAPP","I12": #LOCATION = "C6N1" !CDS_LOCATION = "C6N1" #SEC = "1" !CDS_SEC = "1";
"A":   PN = "1"  !CDS_PN = "1";
"B":   PN = "2"  !CDS_PN = "2";
BODY = "CAPP","I14": #LOCATION = "C6N4" !CDS_LOCATION = "C6N4" #SEC = "1" !CDS_SEC = "1";
"A":   PN = "1"  !CDS_PN = "1";
"B":   PN = "2"  !CDS_PN = "2";
BODY = "CAP","I16": #LOCATION = "C4C5" !CDS_LOCATION = "C4C5" #SEC = "1" !CDS_SEC = "1";
"A":   PN = "1"  !CDS_PN = "1";
"B":   PN = "2"  !CDS_PN = "2";
BODY = "CAP_A","I18": #LOCATION = "C4C4" !CDS_LOCATION = "C4C4" #SEC = "1" !CDS_SEC = "1";
"A":   PN = "1"  !CDS_PN = "1";
"B":   PN = "2"  !CDS_PN = "2";
BODY = "RES","I19": #LOCATION = "R6N3" !CDS_LOCATION = "R6N3" #SEC = "1" !CDS_SEC = "1";
"A":   PN = "1"  !CDS_PN = "1";
"B":   PN = "2"  !CDS_PN = "2";
BODY = "CAP","I20": #LOCATION = "C4C6" !CDS_LOCATION = "C4C6" #SEC = "1" !CDS_SEC = "1";
"A":   PN = "1"  !CDS_PN = "1";
"B":   PN = "2"  !CDS_PN = "2";
BODY = "RES","I24": #LOCATION = "R4C5" !CDS_LOCATION = "R4C5" #SEC = "1" !CDS_SEC = "1";
"A":   PN = "1"  !CDS_PN = "1";
"B":   PN = "2"  !CDS_PN = "2";
BODY = "CAP","I25": #LOCATION = "C4C8" !CDS_LOCATION = "C4C8" #SEC = "1" !CDS_SEC = "1";
"A":   PN = "1"  !CDS_PN = "1";
"B":   PN = "2"  !CDS_PN = "2";
BODY = "RES","I26": #LOCATION = "R4C4" !CDS_LOCATION = "R4C4" #SEC = "1" !CDS_SEC = "1";
"A":   PN = "1"  !CDS_PN = "1";
"B":   PN = "2"  !CDS_PN = "2";
BODY = "RES","I29": #LOCATION = "R4C1" !CDS_LOCATION = "R4C1" #SEC = "1" !CDS_SEC = "1";
"A":   PN = "1"  !CDS_PN = "1";
"B":   PN = "2"  !CDS_PN = "2";
BODY = "RES","I30": #LOCATION = "R4C2" !CDS_LOCATION = "R4C2" #SEC = "1" !CDS_SEC = "1";
"A":   PN = "1"  !CDS_PN = "1";
"B":   PN = "2"  !CDS_PN = "2";
BODY = "CAP_A","I31": #LOCATION = "C4C10" !CDS_LOCATION = "C4C10" #SEC = "1" !CDS_SEC = "1";
"A":   PN = "1"  !CDS_PN = "1";
"B":   PN = "2"  !CDS_PN = "2";
BODY = "CAP","I32": #LOCATION = "C4C9" !CDS_LOCATION = "C4C9" #SEC = "1" !CDS_SEC = "1";
"A":   PN = "1"  !CDS_PN = "1";
"B":   PN = "2"  !CDS_PN = "2";
BODY = "CAP","I33": #LOCATION = "C6N2" !CDS_LOCATION = "C6N2" #SEC = "1" !CDS_SEC = "1";
"A":   PN = "1"  !CDS_PN = "1";
"B":   PN = "2"  !CDS_PN = "2";
BODY = "CAP","I34": #LOCATION = "C6N3" !CDS_LOCATION = "C6N3" #SEC = "1" !CDS_SEC = "1";
"A":   PN = "1"  !CDS_PN = "1";
"B":   PN = "2"  !CDS_PN = "2";
BODY = "CAP","I35": #LOCATION = "C6N6" !CDS_LOCATION = "C6N6" #SEC = "1" !CDS_SEC = "1";
"A":   PN = "1"  !CDS_PN = "1";
"B":   PN = "2"  !CDS_PN = "2";
BODY = "RES","I37": #LOCATION = "R4C3" !CDS_LOCATION = "R4C3" #SEC = "1" !CDS_SEC = "1";
"A":   PN = "1"  !CDS_PN = "1";
"B":   PN = "2"  !CDS_PN = "2";
BODY = "CAP_A","I43": #LOCATION = "C4C11" !CDS_LOCATION = "C4C11" #SEC = "1" !CDS_SEC = "1";
"A":   PN = "1"  !CDS_PN = "1";
"B":   PN = "2"  !CDS_PN = "2";
BODY = "RES","I45": #LOCATION = "R6N4" !CDS_LOCATION = "R6N4" &SEC = "1" #&CDS_SEC = "1";
"A":   PN = "1"  !CDS_PN = "1";
"B":   PN = "2"  !CDS_PN = "2";
BODY = "IR354XX","I46": #LOCATION = "EU4C1" !CDS_LOCATION = "EU4C1" &SEC = "1" #&CDS_SEC = "1";
"BOOST":   PN = "33"  !CDS_PN = "33";
"EN":   PN = "35"  !CDS_PN = "35";
"GL<0>":   PN = "6"  !CDS_PN = "6";
"GL<1>":   PN = "41"  !CDS_PN = "41";
"IOUT":   PN = "38"  !CDS_PN = "38";
"LGND":   PN = "2"  !CDS_PN = "2";
"NC":   PN = "31"  !CDS_PN = "31";
"OCSET":   PN = "37"  !CDS_PN = "37";
"PGND<0>":   PN = "5"  !CDS_PN = "5";
"PGND<1>":   PN = "7"  !CDS_PN = "7";
"PGND<2>":   PN = "40"  !CDS_PN = "40";
"PHASE":   PN = "32"  !CDS_PN = "32";
"PWM":   PN = "34"  !CDS_PN = "34";
"REFIN":   PN = "39"  !CDS_PN = "39";
"SW":   PN = "10"  !CDS_PN = "10";
"TOUT_FLT":   PN = "36"  !CDS_PN = "36";
"VCC":   PN = "3"  !CDS_PN = "3";
"VDRV":   PN = "4"  !CDS_PN = "4";
"VIN<0>":   PN = "25"  !CDS_PN = "25";
"VIN<1>":   PN = "30"  !CDS_PN = "30";
"VOS":   PN = "1"  !CDS_PN = "1";
BODY = "RES","I62": #LOCATION = "R4C13" !CDS_LOCATION = "R4C13" &SEC = "1" #&CDS_SEC = "1";
"A":   PN = "1"  !CDS_PN = "1";
"B":   PN = "2"  !CDS_PN = "2";
BODY = "SC2K2P50V3KX-GP","I64": #LOCATION = "CT59" !CDS_LOCATION = "CT59" &SEC = "1" #&CDS_SEC = "1";
"1":   PN = "1"  !CDS_PN = "1";
"2":   PN = "2"  !CDS_PN = "2";
BODY = "CAP","I65": #LOCATION = "CT58" !CDS_LOCATION = "CT58" &SEC = "1" #&CDS_SEC = "1";
"A":   PN = "1"  !CDS_PN = "1";
"B":   PN = "2"  !CDS_PN = "2";
BODY = "CAP_A","I69": #LOCATION = "CT60" !CDS_LOCATION = "CT60" &SEC = "1" #&CDS_SEC = "1";
"A":   PN = "1"  !CDS_PN = "1";
"B":   PN = "2"  !CDS_PN = "2";
BODY = "3D01R5F-GP","I68": #LOCATION = "RT39" !CDS_LOCATION = "RT39" &SEC = "1" #&CDS_SEC = "1";
"1":   PN = "1"  !CDS_PN = "1";
"2":   PN = "2"  !CDS_PN = "2";
BODY = "RES","I72": #LOCATION = "RT40" !CDS_LOCATION = "RT40" &SEC = "1" #&CDS_SEC = "1";
"A":   PN = "1"  !CDS_PN = "1";
"B":   PN = "2"  !CDS_PN = "2";
DRAWING = "@baseboard_fab2_lib.baseboard_fab2(sch_1):page214";
BODY = "CAP","I8": #LOCATION = "C4E9" !CDS_LOCATION = "C4E9" &SEC = "1" #&CDS_SEC = "1";
"A":   PN = "1"  !CDS_PN = "1";
"B":   PN = "2"  !CDS_PN = "2";
BODY = "CAPP","I20": #LOCATION = "C4E7" !CDS_LOCATION = "C4E7" #SEC = "1" !CDS_SEC = "1";
"A":   PN = "1"  !CDS_PN = "1";
"B":   PN = "2"  !CDS_PN = "2";
BODY = "CAPP","I21": #LOCATION = "C6R12" !CDS_LOCATION = "C6R12" #SEC = "1" !CDS_SEC = "1";
"A":   PN = "1"  !CDS_PN = "1";
"B":   PN = "2"  !CDS_PN = "2";
BODY = "CAPP","I24": #LOCATION = "C6R5" !CDS_LOCATION = "C6R5" #SEC = "1" !CDS_SEC = "1";
"A":   PN = "1"  !CDS_PN = "1";
"B":   PN = "2"  !CDS_PN = "2";
BODY = "CAP","I29": #LOCATION = "C4E8" !CDS_LOCATION = "C4E8" #SEC = "1" !CDS_SEC = "1";
"A":   PN = "1"  !CDS_PN = "1";
"B":   PN = "2"  !CDS_PN = "2";
BODY = "CAP","I31": #LOCATION = "C4E14" !CDS_LOCATION = "C4E14" #SEC = "1" !CDS_SEC = "1";
"A":   PN = "1"  !CDS_PN = "1";
"B":   PN = "2"  !CDS_PN = "2";
BODY = "CAP_A","I65": #LOCATION = "C7R1" !CDS_LOCATION = "C7R1" #SEC = "1" !CDS_SEC = "1";
"A":   PN = "1"  !CDS_PN = "1";
"B":   PN = "2"  !CDS_PN = "2";
BODY = "INDUCTOR","I67": #LOCATION = "L4E2" !CDS_LOCATION = "L4E2" &SEC = "1" #&CDS_SEC = "1";
"INA":   PN = "1"  !CDS_PN = "1";
"INB":   PN = "2"  !CDS_PN = "2";
BODY = "RES","I71": #LOCATION = "R6R5" !CDS_LOCATION = "R6R5" #SEC = "1" !CDS_SEC = "1";
"A":   PN = "1"  !CDS_PN = "1";
"B":   PN = "2"  !CDS_PN = "2";
BODY = "CAP","I73": #LOCATION = "C4E23" !CDS_LOCATION = "C4E23" #SEC = "1" !CDS_SEC = "1";
"A":   PN = "1"  !CDS_PN = "1";
"B":   PN = "2"  !CDS_PN = "2";
BODY = "CAP_A","I74": #LOCATION = "C4E28" !CDS_LOCATION = "C4E28" #SEC = "1" !CDS_SEC = "1";
"A":   PN = "1"  !CDS_PN = "1";
"B":   PN = "2"  !CDS_PN = "2";
BODY = "CAP","I76": #LOCATION = "C4E22" !CDS_LOCATION = "C4E22" #SEC = "1" !CDS_SEC = "1";
"A":   PN = "1"  !CDS_PN = "1";
"B":   PN = "2"  !CDS_PN = "2";
BODY = "CAP_A","I77": #LOCATION = "C4E13" !CDS_LOCATION = "C4E13" #SEC = "1" !CDS_SEC = "1";
"A":   PN = "1"  !CDS_PN = "1";
"B":   PN = "2"  !CDS_PN = "2";
BODY = "CAP","I78": #LOCATION = "C4E18" !CDS_LOCATION = "C4E18" #SEC = "1" !CDS_SEC = "1";
"A":   PN = "1"  !CDS_PN = "1";
"B":   PN = "2"  !CDS_PN = "2";
BODY = "CAP","I79": #LOCATION = "C4E15" !CDS_LOCATION = "C4E15" #SEC = "1" !CDS_SEC = "1";
"A":   PN = "1"  !CDS_PN = "1";
"B":   PN = "2"  !CDS_PN = "2";
BODY = "CAP","I80": #LOCATION = "C6R14" !CDS_LOCATION = "C6R14" #SEC = "1" !CDS_SEC = "1";
"A":   PN = "1"  !CDS_PN = "1";
"B":   PN = "2"  !CDS_PN = "2";
BODY = "CAP","I81": #LOCATION = "C6R10" !CDS_LOCATION = "C6R10" #SEC = "1" !CDS_SEC = "1";
"A":   PN = "1"  !CDS_PN = "1";
"B":   PN = "2"  !CDS_PN = "2";
BODY = "CAP","I83": #LOCATION = "C6R8" !CDS_LOCATION = "C6R8" #SEC = "1" !CDS_SEC = "1";
"A":   PN = "1"  !CDS_PN = "1";
"B":   PN = "2"  !CDS_PN = "2";
BODY = "CAP_A","I96": #LOCATION = "C3D27" !CDS_LOCATION = "C3D27" #SEC = "1" !CDS_SEC = "1";
"A":   PN = "1"  !CDS_PN = "1";
"B":   PN = "2"  !CDS_PN = "2";
BODY = "RES","I101": #LOCATION = "R3D28" !CDS_LOCATION = "R3D28" #SEC = "1" !CDS_SEC = "1";
"A":   PN = "1"  !CDS_PN = "1";
"B":   PN = "2"  !CDS_PN = "2";
BODY = "RES","I105": #LOCATION = "R3E1" !CDS_LOCATION = "R3E1" #SEC = "1" !CDS_SEC = "1";
"A":   PN = "1"  !CDS_PN = "1";
"B":   PN = "2"  !CDS_PN = "2";
BODY = "CAP_A","I108": #LOCATION = "C3E1" !CDS_LOCATION = "C3E1" &SEC = "1" #&CDS_SEC = "1";
"A":   PN = "1"  !CDS_PN = "1";
"B":   PN = "2"  !CDS_PN = "2";
BODY = "RES","I109": #LOCATION = "R7R1" !CDS_LOCATION = "R7R1" &SEC = "1" #&CDS_SEC = "1";
"A":   PN = "1"  !CDS_PN = "1";
"B":   PN = "2"  !CDS_PN = "2";
BODY = "IR354XX","I126": #LOCATION = "EU4E2" !CDS_LOCATION = "EU4E2" #SEC = "1" !CDS_SEC = "1";
"BOOST":   PN = "33"  !CDS_PN = "33";
"EN":   PN = "35"  !CDS_PN = "35";
"GL<0>":   PN = "6"  !CDS_PN = "6";
"GL<1>":   PN = "41"  !CDS_PN = "41";
"IOUT":   PN = "38"  !CDS_PN = "38";
"LGND":   PN = "2"  !CDS_PN = "2";
"NC":   PN = "31"  !CDS_PN = "31";
"OCSET":   PN = "37"  !CDS_PN = "37";
"PGND<0>":   PN = "5"  !CDS_PN = "5";
"PGND<1>":   PN = "7"  !CDS_PN = "7";
"PGND<2>":   PN = "40"  !CDS_PN = "40";
"PHASE":   PN = "32"  !CDS_PN = "32";
"PWM":   PN = "34"  !CDS_PN = "34";
"REFIN":   PN = "39"  !CDS_PN = "39";
"SW":   PN = "10"  !CDS_PN = "10";
"TOUT_FLT":   PN = "36"  !CDS_PN = "36";
"VCC":   PN = "3"  !CDS_PN = "3";
"VDRV":   PN = "4"  !CDS_PN = "4";
"VIN<0>":   PN = "25"  !CDS_PN = "25";
"VIN<1>":   PN = "30"  !CDS_PN = "30";
"VOS":   PN = "1"  !CDS_PN = "1";
BODY = "RES","I127": #LOCATION = "R4E21" !CDS_LOCATION = "R4E21" &SEC = "1" #&CDS_SEC = "1";
"A":   PN = "1"  !CDS_PN = "1";
"B":   PN = "2"  !CDS_PN = "2";
BODY = "SHUNT","I129": #LOCATION = "SH3D2" !CDS_LOCATION = "SH3D2" #SEC = "1" !CDS_SEC = "1";
"A":   PN = "1"  !CDS_PN = "1";
"B":   PN = "2"  !CDS_PN = "2";
BODY = "SHUNT","I130": #LOCATION = "SH3D1" !CDS_LOCATION = "SH3D1" #SEC = "1" !CDS_SEC = "1";
"A":   PN = "1"  !CDS_PN = "1";
"B":   PN = "2"  !CDS_PN = "2";
BODY = "SC2K2P50V3KX-GP","I131": #LOCATION = "CT62" !CDS_LOCATION = "CT62" &SEC = "1" #&CDS_SEC = "1";
"1":   PN = "1"  !CDS_PN = "1";
"2":   PN = "2"  !CDS_PN = "2";
BODY = "CAP","I134": #LOCATION = "CT61" !CDS_LOCATION = "CT61" &SEC = "1" #&CDS_SEC = "1";
"A":   PN = "1"  !CDS_PN = "1";
"B":   PN = "2"  !CDS_PN = "2";
BODY = "CAP_A","I137": #LOCATION = "CT63" !CDS_LOCATION = "CT63" &SEC = "1" #&CDS_SEC = "1";
"A":   PN = "1"  !CDS_PN = "1";
"B":   PN = "2"  !CDS_PN = "2";
BODY = "3D01R5F-GP","I132": #LOCATION = "RT42" !CDS_LOCATION = "RT42" &SEC = "1" #&CDS_SEC = "1";
"1":   PN = "1"  !CDS_PN = "1";
"2":   PN = "2"  !CDS_PN = "2";
BODY = "RES","I139": #LOCATION = "RT41" !CDS_LOCATION = "RT41" &SEC = "1" #&CDS_SEC = "1";
"A":   PN = "1"  !CDS_PN = "1";
"B":   PN = "2"  !CDS_PN = "2";
DRAWING = "@baseboard_fab2_lib.baseboard_fab2(sch_1):page236";
BODY = "CAP","I9": #LOCATION = "C7A30" !CDS_LOCATION = "C7A30" #SEC = "1" !CDS_SEC = "1";
"A":   PN = "1"  !CDS_PN = "1";
"B":   PN = "2"  !CDS_PN = "2";
BODY = "INDUCTOR","I10": #LOCATION = "L7A2" !CDS_LOCATION = "L7A2" #SEC = "1" !CDS_SEC = "1";
"INA":   PN = "1"  !CDS_PN = "1";
"INB":   PN = "2"  !CDS_PN = "2";
BODY = "RES","I14": #LOCATION = "R3L1" !CDS_LOCATION = "R3L1" #SEC = "1" !CDS_SEC = "1";
"A":   PN = "1"  !CDS_PN = "1";
"B":   PN = "2"  !CDS_PN = "2";
BODY = "CAP","I16": #LOCATION = "C7A8" !CDS_LOCATION = "C7A8" #SEC = "1" !CDS_SEC = "1";
"A":   PN = "1"  !CDS_PN = "1";
"B":   PN = "2"  !CDS_PN = "2";
BODY = "CAP_A","I17": #LOCATION = "C3L1" !CDS_LOCATION = "C3L1" #SEC = "1" !CDS_SEC = "1";
"A":   PN = "1"  !CDS_PN = "1";
"B":   PN = "2"  !CDS_PN = "2";
BODY = "CAP","I19": #LOCATION = "C7A6" !CDS_LOCATION = "C7A6" #SEC = "1" !CDS_SEC = "1";
"A":   PN = "1"  !CDS_PN = "1";
"B":   PN = "2"  !CDS_PN = "2";
BODY = "CAP_A","I20": #LOCATION = "C7A39" !CDS_LOCATION = "C7A39" #SEC = "1" !CDS_SEC = "1";
"A":   PN = "1"  !CDS_PN = "1";
"B":   PN = "2"  !CDS_PN = "2";
BODY = "CAP","I21": #LOCATION = "C7A43" !CDS_LOCATION = "C7A43" #SEC = "1" !CDS_SEC = "1";
"A":   PN = "1"  !CDS_PN = "1";
"B":   PN = "2"  !CDS_PN = "2";
BODY = "CAP","I22": #LOCATION = "C7A7" !CDS_LOCATION = "C7A7" #SEC = "1" !CDS_SEC = "1";
"A":   PN = "1"  !CDS_PN = "1";
"B":   PN = "2"  !CDS_PN = "2";
BODY = "CAP","I23": #LOCATION = "C3L12" !CDS_LOCATION = "C3L12" #SEC = "1" !CDS_SEC = "1";
"A":   PN = "1"  !CDS_PN = "1";
"B":   PN = "2"  !CDS_PN = "2";
BODY = "CAP","I24": #LOCATION = "C3L11" !CDS_LOCATION = "C3L11" #SEC = "1" !CDS_SEC = "1";
"A":   PN = "1"  !CDS_PN = "1";
"B":   PN = "2"  !CDS_PN = "2";
BODY = "CAP","I26": #LOCATION = "C3L8" !CDS_LOCATION = "C3L8" #SEC = "1" !CDS_SEC = "1";
"A":   PN = "1"  !CDS_PN = "1";
"B":   PN = "2"  !CDS_PN = "2";
BODY = "CAP","I29": #LOCATION = "C3L9" !CDS_LOCATION = "C3L9" #SEC = "1" !CDS_SEC = "1";
"A":   PN = "1"  !CDS_PN = "1";
"B":   PN = "2"  !CDS_PN = "2";
BODY = "CAP","I31": #LOCATION = "C3L7" !CDS_LOCATION = "C3L7" #SEC = "1" !CDS_SEC = "1";
"A":   PN = "1"  !CDS_PN = "1";
"B":   PN = "2"  !CDS_PN = "2";
BODY = "CAP","I32": #LOCATION = "C3L10" !CDS_LOCATION = "C3L10" #SEC = "1" !CDS_SEC = "1";
"A":   PN = "1"  !CDS_PN = "1";
"B":   PN = "2"  !CDS_PN = "2";
BODY = "CAP","I33": #LOCATION = "C7A9" !CDS_LOCATION = "C7A9" #SEC = "1" !CDS_SEC = "1";
"A":   PN = "1"  !CDS_PN = "1";
"B":   PN = "2"  !CDS_PN = "2";
BODY = "CAP","I34": #LOCATION = "C7A44" !CDS_LOCATION = "C7A44" #SEC = "1" !CDS_SEC = "1";
"A":   PN = "1"  !CDS_PN = "1";
"B":   PN = "2"  !CDS_PN = "2";
BODY = "CAP_A","I35": #LOCATION = "C7A40" !CDS_LOCATION = "C7A40" #SEC = "1" !CDS_SEC = "1";
"A":   PN = "1"  !CDS_PN = "1";
"B":   PN = "2"  !CDS_PN = "2";
BODY = "CAP","I36": #LOCATION = "C7A10" !CDS_LOCATION = "C7A10" #SEC = "1" !CDS_SEC = "1";
"A":   PN = "1"  !CDS_PN = "1";
"B":   PN = "2"  !CDS_PN = "2";
BODY = "CAP_A","I38": #LOCATION = "C3L29" !CDS_LOCATION = "C3L29" #SEC = "1" !CDS_SEC = "1";
"A":   PN = "1"  !CDS_PN = "1";
"B":   PN = "2"  !CDS_PN = "2";
BODY = "CAP","I39": #LOCATION = "C7A41" !CDS_LOCATION = "C7A41" #SEC = "1" !CDS_SEC = "1";
"A":   PN = "1"  !CDS_PN = "1";
"B":   PN = "2"  !CDS_PN = "2";
BODY = "RES","I41": #LOCATION = "R3L4" !CDS_LOCATION = "R3L4" #SEC = "1" !CDS_SEC = "1";
"A":   PN = "1"  !CDS_PN = "1";
"B":   PN = "2"  !CDS_PN = "2";
BODY = "INDUCTOR","I45": #LOCATION = "L7A4" !CDS_LOCATION = "L7A4" #SEC = "1" !CDS_SEC = "1";
"INA":   PN = "1"  !CDS_PN = "1";
"INB":   PN = "2"  !CDS_PN = "2";
BODY = "CAP","I46": #LOCATION = "C7A42" !CDS_LOCATION = "C7A42" #SEC = "1" !CDS_SEC = "1";
"A":   PN = "1"  !CDS_PN = "1";
"B":   PN = "2"  !CDS_PN = "2";
BODY = "RES","I56": #LOCATION = "R8B14" !CDS_LOCATION = "R8B14" #SEC = "1" !CDS_SEC = "1";
"A":   PN = "1"  !CDS_PN = "1";
"B":   PN = "2"  !CDS_PN = "2";
BODY = "RES","I57": #LOCATION = "R8B15" !CDS_LOCATION = "R8B15" #SEC = "1" !CDS_SEC = "1";
"A":   PN = "1"  !CDS_PN = "1";
"B":   PN = "2"  !CDS_PN = "2";
BODY = "RES","I59": #LOCATION = "R8B12" !CDS_LOCATION = "R8B12" #SEC = "1" !CDS_SEC = "1";
"A":   PN = "1"  !CDS_PN = "1";
"B":   PN = "2"  !CDS_PN = "2";
BODY = "CAP","I63": #LOCATION = "C7A13" !CDS_LOCATION = "C7A13" &SEC = "1" #&CDS_SEC = "1";
"A":   PN = "1"  !CDS_PN = "1";
"B":   PN = "2"  !CDS_PN = "2";
BODY = "CAP","I65": #LOCATION = "C7A14" !CDS_LOCATION = "C7A14" &SEC = "1" #&CDS_SEC = "1";
"A":   PN = "1"  !CDS_PN = "1";
"B":   PN = "2"  !CDS_PN = "2";
BODY = "CAPP","I71": #LOCATION = "C3L18" !CDS_LOCATION = "C3L18" #SEC = "1" !CDS_SEC = "1";
"A":   PN = "1"  !CDS_PN = "1";
"B":   PN = "2"  !CDS_PN = "2";
BODY = "CAPP","I73": #LOCATION = "C3L20" !CDS_LOCATION = "C3L20" #SEC = "1" !CDS_SEC = "1";
"A":   PN = "1"  !CDS_PN = "1";
"B":   PN = "2"  !CDS_PN = "2";
BODY = "CAPP","I74": #LOCATION = "C3L21" !CDS_LOCATION = "C3L21" #SEC = "1" !CDS_SEC = "1";
"A":   PN = "1"  !CDS_PN = "1";
"B":   PN = "2"  !CDS_PN = "2";
BODY = "CAPP","I75": #LOCATION = "C7A27" !CDS_LOCATION = "C7A27" #SEC = "1" !CDS_SEC = "1";
"A":   PN = "1"  !CDS_PN = "1";
"B":   PN = "2"  !CDS_PN = "2";
BODY = "CAPP","I76": #LOCATION = "C3L19" !CDS_LOCATION = "C3L19" #SEC = "1" !CDS_SEC = "1";
"A":   PN = "1"  !CDS_PN = "1";
"B":   PN = "2"  !CDS_PN = "2";
BODY = "CAPP","I77": #LOCATION = "C2L46" !CDS_LOCATION = "C2L46" &SEC = "1" #&CDS_SEC = "1";
"A":   PN = "1"  !CDS_PN = "1";
"B":   PN = "2"  !CDS_PN = "2";
BODY = "CAPP","I78": #LOCATION = "C8A15" !CDS_LOCATION = "C8A15" &SEC = "1" #&CDS_SEC = "1";
"A":   PN = "1"  !CDS_PN = "1";
"B":   PN = "2"  !CDS_PN = "2";
BODY = "CAPP","I79": #LOCATION = "C2L25" !CDS_LOCATION = "C2L25" &SEC = "1" #&CDS_SEC = "1";
"A":   PN = "1"  !CDS_PN = "1";
"B":   PN = "2"  !CDS_PN = "2";
BODY = "RES","I90": #LOCATION = "R7A13" !CDS_LOCATION = "R7A13" &SEC = "1" #&CDS_SEC = "1";
"A":   PN = "1"  !CDS_PN = "1";
"B":   PN = "2"  !CDS_PN = "2";
BODY = "RES","I92": #LOCATION = "R7A18" !CDS_LOCATION = "R7A18" &SEC = "1" #&CDS_SEC = "1";
"A":   PN = "1"  !CDS_PN = "1";
"B":   PN = "2"  !CDS_PN = "2";
BODY = "RES","I93": #LOCATION = "R7A19" !CDS_LOCATION = "R7A19" #SEC = "1" !CDS_SEC = "1";
"A":   PN = "1"  !CDS_PN = "1";
"B":   PN = "2"  !CDS_PN = "2";
BODY = "RES","I94": #LOCATION = "R7A14" !CDS_LOCATION = "R7A14" #SEC = "1" !CDS_SEC = "1";
"A":   PN = "1"  !CDS_PN = "1";
"B":   PN = "2"  !CDS_PN = "2";
BODY = "IR354XX","I116": #LOCATION = "EU7A3" !CDS_LOCATION = "EU7A3" #SEC = "1" !CDS_SEC = "1";
"BOOST":   PN = "33"  !CDS_PN = "33";
"EN":   PN = "35"  !CDS_PN = "35";
"GL<0>":   PN = "6"  !CDS_PN = "6";
"GL<1>":   PN = "41"  !CDS_PN = "41";
"IOUT":   PN = "38"  !CDS_PN = "38";
"LGND":   PN = "2"  !CDS_PN = "2";
"NC":   PN = "31"  !CDS_PN = "31";
"OCSET":   PN = "37"  !CDS_PN = "37";
"PGND<0>":   PN = "5"  !CDS_PN = "5";
"PGND<1>":   PN = "7"  !CDS_PN = "7";
"PGND<2>":   PN = "40"  !CDS_PN = "40";
"PHASE":   PN = "32"  !CDS_PN = "32";
"PWM":   PN = "34"  !CDS_PN = "34";
"REFIN":   PN = "39"  !CDS_PN = "39";
"SW":   PN = "10"  !CDS_PN = "10";
"TOUT_FLT":   PN = "36"  !CDS_PN = "36";
"VCC":   PN = "3"  !CDS_PN = "3";
"VDRV":   PN = "4"  !CDS_PN = "4";
"VIN<0>":   PN = "25"  !CDS_PN = "25";
"VIN<1>":   PN = "30"  !CDS_PN = "30";
"VOS":   PN = "1"  !CDS_PN = "1";
BODY = "IR354XX","I117": #LOCATION = "EU7A2" !CDS_LOCATION = "EU7A2" #SEC = "1" !CDS_SEC = "1";
"BOOST":   PN = "33"  !CDS_PN = "33";
"EN":   PN = "35"  !CDS_PN = "35";
"GL<0>":   PN = "6"  !CDS_PN = "6";
"GL<1>":   PN = "41"  !CDS_PN = "41";
"IOUT":   PN = "38"  !CDS_PN = "38";
"LGND":   PN = "2"  !CDS_PN = "2";
"NC":   PN = "31"  !CDS_PN = "31";
"OCSET":   PN = "37"  !CDS_PN = "37";
"PGND<0>":   PN = "5"  !CDS_PN = "5";
"PGND<1>":   PN = "7"  !CDS_PN = "7";
"PGND<2>":   PN = "40"  !CDS_PN = "40";
"PHASE":   PN = "32"  !CDS_PN = "32";
"PWM":   PN = "34"  !CDS_PN = "34";
"REFIN":   PN = "39"  !CDS_PN = "39";
"SW":   PN = "10"  !CDS_PN = "10";
"TOUT_FLT":   PN = "36"  !CDS_PN = "36";
"VCC":   PN = "3"  !CDS_PN = "3";
"VDRV":   PN = "4"  !CDS_PN = "4";
"VIN<0>":   PN = "25"  !CDS_PN = "25";
"VIN<1>":   PN = "30"  !CDS_PN = "30";
"VOS":   PN = "1"  !CDS_PN = "1";
BODY = "RES","I118": #LOCATION = "R3L15" !CDS_LOCATION = "R3L15" &SEC = "1" #&CDS_SEC = "1";
"A":   PN = "1"  !CDS_PN = "1";
"B":   PN = "2"  !CDS_PN = "2";
BODY = "RES","I120": #LOCATION = "R3L14" !CDS_LOCATION = "R3L14" &SEC = "1" #&CDS_SEC = "1";
"A":   PN = "1"  !CDS_PN = "1";
"B":   PN = "2"  !CDS_PN = "2";
BODY = "CAP_A","I124": #LOCATION = "CT67" !CDS_LOCATION = "CT67" &SEC = "1" #&CDS_SEC = "1";
"A":   PN = "1"  !CDS_PN = "1";
"B":   PN = "2"  !CDS_PN = "2";
BODY = "CAP_A","I127": #LOCATION = "CT66" !CDS_LOCATION = "CT66" &SEC = "1" #&CDS_SEC = "1";
"A":   PN = "1"  !CDS_PN = "1";
"B":   PN = "2"  !CDS_PN = "2";
BODY = "SC2K2P50V3KX-GP","I131": #LOCATION = "CT65" !CDS_LOCATION = "CT65" &SEC = "1" #&CDS_SEC = "1";
"1":   PN = "1"  !CDS_PN = "1";
"2":   PN = "2"  !CDS_PN = "2";
BODY = "CAP","I134": #LOCATION = "CT69" !CDS_LOCATION = "CT69" &SEC = "1" #&CDS_SEC = "1";
"A":   PN = "1"  !CDS_PN = "1";
"B":   PN = "2"  !CDS_PN = "2";
BODY = "CAP","I136": #LOCATION = "CT64" !CDS_LOCATION = "CT64" &SEC = "1" #&CDS_SEC = "1";
"A":   PN = "1"  !CDS_PN = "1";
"B":   PN = "2"  !CDS_PN = "2";
BODY = "SC2K2P50V3KX-GP","I140": #LOCATION = "CT68" !CDS_LOCATION = "CT68" &SEC = "1" #&CDS_SEC = "1";
"1":   PN = "1"  !CDS_PN = "1";
"2":   PN = "2"  !CDS_PN = "2";
BODY = "3D01R5F-GP","I137": #LOCATION = "RT45" !CDS_LOCATION = "RT45" &SEC = "1" #&CDS_SEC = "1";
"1":   PN = "1"  !CDS_PN = "1";
"2":   PN = "2"  !CDS_PN = "2";
BODY = "3D01R5F-GP","I132": #LOCATION = "RT43" !CDS_LOCATION = "RT43" &SEC = "1" #&CDS_SEC = "1";
"1":   PN = "1"  !CDS_PN = "1";
"2":   PN = "2"  !CDS_PN = "2";
BODY = "RES","I141": #LOCATION = "RT44" !CDS_LOCATION = "RT44" &SEC = "1" #&CDS_SEC = "1";
"A":   PN = "1"  !CDS_PN = "1";
"B":   PN = "2"  !CDS_PN = "2";
BODY = "RES","I142": #LOCATION = "RT46" !CDS_LOCATION = "RT46" &SEC = "1" #&CDS_SEC = "1";
"A":   PN = "1"  !CDS_PN = "1";
"B":   PN = "2"  !CDS_PN = "2";
DRAWING = "@baseboard_fab2_lib.baseboard_fab2(sch_1):page212";
BODY = "CAPP","I16": #LOCATION = "C3N38" !CDS_LOCATION = "C3N38" &SEC = "1" #&CDS_SEC = "1";
"A":   PN = "1"  !CDS_PN = "1";
"B":   PN = "2"  !CDS_PN = "2";
BODY = "CAPP","I17": #LOCATION = "C3N26" !CDS_LOCATION = "C3N26" &SEC = "1" #&CDS_SEC = "1";
"A":   PN = "1"  !CDS_PN = "1";
"B":   PN = "2"  !CDS_PN = "2";
BODY = "CAPP","I18": #LOCATION = "C3N35" !CDS_LOCATION = "C3N35" &SEC = "1" #&CDS_SEC = "1";
"A":   PN = "1"  !CDS_PN = "1";
"B":   PN = "2"  !CDS_PN = "2";
BODY = "CAP_A","I23": #LOCATION = "C7C6" !CDS_LOCATION = "C7C6" #SEC = "1" !CDS_SEC = "1";
"A":   PN = "1"  !CDS_PN = "1";
"B":   PN = "2"  !CDS_PN = "2";
BODY = "INDUCTOR","I25": #LOCATION = "L7C2" !CDS_LOCATION = "L7C2" &SEC = "1" #&CDS_SEC = "1";
"INA":   PN = "1"  !CDS_PN = "1";
"INB":   PN = "2"  !CDS_PN = "2";
BODY = "RES","I32": #LOCATION = "R3N7" !CDS_LOCATION = "R3N7" #SEC = "1" !CDS_SEC = "1";
"A":   PN = "1"  !CDS_PN = "1";
"B":   PN = "2"  !CDS_PN = "2";
BODY = "CAP","I33": #LOCATION = "C7C18" !CDS_LOCATION = "C7C18" #SEC = "1" !CDS_SEC = "1";
"A":   PN = "1"  !CDS_PN = "1";
"B":   PN = "2"  !CDS_PN = "2";
BODY = "CAP_A","I34": #LOCATION = "C7C20" !CDS_LOCATION = "C7C20" #SEC = "1" !CDS_SEC = "1";
"A":   PN = "1"  !CDS_PN = "1";
"B":   PN = "2"  !CDS_PN = "2";
BODY = "CAP","I36": #LOCATION = "C7C17" !CDS_LOCATION = "C7C17" #SEC = "1" !CDS_SEC = "1";
"A":   PN = "1"  !CDS_PN = "1";
"B":   PN = "2"  !CDS_PN = "2";
BODY = "CAP","I37": #LOCATION = "C7C14" !CDS_LOCATION = "C7C14" #SEC = "1" !CDS_SEC = "1";
"A":   PN = "1"  !CDS_PN = "1";
"B":   PN = "2"  !CDS_PN = "2";
BODY = "CAP_A","I38": #LOCATION = "C7C11" !CDS_LOCATION = "C7C11" #SEC = "1" !CDS_SEC = "1";
"A":   PN = "1"  !CDS_PN = "1";
"B":   PN = "2"  !CDS_PN = "2";
BODY = "CAP","I39": #LOCATION = "C7C12" !CDS_LOCATION = "C7C12" #SEC = "1" !CDS_SEC = "1";
"A":   PN = "1"  !CDS_PN = "1";
"B":   PN = "2"  !CDS_PN = "2";
BODY = "CAP","I40": #LOCATION = "C3N36" !CDS_LOCATION = "C3N36" #SEC = "1" !CDS_SEC = "1";
"A":   PN = "1"  !CDS_PN = "1";
"B":   PN = "2"  !CDS_PN = "2";
BODY = "CAP","I41": #LOCATION = "C3N33" !CDS_LOCATION = "C3N33" #SEC = "1" !CDS_SEC = "1";
"A":   PN = "1"  !CDS_PN = "1";
"B":   PN = "2"  !CDS_PN = "2";
BODY = "CAP","I43": #LOCATION = "C3N34" !CDS_LOCATION = "C3N34" #SEC = "1" !CDS_SEC = "1";
"A":   PN = "1"  !CDS_PN = "1";
"B":   PN = "2"  !CDS_PN = "2";
BODY = "CAP","I51": #LOCATION = "C7C8" !CDS_LOCATION = "C7C8" #SEC = "1" !CDS_SEC = "1";
"A":   PN = "1"  !CDS_PN = "1";
"B":   PN = "2"  !CDS_PN = "2";
BODY = "CAP","I54": #LOCATION = "C7C7" !CDS_LOCATION = "C7C7" #SEC = "1" !CDS_SEC = "1";
"A":   PN = "1"  !CDS_PN = "1";
"B":   PN = "2"  !CDS_PN = "2";
BODY = "INDUCTOR","I56": #LOCATION = "L7C1" !CDS_LOCATION = "L7C1" #SEC = "1" !CDS_SEC = "1";
"INA":   PN = "1"  !CDS_PN = "1";
"INB":   PN = "2"  !CDS_PN = "2";
BODY = "CAP_A","I60": #LOCATION = "C3P1" !CDS_LOCATION = "C3P1" &SEC = "1" #&CDS_SEC = "1";
"A":   PN = "1"  !CDS_PN = "1";
"B":   PN = "2"  !CDS_PN = "2";
BODY = "RES","I68": #LOCATION = "R3N20" !CDS_LOCATION = "R3N20" &SEC = "1" #&CDS_SEC = "1";
"A":   PN = "1"  !CDS_PN = "1";
"B":   PN = "2"  !CDS_PN = "2";
BODY = "RES","I74": #LOCATION = "R3N21" !CDS_LOCATION = "R3N21" &SEC = "1" #&CDS_SEC = "1";
"A":   PN = "1"  !CDS_PN = "1";
"B":   PN = "2"  !CDS_PN = "2";
BODY = "CAP_A","I77": #LOCATION = "C7C10" !CDS_LOCATION = "C7C10" #SEC = "1" !CDS_SEC = "1";
"A":   PN = "1"  !CDS_PN = "1";
"B":   PN = "2"  !CDS_PN = "2";
BODY = "RES","I78": #LOCATION = "R7C3" !CDS_LOCATION = "R7C3" #SEC = "1" !CDS_SEC = "1";
"A":   PN = "1"  !CDS_PN = "1";
"B":   PN = "2"  !CDS_PN = "2";
BODY = "IR354XX","I101": #LOCATION = "EU7C1" !CDS_LOCATION = "EU7C1" &SEC = "1" #&CDS_SEC = "1";
"BOOST":   PN = "33"  !CDS_PN = "33";
"EN":   PN = "35"  !CDS_PN = "35";
"GL<0>":   PN = "6"  !CDS_PN = "6";
"GL<1>":   PN = "41"  !CDS_PN = "41";
"IOUT":   PN = "38"  !CDS_PN = "38";
"LGND":   PN = "2"  !CDS_PN = "2";
"NC":   PN = "31"  !CDS_PN = "31";
"OCSET":   PN = "37"  !CDS_PN = "37";
"PGND<0>":   PN = "5"  !CDS_PN = "5";
"PGND<1>":   PN = "7"  !CDS_PN = "7";
"PGND<2>":   PN = "40"  !CDS_PN = "40";
"PHASE":   PN = "32"  !CDS_PN = "32";
"PWM":   PN = "34"  !CDS_PN = "34";
"REFIN":   PN = "39"  !CDS_PN = "39";
"SW":   PN = "10"  !CDS_PN = "10";
"TOUT_FLT":   PN = "36"  !CDS_PN = "36";
"VCC":   PN = "3"  !CDS_PN = "3";
"VDRV":   PN = "4"  !CDS_PN = "4";
"VIN<0>":   PN = "25"  !CDS_PN = "25";
"VIN<1>":   PN = "30"  !CDS_PN = "30";
"VOS":   PN = "1"  !CDS_PN = "1";
BODY = "RES","I103": #LOCATION = "R7C25" !CDS_LOCATION = "R7C25" &SEC = "1" #&CDS_SEC = "1";
"A":   PN = "1"  !CDS_PN = "1";
"B":   PN = "2"  !CDS_PN = "2";
BODY = "SHUNT","I104": #LOCATION = "SH3P1" !CDS_LOCATION = "SH3P1" #SEC = "1" !CDS_SEC = "1";
"A":   PN = "1"  !CDS_PN = "1";
"B":   PN = "2"  !CDS_PN = "2";
BODY = "SHUNT","I105": #LOCATION = "SH3P2" !CDS_LOCATION = "SH3P2" #SEC = "1" !CDS_SEC = "1";
"A":   PN = "1"  !CDS_PN = "1";
"B":   PN = "2"  !CDS_PN = "2";
BODY = "CAP_A","I106": #LOCATION = "CT70" !CDS_LOCATION = "CT70" &SEC = "1" #&CDS_SEC = "1";
"A":   PN = "1"  !CDS_PN = "1";
"B":   PN = "2"  !CDS_PN = "2";
BODY = "CAP","I109": #LOCATION = "CT71" !CDS_LOCATION = "CT71" &SEC = "1" #&CDS_SEC = "1";
"A":   PN = "1"  !CDS_PN = "1";
"B":   PN = "2"  !CDS_PN = "2";
BODY = "SC2K2P50V3KX-GP","I111": #LOCATION = "CT72" !CDS_LOCATION = "CT72" &SEC = "1" #&CDS_SEC = "1";
"1":   PN = "1"  !CDS_PN = "1";
"2":   PN = "2"  !CDS_PN = "2";
BODY = "3D01R5F-GP","I112": #LOCATION = "RT48" !CDS_LOCATION = "RT48" &SEC = "1" #&CDS_SEC = "1";
"1":   PN = "1"  !CDS_PN = "1";
"2":   PN = "2"  !CDS_PN = "2";
BODY = "RES","I114": #LOCATION = "RT47" !CDS_LOCATION = "RT47" &SEC = "1" #&CDS_SEC = "1";
"A":   PN = "1"  !CDS_PN = "1";
"B":   PN = "2"  !CDS_PN = "2";
DRAWING = "@baseboard_fab2_lib.baseboard_fab2(sch_1):page239";
BODY = "CAP","I4": #LOCATION = "C9F10" !CDS_LOCATION = "C9F10" &SEC = "1" #&CDS_SEC = "1";
"A":   PN = "1"  !CDS_PN = "1";
"B":   PN = "2"  !CDS_PN = "2";
BODY = "RES","I6": #LOCATION = "R9F12" !CDS_LOCATION = "R9F12" #SEC = "1" !CDS_SEC = "1";
"A":   PN = "1"  !CDS_PN = "1";
"B":   PN = "2"  !CDS_PN = "2";
BODY = "CAP","I7": #LOCATION = "C9F13" !CDS_LOCATION = "C9F13" #SEC = "1" !CDS_SEC = "1";
"A":   PN = "1"  !CDS_PN = "1";
"B":   PN = "2"  !CDS_PN = "2";
BODY = "CAP","I12": #LOCATION = "C1T15" !CDS_LOCATION = "C1T15" #SEC = "1" !CDS_SEC = "1";
"A":   PN = "1"  !CDS_PN = "1";
"B":   PN = "2"  !CDS_PN = "2";
BODY = "RES","I15": #LOCATION = "R9F32" !CDS_LOCATION = "R9F32" #SEC = "1" !CDS_SEC = "1";
"A":   PN = "1"  !CDS_PN = "1";
"B":   PN = "2"  !CDS_PN = "2";
BODY = "CAP","I22": #LOCATION = "C1T7" !CDS_LOCATION = "C1T7" #SEC = "1" !CDS_SEC = "1";
"A":   PN = "1"  !CDS_PN = "1";
"B":   PN = "2"  !CDS_PN = "2";
BODY = "CAP","I30": #LOCATION = "C9F6" !CDS_LOCATION = "C9F6" &SEC = "1" #&CDS_SEC = "1";
"A":   PN = "1"  !CDS_PN = "1";
"B":   PN = "2"  !CDS_PN = "2";
BODY = "RT9059","I70": #LOCATION = "EU9F2" !CDS_LOCATION = "EU9F2" #SEC = "1" !CDS_SEC = "1";
"ADJ_NC":   PN = "4"  !CDS_PN = "4";
"EN":   PN = "6"  !CDS_PN = "6";
"GND":   PN = "11"  !CDS_PN = "11";
"PGOOD":   PN = "5"  !CDS_PN = "5";
"VDD":   PN = "10"  !CDS_PN = "10";
"VIN<0>":   PN = "7"  !CDS_PN = "7";
"VIN<1>":   PN = "8"  !CDS_PN = "8";
"VIN<2>":   PN = "9"  !CDS_PN = "9";
"VOUT<0>":   PN = "1"  !CDS_PN = "1";
"VOUT<1>":   PN = "2"  !CDS_PN = "2";
"VOUT<2>":   PN = "3"  !CDS_PN = "3";
BODY = "CAP_A","I71": #LOCATION = "C9F5" !CDS_LOCATION = "C9F5" #SEC = "1" !CDS_SEC = "1";
"A":   PN = "1"  !CDS_PN = "1";
"B":   PN = "2"  !CDS_PN = "2";
BODY = "RES","I72": #LOCATION = "R1T9" !CDS_LOCATION = "R1T9" #SEC = "1" !CDS_SEC = "1";
"A":   PN = "1"  !CDS_PN = "1";
"B":   PN = "2"  !CDS_PN = "2";
BODY = "RT9059","I73": #LOCATION = "EU25F2" !CDS_LOCATION = "EU25F2" &SEC = "1" #&CDS_SEC = "1";
"ADJ_NC":   PN = "4"  !CDS_PN = "4";
"EN":   PN = "6"  !CDS_PN = "6";
"GND":   PN = "11"  !CDS_PN = "11";
"PGOOD":   PN = "5"  !CDS_PN = "5";
"VDD":   PN = "10"  !CDS_PN = "10";
"VIN<0>":   PN = "7"  !CDS_PN = "7";
"VIN<1>":   PN = "8"  !CDS_PN = "8";
"VIN<2>":   PN = "9"  !CDS_PN = "9";
"VOUT<0>":   PN = "1"  !CDS_PN = "1";
"VOUT<1>":   PN = "2"  !CDS_PN = "2";
"VOUT<2>":   PN = "3"  !CDS_PN = "3";
BODY = "RES","I77": #LOCATION = "R1W9" !CDS_LOCATION = "R1W9" &SEC = "1" #&CDS_SEC = "1";
"A":   PN = "1"  !CDS_PN = "1";
"B":   PN = "2"  !CDS_PN = "2";
BODY = "RES","I79": #LOCATION = "R9W12" !CDS_LOCATION = "R9W12" &SEC = "1" #&CDS_SEC = "1";
"A":   PN = "1"  !CDS_PN = "1";
"B":   PN = "2"  !CDS_PN = "2";
BODY = "CAP","I81": #LOCATION = "C9W13" !CDS_LOCATION = "C9W13" &SEC = "1" #&CDS_SEC = "1";
"A":   PN = "1"  !CDS_PN = "1";
"B":   PN = "2"  !CDS_PN = "2";
BODY = "CAP","I83": #LOCATION = "C1W15" !CDS_LOCATION = "C1W15" &SEC = "1" #&CDS_SEC = "1";
"A":   PN = "1"  !CDS_PN = "1";
"B":   PN = "2"  !CDS_PN = "2";
BODY = "CAP","I84": #LOCATION = "C9W10" !CDS_LOCATION = "C9W10" &SEC = "1" #&CDS_SEC = "1";
"A":   PN = "1"  !CDS_PN = "1";
"B":   PN = "2"  !CDS_PN = "2";
BODY = "RES","I87": #LOCATION = "R9W32" !CDS_LOCATION = "R9W32" &SEC = "1" #&CDS_SEC = "1";
"A":   PN = "1"  !CDS_PN = "1";
"B":   PN = "2"  !CDS_PN = "2";
BODY = "CAP_A","I90": #LOCATION = "C9W5" !CDS_LOCATION = "C9W5" &SEC = "1" #&CDS_SEC = "1";
"A":   PN = "1"  !CDS_PN = "1";
"B":   PN = "2"  !CDS_PN = "2";
BODY = "CAP","I91": #LOCATION = "C9W6" !CDS_LOCATION = "C9W6" &SEC = "1" #&CDS_SEC = "1";
"A":   PN = "1"  !CDS_PN = "1";
"B":   PN = "2"  !CDS_PN = "2";
BODY = "CAP","I92": #LOCATION = "C1W7" !CDS_LOCATION = "C1W7" &SEC = "1" #&CDS_SEC = "1";
"A":   PN = "1"  !CDS_PN = "1";
"B":   PN = "2"  !CDS_PN = "2";
BODY = "5K1R2F-2-GP","I98": #LOCATION = "R9F31" !CDS_LOCATION = "R9F31" &SEC = "1" #&CDS_SEC = "1";
"1":   PN = "1"  !CDS_PN = "1";
"2":   PN = "2"  !CDS_PN = "2";
BODY = "21K5R2F-GP","I99": #LOCATION = "R9W31" !CDS_LOCATION = "R9W31" &SEC = "1" #&CDS_SEC = "1";
"1":   PN = "1"  !CDS_PN = "1";
"2":   PN = "2"  !CDS_PN = "2";
DRAWING = "@baseboard_fab2_lib.baseboard_fab2(sch_1):page21";
BODY = "RES","I149": #LOCATION = "R6N10" !CDS_LOCATION = "R6N10" #SEC = "1" !CDS_SEC = "1";
"A":   PN = "1"  !CDS_PN = "1";
"B":   PN = "2"  !CDS_PN = "2";
BODY = "RES","I150": #LOCATION = "R6N12" !CDS_LOCATION = "R6N12" #SEC = "1" !CDS_SEC = "1";
"A":   PN = "1"  !CDS_PN = "1";
"B":   PN = "2"  !CDS_PN = "2";
BODY = "RES","I151": #LOCATION = "R6N11" !CDS_LOCATION = "R6N11" #SEC = "1" !CDS_SEC = "1";
"A":   PN = "1"  !CDS_PN = "1";
"B":   PN = "2"  !CDS_PN = "2";
BODY = "RES","I152": #LOCATION = "R6B3" !CDS_LOCATION = "R6B3" #SEC = "1" !CDS_SEC = "1";
"A":   PN = "1"  !CDS_PN = "1";
"B":   PN = "2"  !CDS_PN = "2";
BODY = "RES","I153": #LOCATION = "R6B5" !CDS_LOCATION = "R6B5" #SEC = "1" !CDS_SEC = "1";
"A":   PN = "1"  !CDS_PN = "1";
"B":   PN = "2"  !CDS_PN = "2";
BODY = "RES","I154": #LOCATION = "R6B4" !CDS_LOCATION = "R6B4" #SEC = "1" !CDS_SEC = "1";
"A":   PN = "1"  !CDS_PN = "1";
"B":   PN = "2"  !CDS_PN = "2";
BODY = "RES","I159": #LOCATION = "R6B2" !CDS_LOCATION = "R6B2" #SEC = "1" !CDS_SEC = "1";
"A":   PN = "1"  !CDS_PN = "1";
"B":   PN = "2"  !CDS_PN = "2";
BODY = "RES","I161": #LOCATION = "R6B1" !CDS_LOCATION = "R6B1" #SEC = "1" !CDS_SEC = "1";
"A":   PN = "1"  !CDS_PN = "1";
"B":   PN = "2"  !CDS_PN = "2";
BODY = "RES","I163": #LOCATION = "R6N2" !CDS_LOCATION = "R6N2" #SEC = "1" !CDS_SEC = "1";
"A":   PN = "1"  !CDS_PN = "1";
"B":   PN = "2"  !CDS_PN = "2";
BODY = "RES","I164": #LOCATION = "R6N1" !CDS_LOCATION = "R6N1" #SEC = "1" !CDS_SEC = "1";
"A":   PN = "1"  !CDS_PN = "1";
"B":   PN = "2"  !CDS_PN = "2";
BODY = "RES","I177": #LOCATION = "R5D1" !CDS_LOCATION = "R5D1" #SEC = "1" !CDS_SEC = "1";
"A":   PN = "1"  !CDS_PN = "1";
"B":   PN = "2"  !CDS_PN = "2";
BODY = "RES","I178": #LOCATION = "R5D2" !CDS_LOCATION = "R5D2" #SEC = "1" !CDS_SEC = "1";
"A":   PN = "1"  !CDS_PN = "1";
"B":   PN = "2"  !CDS_PN = "2";
BODY = "RES","I179": #LOCATION = "R6D1" !CDS_LOCATION = "R6D1" #SEC = "1" !CDS_SEC = "1";
"A":   PN = "1"  !CDS_PN = "1";
"B":   PN = "2"  !CDS_PN = "2";
BODY = "RES","I180": #LOCATION = "R4P8" !CDS_LOCATION = "R4P8" #SEC = "1" !CDS_SEC = "1";
"A":   PN = "1"  !CDS_PN = "1";
"B":   PN = "2"  !CDS_PN = "2";
BODY = "RES","I181": #LOCATION = "R4P10" !CDS_LOCATION = "R4P10" #SEC = "1" !CDS_SEC = "1";
"A":   PN = "1"  !CDS_PN = "1";
"B":   PN = "2"  !CDS_PN = "2";
BODY = "RES","I182": #LOCATION = "R4P11" !CDS_LOCATION = "R4P11" #SEC = "1" !CDS_SEC = "1";
"A":   PN = "1"  !CDS_PN = "1";
"B":   PN = "2"  !CDS_PN = "2";
BODY = "RES","I184": #LOCATION = "R6D11" !CDS_LOCATION = "R6D11" #SEC = "1" !CDS_SEC = "1";
"A":   PN = "1"  !CDS_PN = "1";
"B":   PN = "2"  !CDS_PN = "2";
BODY = "RES","I186": #LOCATION = "R4P3" !CDS_LOCATION = "R4P3" #SEC = "1" !CDS_SEC = "1";
"A":   PN = "1"  !CDS_PN = "1";
"B":   PN = "2"  !CDS_PN = "2";
BODY = "RES","I188": #LOCATION = "R4P2" !CDS_LOCATION = "R4P2" #SEC = "1" !CDS_SEC = "1";
"A":   PN = "1"  !CDS_PN = "1";
"B":   PN = "2"  !CDS_PN = "2";
BODY = "RES","I189": #LOCATION = "R4P4" !CDS_LOCATION = "R4P4" #SEC = "1" !CDS_SEC = "1";
"A":   PN = "1"  !CDS_PN = "1";
"B":   PN = "2"  !CDS_PN = "2";
BODY = "RES","I204": #LOCATION = "R6D2" !CDS_LOCATION = "R6D2" #SEC = "1" !CDS_SEC = "1";
"A":   PN = "1"  !CDS_PN = "1";
"B":   PN = "2"  !CDS_PN = "2";
BODY = "SOCKET_P_MECH_A","I216": #LOCATION = "XRU1" !CDS_LOCATION = "XRU1";
BODY = "SOCKET_P_MECH_A","I217": #LOCATION = "XLU1" !CDS_LOCATION = "XLU1";
BODY = "RES","I219": #LOCATION = "R4P19" !CDS_LOCATION = "R4P19" #SEC = "1" !CDS_SEC = "1";
"A":   PN = "1"  !CDS_PN = "1";
"B":   PN = "2"  !CDS_PN = "2";
BODY = "RES","I227": #LOCATION = "R5N2" !CDS_LOCATION = "R5N2" #SEC = "1" !CDS_SEC = "1";
"A":   PN = "1"  !CDS_PN = "1";
"B":   PN = "2"  !CDS_PN = "2";
BODY = "RES","I238": #LOCATION = "R5N1" !CDS_LOCATION = "R5N1" #SEC = "1" !CDS_SEC = "1";
"A":   PN = "1"  !CDS_PN = "1";
"B":   PN = "2"  !CDS_PN = "2";
BODY = "RES","I239": #LOCATION = "R5N5" !CDS_LOCATION = "R5N5" #SEC = "1" !CDS_SEC = "1";
"A":   PN = "1"  !CDS_PN = "1";
"B":   PN = "2"  !CDS_PN = "2";
BODY = "RES","I240": #LOCATION = "R5N3" !CDS_LOCATION = "R5N3" #SEC = "1" !CDS_SEC = "1";
"A":   PN = "1"  !CDS_PN = "1";
"B":   PN = "2"  !CDS_PN = "2";
BODY = "RES","I241": #LOCATION = "R5N4" !CDS_LOCATION = "R5N4" #SEC = "1" !CDS_SEC = "1";
"A":   PN = "1"  !CDS_PN = "1";
"B":   PN = "2"  !CDS_PN = "2";
BODY = "RES","I244": #LOCATION = "R4P18" !CDS_LOCATION = "R4P18" #SEC = "1" !CDS_SEC = "1";
"A":   PN = "1"  !CDS_PN = "1";
"B":   PN = "2"  !CDS_PN = "2";
BODY = "RES","I258": #LOCATION = "R4R5" !CDS_LOCATION = "R4R5" #SEC = "1" !CDS_SEC = "1";
"A":   PN = "1"  !CDS_PN = "1";
"B":   PN = "2"  !CDS_PN = "2";
BODY = "SKX_EXT_B","I259": #LOCATION = "U5D1" !CDS_LOCATION = "U5D1" #SEC = "1" !CDS_SEC = "1";
"BCLK0_DN":   PN = "AU24"  !CDS_PN = "AU24";
"BCLK0_DP":   PN = "AW24"  !CDS_PN = "AW24";
"BCLK1_DN":   PN = "CR26"  !CDS_PN = "CR26";
"BCLK1_DP":   PN = "CP27"  !CDS_PN = "CP27";
"BCLK2_DN":   PN = "CT25"  !CDS_PN = "CT25";
"BCLK2_DP":   PN = "CU26"  !CDS_PN = "CU26";
"BIST_ENABLE":   PN = "BA20"  !CDS_PN = "BA20";
"BMCINIT":   PN = "BD23"  !CDS_PN = "BD23";
"BPM<0>_N":   PN = "AJ10"  !CDS_PN = "AJ10";
"BPM<1>_N":   PN = "AH11"  !CDS_PN = "AH11";
"BPM<2>_N":   PN = "AG10"  !CDS_PN = "AG10";
"BPM<3>_N":   PN = "AF11"  !CDS_PN = "AF11";
"BPM<4>_N":   PN = "AA12"  !CDS_PN = "AA12";
"BPM<5>_N":   PN = "Y11"  !CDS_PN = "Y11";
"BPM<6>_N":   PN = "AE12"  !CDS_PN = "AE12";
"BPM<7>_N":   PN = "AC12"  !CDS_PN = "AC12";
"CATERR_N":   PN = "AL14"  !CDS_PN = "AL14";
"DDR0_CAVREF":   PN = "AJ64"  !CDS_PN = "AJ64";
"DDR1_CAVREF":   PN = "AK63"  !CDS_PN = "AK63";
"DDR2_CAVREF":   PN = "AH63"  !CDS_PN = "AH63";
"DDR3_CAVREF":   PN = "CP61"  !CDS_PN = "CP61";
"DDR4_CAVREF":   PN = "CT61"  !CDS_PN = "CT61";
"DDR5_CAVREF":   PN = "CV61"  !CDS_PN = "CV61";
"DDR012_DRAM_PWR_OK":   PN = "AN30"  !CDS_PN = "AN30";
"DDR012_RCOMP<0>":   PN = "Y43"  !CDS_PN = "Y43";
"DDR012_RCOMP<1>":   PN = "AB43"  !CDS_PN = "AB43";
"DDR012_RCOMP<2>":   PN = "AC42"  !CDS_PN = "AC42";
"DDR012_RESET_N":   PN = "U64"  !CDS_PN = "U64";
"DDR012_SPDSCL":   PN = "AJ18"  !CDS_PN = "AJ18";
"DDR012_SPDSDA":   PN = "AF17"  !CDS_PN = "AF17";
"DDR345_DRAM_PWR_OK":   PN = "CR28"  !CDS_PN = "CR28";
"DDR345_RCOMP<0>":   PN = "DC48"  !CDS_PN = "DC48";
"DDR345_RCOMP<1>":   PN = "DD47"  !CDS_PN = "DD47";
"DDR345_RCOMP<2>":   PN = "DD49"  !CDS_PN = "DD49";
"DDR345_RESET_N":   PN = "DV63"  !CDS_PN = "DV63";
"DDR345_SPDSCL":   PN = "AE18"  !CDS_PN = "AE18";
"DDR345_SPDSDA":   PN = "AD17"  !CDS_PN = "AD17";
"EAR_N":   PN = "AJ14"  !CDS_PN = "AJ14";
"ERROR<0>_N":   PN = "AJ12"  !CDS_PN = "AJ12";
"ERROR<1>_N":   PN = "AK11"  !CDS_PN = "AK11";
"ERROR<2>_N":   PN = "AL12"  !CDS_PN = "AL12";
"FRMAGENT":   PN = "AV17"  !CDS_PN = "AV17";
"LEGACY_SKT":   PN = "AE20"  !CDS_PN = "AE20";
"MCP01_RBIAS<0>":   PN = "CU32"  !CDS_PN = "CU32";
"MCP01_RBIAS<1>":   PN = "CT31"  !CDS_PN = "CT31";
"MEM_HOT_C012_N":   PN = "AH13"  !CDS_PN = "AH13";
"MEM_HOT_C345_N":   PN = "AF13"  !CDS_PN = "AF13";
"MSMI_N":   PN = "AN20"  !CDS_PN = "AN20";
"NMI":   PN = "AP11"  !CDS_PN = "AP11";
"PE3_RBIAS<0>":   PN = "CP29"  !CDS_PN = "CP29";
"PE3_RBIAS<1>":   PN = "CR30"  !CDS_PN = "CR30";
"PE012_RBIAS<0>":   PN = "CN30"  !CDS_PN = "CN30";
"PE012_RBIAS<1>":   PN = "CL30"  !CDS_PN = "CL30";
"PE_HP_SCL":   PN = "AM19"  !CDS_PN = "AM19";
"PE_HP_SDA":   PN = "AL18"  !CDS_PN = "AL18";
"PECI":   PN = "AU12"  !CDS_PN = "AU12";
"PIROM_ADDR<0>":   PN = "CU58"  !CDS_PN = "CU58";
"PIROM_ADDR<1>":   PN = "CV57"  !CDS_PN = "CV57";
"PIROM_ADDR<2>":   PN = "CW56"  !CDS_PN = "CW56";
"PKGID<0>":   PN = "DC72"  !CDS_PN = "DC72";
"PKGID<1>":   PN = "CW72"  !CDS_PN = "CW72";
"PKGID<2>":   PN = "DA72"  !CDS_PN = "DA72";
"PM_FAST_WAKE_N":   PN = "AF15"  !CDS_PN = "AF15";
"PMSYNC":   PN = "AR14"  !CDS_PN = "AR14";
"PMSYNC_CLK":   PN = "AT19"  !CDS_PN = "AT19";
"PRDY_N":   PN = "AG16"  !CDS_PN = "AG16";
"PREQ_N":   PN = "AR12"  !CDS_PN = "AR12";
"PROC_ID<0>":   PN = "CY71"  !CDS_PN = "CY71";
"PROC_ID<1>":   PN = "DB71"  !CDS_PN = "DB71";
"PROCDIS_N":   PN = "AB17"  !CDS_PN = "AB17";
"PROCHOT_N":   PN = "AC16"  !CDS_PN = "AC16";
"PWRGOOD":   PN = "BC24"  !CDS_PN = "BC24";
"RESET_N":   PN = "AP21"  !CDS_PN = "AP21";
"SAFE_MODE_BOOT":   PN = "AR18"  !CDS_PN = "AR18";
"SKTOCC_N":   PN = "AB13"  !CDS_PN = "AB13";
"SM_WP":   PN = "CV59"  !CDS_PN = "CV59";
"SMBCLK":   PN = "CT59"  !CDS_PN = "CT59";
"SMBDAT":   PN = "CW58"  !CDS_PN = "CW58";
"SOCKET_ID<0>":   PN = "AU22"  !CDS_PN = "AU22";
"SOCKET_ID<1>":   PN = "AU16"  !CDS_PN = "AU16";
"SOCKET_ID<2>":   PN = "AU20"  !CDS_PN = "AU20";
"SVIDALERT<0>_N":   PN = "DE44"  !CDS_PN = "DE44";
"SVIDALERT<1>_N":   PN = "DL44"  !CDS_PN = "DL44";
"SVIDCLK<0>":   PN = "DC44"  !CDS_PN = "DC44";
"SVIDCLK<1>":   PN = "DG44"  !CDS_PN = "DG44";
"SVIDDATA<0>":   PN = "DB45"  !CDS_PN = "DB45";
"SVIDDATA<1>":   PN = "DJ44"  !CDS_PN = "DJ44";
"TCK":   PN = "AA14"  !CDS_PN = "AA14";
"TDI":   PN = "AC14"  !CDS_PN = "AC14";
"TDO":   PN = "AE14"  !CDS_PN = "AE14";
"TEST_12":   PN = "AY19"  !CDS_PN = "AY19";
"TEST_13":   PN = "DB51"  !CDS_PN = "DB51";
"TEST_14":   PN = "DC50"  !CDS_PN = "DC50";
"TEST_15":   PN = "AW14"  !CDS_PN = "AW14";
"THERMTRIP_N":   PN = "AB15"  !CDS_PN = "AB15";
"TMS":   PN = "W14"  !CDS_PN = "W14";
"TRST_N":   PN = "Y13"  !CDS_PN = "Y13";
"TSC_SYNC":   PN = "AM11"  !CDS_PN = "AM11";
"TXT_AGENT":   PN = "AW18"  !CDS_PN = "AW18";
"TXT_PLTEN":   PN = "AV15"  !CDS_PN = "AV15";
"UPI01_RBIAS<0>":   PN = "AT29"  !CDS_PN = "AT29";
"UPI01_RBIAS<1>":   PN = "AP29"  !CDS_PN = "AP29";
"UPI2_RBIAS<0>":   PN = "CL28"  !CDS_PN = "CL28";
"UPI2_RBIAS<1>":   PN = "CK29"  !CDS_PN = "CK29";
DRAWING = "@baseboard_fab2_lib.baseboard_fab2(sch_1):page22";
BODY = "RES","I188": #LOCATION = "R5R1" !CDS_LOCATION = "R5R1" #SEC = "1" !CDS_SEC = "1";
"A":   PN = "1"  !CDS_PN = "1";
"B":   PN = "2"  !CDS_PN = "2";
BODY = "RES","I190": #LOCATION = "R5P4" !CDS_LOCATION = "R5P4" #SEC = "1" !CDS_SEC = "1";
"A":   PN = "1"  !CDS_PN = "1";
"B":   PN = "2"  !CDS_PN = "2";
BODY = "SKX_EXT_B","I204": #LOCATION = "U5D1" !CDS_LOCATION = "U5D1" #SEC = "2" !CDS_SEC = "2";
"DEBUG_EN_N":   PN = "AV21"  !CDS_PN = "AV21";
"DMIMODE_OVERRIDE":   PN = "AW12"  !CDS_PN = "AW12";
"FIVR_FAULT":   PN = "AU14"  !CDS_PN = "AU14";
"PWR_DEBUG_N":   PN = "AP17"  !CDS_PN = "AP17";
"RSVD<194>":   PN = "AP61"  !CDS_PN = "AP61";
"RSVD<195>":   PN = "AP27"  !CDS_PN = "AP27";
"RSVD<196>":   PN = "AP25"  !CDS_PN = "AP25";
"RSVD<197>":   PN = "AP23"  !CDS_PN = "AP23";
"RSVD<198>":   PN = "AN62"  !CDS_PN = "AN62";
"RSVD<199>":   PN = "AN60"  !CDS_PN = "AN60";
"RSVD<200>":   PN = "AN26"  !CDS_PN = "AN26";
"RSVD<201>":   PN = "AN24"  !CDS_PN = "AN24";
"RSVD<202>":   PN = "AN22"  !CDS_PN = "AN22";
"RSVD<203>":   PN = "AN18"  !CDS_PN = "AN18";
"RSVD<204>":   PN = "AM61"  !CDS_PN = "AM61";
"RSVD<205>":   PN = "AM59"  !CDS_PN = "AM59";
"RSVD<206>":   PN = "AM27"  !CDS_PN = "AM27";
"RSVD<207>":   PN = "AM25"  !CDS_PN = "AM25";
"RSVD<208>":   PN = "AM23"  !CDS_PN = "AM23";
"RSVD<209>":   PN = "AM21"  !CDS_PN = "AM21";
"RSVD<210>":   PN = "AL62"  !CDS_PN = "AL62";
"RSVD<211>":   PN = "AL60"  !CDS_PN = "AL60";
"RSVD<212>":   PN = "AL58"  !CDS_PN = "AL58";
"RSVD<213>":   PN = "AL26"  !CDS_PN = "AL26";
"RSVD<214>":   PN = "AL22"  !CDS_PN = "AL22";
"RSVD<215>":   PN = "AL20"  !CDS_PN = "AL20";
"RSVD<216>":   PN = "AK69"  !CDS_PN = "AK69";
"RSVD<217>":   PN = "AK61"  !CDS_PN = "AK61";
"RSVD<218>":   PN = "AK59"  !CDS_PN = "AK59";
"RSVD<219>":   PN = "AK57"  !CDS_PN = "AK57";
"RSVD<220>":   PN = "AK27"  !CDS_PN = "AK27";
"RSVD<221>":   PN = "AK21"  !CDS_PN = "AK21";
"RSVD<222>":   PN = "AJ70"  !CDS_PN = "AJ70";
"RSVD<223>":   PN = "AJ62"  !CDS_PN = "AJ62";
"RSVD<224>":   PN = "AJ60"  !CDS_PN = "AJ60";
"RSVD<225>":   PN = "AJ58"  !CDS_PN = "AJ58";
"RSVD<226>":   PN = "AJ56"  !CDS_PN = "AJ56";
"RSVD<227>":   PN = "AJ20"  !CDS_PN = "AJ20";
"RSVD<228>":   PN = "AH73"  !CDS_PN = "AH73";
"RSVD<229>":   PN = "AH71"  !CDS_PN = "AH71";
"RSVD<230>":   PN = "AH57"  !CDS_PN = "AH57";
"RSVD<231>":   PN = "AH55"  !CDS_PN = "AH55";
"RSVD<232>":   PN = "AH19"  !CDS_PN = "AH19";
"RSVD<233>":   PN = "AH15"  !CDS_PN = "AH15";
"RSVD<234>":   PN = "AG72"  !CDS_PN = "AG72";
"RSVD<235>":   PN = "AG56"  !CDS_PN = "AG56";
"RSVD<236>":   PN = "AG54"  !CDS_PN = "AG54";
"RSVD<237>":   PN = "AG52"  !CDS_PN = "AG52";
"RSVD<238>":   PN = "AG50"  !CDS_PN = "AG50";
"RSVD<239>":   PN = "AG48"  !CDS_PN = "AG48";
"RSVD<240>":   PN = "AG20"  !CDS_PN = "AG20";
"RSVD<241>":   PN = "AF71"  !CDS_PN = "AF71";
"RSVD<242>":   PN = "AF53"  !CDS_PN = "AF53";
"RSVD<243>":   PN = "AF51"  !CDS_PN = "AF51";
"RSVD<244>":   PN = "AF49"  !CDS_PN = "AF49";
"RSVD<245>":   PN = "AF47"  !CDS_PN = "AF47";
"RSVD<246>":   PN = "AF19"  !CDS_PN = "AF19";
"RSVD<247>":   PN = "AE72"  !CDS_PN = "AE72";
"RSVD<248>":   PN = "AE52"  !CDS_PN = "AE52";
"RSVD<249>":   PN = "AE50"  !CDS_PN = "AE50";
"RSVD<250>":   PN = "AE48"  !CDS_PN = "AE48";
"RSVD<251>":   PN = "AE46"  !CDS_PN = "AE46";
"RSVD<252>":   PN = "AD51"  !CDS_PN = "AD51";
"RSVD<253>":   PN = "AD49"  !CDS_PN = "AD49";
"RSVD<254>":   PN = "AD47"  !CDS_PN = "AD47";
"RSVD<256>":   PN = "Y65"  !CDS_PN = "Y65";
"RSVD<257>":   PN = "Y23"  !CDS_PN = "Y23";
"RSVD<258>":   PN = "W66"  !CDS_PN = "W66";
"RSVD<259>":   PN = "V67"  !CDS_PN = "V67";
"RSVD<260>":   PN = "V65"  !CDS_PN = "V65";
"RSVD<261>":   PN = "U66"  !CDS_PN = "U66";
"RSVD<262>":   PN = "T67"  !CDS_PN = "T67";
"RSVD<263>":   PN = "R66"  !CDS_PN = "R66";
"RSVD<264>":   PN = "R62"  !CDS_PN = "R62";
"RSVD<265>":   PN = "P65"  !CDS_PN = "P65";
"RSVD<266>":   PN = "M63"  !CDS_PN = "M63";
"RSVD<267>":   PN = "K61"  !CDS_PN = "K61";
"RSVD<268>":   PN = "J62"  !CDS_PN = "J62";
"RSVD<269>":   PN = "J46"  !CDS_PN = "J46";
"RSVD<270>":   PN = "H85"  !CDS_PN = "H85";
"RSVD<271>":   PN = "H83"  !CDS_PN = "H83";
"RSVD<272>":   PN = "H1"  !CDS_PN = "H1";
"RSVD<273>":   PN = "G84"  !CDS_PN = "G84";
"RSVD<274>":   PN = "G64"  !CDS_PN = "G64";
"RSVD<275>":   PN = "G2"  !CDS_PN = "G2";
"RSVD<276>":   PN = "F83"  !CDS_PN = "F83";
"RSVD<277>":   PN = "F65"  !CDS_PN = "F65";
"RSVD<278>":   PN = "F23"  !CDS_PN = "F23";
"RSVD<279>":   PN = "F3"  !CDS_PN = "F3";
"RSVD<280>":   PN = "E84"  !CDS_PN = "E84";
"RSVD<281>":   PN = "E24"  !CDS_PN = "E24";
"RSVD<282>":   PN = "E4"  !CDS_PN = "E4";
"RSVD<283>":   PN = "E2"  !CDS_PN = "E2";
"RSVD<284>":   PN = "D83"  !CDS_PN = "D83";
"RSVD<285>":   PN = "D65"  !CDS_PN = "D65";
"RSVD<286>":   PN = "D17"  !CDS_PN = "D17";
"RSVD<287>":   PN = "D5"  !CDS_PN = "D5";
"RSVD<288>":   PN = "C82"  !CDS_PN = "C82";
"RSVD<289>":   PN = "C24"  !CDS_PN = "C24";
"RSVD<290>":   PN = "C18"  !CDS_PN = "C18";
"RSVD<291>":   PN = "C6"  !CDS_PN = "C6";
"RSVD<292>":   PN = "B81"  !CDS_PN = "B81";
"RSVD<293>":   PN = "B77"  !CDS_PN = "B77";
"RSVD<294>":   PN = "B17"  !CDS_PN = "B17";
"RSVD<295>":   PN = "B15"  !CDS_PN = "B15";
"RSVD<296>":   PN = "B13"  !CDS_PN = "B13";
"RSVD<298>":   PN = "B7"  !CDS_PN = "B7";
"RSVD<299>":   PN = "B3"  !CDS_PN = "B3";
"RSVD<300>":   PN = "A24"  !CDS_PN = "A24";
"RSVD<301>":   PN = "A16"  !CDS_PN = "A16";
"RSVD<302>":   PN = "A14"  !CDS_PN = "A14";
"RSVD<303>":   PN = "A6"  !CDS_PN = "A6";
"RSVD<304>":   PN = "A4"  !CDS_PN = "A4";
"TEST_1":   PN = "AF45"  !CDS_PN = "AF45";
"TEST_2":   PN = "AG46"  !CDS_PN = "AG46";
"TEST_3":   PN = "AM13"  !CDS_PN = "AM13";
"TEST_4":   PN = "AN12"  !CDS_PN = "AN12";
"TEST_5":   PN = "AN14"  !CDS_PN = "AN14";
"TEST_11":   PN = "AY13"  !CDS_PN = "AY13";
DRAWING = "@baseboard_fab2_lib.baseboard_fab2(sch_1):page23";
BODY = "SKX_EXT_B","I172": #LOCATION = "U5D1" !CDS_LOCATION = "U5D1" #SEC = "3" !CDS_SEC = "3";
"DDR0_ACT_N":   PN = "J60"  !CDS_PN = "J60";
"DDR0_ALERT_N":   PN = "B61"  !CDS_PN = "B61";
"DDR0_BA<0>":   PN = "C52"  !CDS_PN = "C52";
"DDR0_BA<1>":   PN = "G54"  !CDS_PN = "G54";
"DDR0_BG<0>":   PN = "D61"  !CDS_PN = "D61";
"DDR0_BG<1>":   PN = "F63"  !CDS_PN = "F63";
"DDR0_CID<2>":   PN = "G46"  !CDS_PN = "G46";
"DDR0_CKE<0>":   PN = "C62"  !CDS_PN = "C62";
"DDR0_CKE<1>":   PN = "C64"  !CDS_PN = "C64";
"DDR0_CKE<2>":   PN = "B63"  !CDS_PN = "B63";
"DDR0_CKE<3>":   PN = "D63"  !CDS_PN = "D63";
"DDR0_CLK_DN<0>":   PN = "F55"  !CDS_PN = "F55";
"DDR0_CLK_DN<1>":   PN = "C54"  !CDS_PN = "C54";
"DDR0_CLK_DN<2>":   PN = "J56"  !CDS_PN = "J56";
"DDR0_CLK_DN<3>":   PN = "C56"  !CDS_PN = "C56";
"DDR0_CLK_DP<0>":   PN = "D55"  !CDS_PN = "D55";
"DDR0_CLK_DP<1>":   PN = "B55"  !CDS_PN = "B55";
"DDR0_CLK_DP<2>":   PN = "G56"  !CDS_PN = "G56";
"DDR0_CLK_DP<3>":   PN = "B57"  !CDS_PN = "B57";
"DDR0_CS<0>_N":   PN = "G52"  !CDS_PN = "G52";
"DDR0_CS<1>_N":   PN = "F49"  !CDS_PN = "F49";
"DDR0_CS<2>_N":   PN = "D47"  !CDS_PN = "D47";
"DDR0_CS<3>_N":   PN = "F47"  !CDS_PN = "F47";
"DDR0_CS<4>_N":   PN = "B51"  !CDS_PN = "B51";
"DDR0_CS<5>_N":   PN = "D49"  !CDS_PN = "D49";
"DDR0_CS<6>_N":   PN = "F45"  !CDS_PN = "F45";
"DDR0_CS<7>_N":   PN = "K45"  !CDS_PN = "K45";
"DDR0_DQ<0>":   PN = "AN86"  !CDS_PN = "AN86";
"DDR0_DQ<1>":   PN = "AN84"  !CDS_PN = "AN84";
"DDR0_DQ<2>":   PN = "AE86"  !CDS_PN = "AE86";
"DDR0_DQ<3>":   PN = "AE84"  !CDS_PN = "AE84";
"DDR0_DQ<4>":   PN = "AR86"  !CDS_PN = "AR86";
"DDR0_DQ<5>":   PN = "AR84"  !CDS_PN = "AR84";
"DDR0_DQ<6>":   PN = "AG86"  !CDS_PN = "AG86";
"DDR0_DQ<7>":   PN = "AG84"  !CDS_PN = "AG84";
"DDR0_DQ<8>":   PN = "W86"  !CDS_PN = "W86";
"DDR0_DQ<9>":   PN = "W84"  !CDS_PN = "W84";
"DDR0_DQ<10>":   PN = "L86"  !CDS_PN = "L86";
"DDR0_DQ<11>":   PN = "L84"  !CDS_PN = "L84";
"DDR0_DQ<12>":   PN = "AA86"  !CDS_PN = "AA86";
"DDR0_DQ<13>":   PN = "AA84"  !CDS_PN = "AA84";
"DDR0_DQ<14>":   PN = "N86"  !CDS_PN = "N86";
"DDR0_DQ<15>":   PN = "N84"  !CDS_PN = "N84";
"DDR0_DQ<16>":   PN = "V81"  !CDS_PN = "V81";
"DDR0_DQ<17>":   PN = "T79"  !CDS_PN = "T79";
"DDR0_DQ<18>":   PN = "N82"  !CDS_PN = "N82";
"DDR0_DQ<19>":   PN = "M81"  !CDS_PN = "M81";
"DDR0_DQ<20>":   PN = "W80"  !CDS_PN = "W80";
"DDR0_DQ<21>":   PN = "V79"  !CDS_PN = "V79";
"DDR0_DQ<22>":   PN = "R82"  !CDS_PN = "R82";
"DDR0_DQ<23>":   PN = "N80"  !CDS_PN = "N80";
"DDR0_DQ<24>":   PN = "L76"  !CDS_PN = "L76";
"DDR0_DQ<25>":   PN = "R76"  !CDS_PN = "R76";
"DDR0_DQ<26>":   PN = "M73"  !CDS_PN = "M73";
"DDR0_DQ<27>":   PN = "P73"  !CDS_PN = "P73";
"DDR0_DQ<28>":   PN = "M77"  !CDS_PN = "M77";
"DDR0_DQ<29>":   PN = "P77"  !CDS_PN = "P77";
"DDR0_DQ<30>":   PN = "L74"  !CDS_PN = "L74";
"DDR0_DQ<31>":   PN = "R74"  !CDS_PN = "R74";
"DDR0_DQ<32>":   PN = "C42"  !CDS_PN = "C42";
"DDR0_DQ<33>":   PN = "B41"  !CDS_PN = "B41";
"DDR0_DQ<34>":   PN = "C38"  !CDS_PN = "C38";
"DDR0_DQ<35>":   PN = "E38"  !CDS_PN = "E38";
"DDR0_DQ<36>":   PN = "E42"  !CDS_PN = "E42";
"DDR0_DQ<37>":   PN = "F41"  !CDS_PN = "F41";
"DDR0_DQ<38>":   PN = "B39"  !CDS_PN = "B39";
"DDR0_DQ<39>":   PN = "F39"  !CDS_PN = "F39";
"DDR0_DQ<40>":   PN = "K37"  !CDS_PN = "K37";
"DDR0_DQ<41>":   PN = "P37"  !CDS_PN = "P37";
"DDR0_DQ<42>":   PN = "L34"  !CDS_PN = "L34";
"DDR0_DQ<43>":   PN = "N34"  !CDS_PN = "N34";
"DDR0_DQ<44>":   PN = "L38"  !CDS_PN = "L38";
"DDR0_DQ<45>":   PN = "N38"  !CDS_PN = "N38";
"DDR0_DQ<46>":   PN = "K35"  !CDS_PN = "K35";
"DDR0_DQ<47>":   PN = "P35"  !CDS_PN = "P35";
"DDR0_DQ<48>":   PN = "K31"  !CDS_PN = "K31";
"DDR0_DQ<49>":   PN = "P31"  !CDS_PN = "P31";
"DDR0_DQ<50>":   PN = "L28"  !CDS_PN = "L28";
"DDR0_DQ<51>":   PN = "N28"  !CDS_PN = "N28";
"DDR0_DQ<52>":   PN = "L32"  !CDS_PN = "L32";
"DDR0_DQ<53>":   PN = "N32"  !CDS_PN = "N32";
"DDR0_DQ<54>":   PN = "K29"  !CDS_PN = "K29";
"DDR0_DQ<55>":   PN = "P29"  !CDS_PN = "P29";
"DDR0_DQ<56>":   PN = "K25"  !CDS_PN = "K25";
"DDR0_DQ<57>":   PN = "P25"  !CDS_PN = "P25";
"DDR0_DQ<58>":   PN = "P23"  !CDS_PN = "P23";
"DDR0_DQ<59>":   PN = "T23"  !CDS_PN = "T23";
"DDR0_DQ<60>":   PN = "L26"  !CDS_PN = "L26";
"DDR0_DQ<61>":   PN = "N26"  !CDS_PN = "N26";
"DDR0_DQ<62>":   PN = "H23"  !CDS_PN = "H23";
"DDR0_DQ<63>":   PN = "K23"  !CDS_PN = "K23";
"DDR0_DQS_DN<0>":   PN = "AJ84"  !CDS_PN = "AJ84";
"DDR0_DQS_DN<1>":   PN = "R84"  !CDS_PN = "R84";
"DDR0_DQS_DN<2>":   PN = "P79"  !CDS_PN = "P79";
"DDR0_DQS_DN<3>":   PN = "T75"  !CDS_PN = "T75";
"DDR0_DQS_DN<4>":   PN = "G40"  !CDS_PN = "G40";
"DDR0_DQS_DN<5>":   PN = "R36"  !CDS_PN = "R36";
"DDR0_DQS_DN<6>":   PN = "R30"  !CDS_PN = "R30";
"DDR0_DQS_DN<7>":   PN = "N24"  !CDS_PN = "N24";
"DDR0_DQS_DN<8>":   PN = "AH67"  !CDS_PN = "AH67";
"DDR0_DQS_DN<9>":   PN = "AL84"  !CDS_PN = "AL84";
"DDR0_DQS_DN<10>":   PN = "U84"  !CDS_PN = "U84";
"DDR0_DQS_DN<11>":   PN = "U82"  !CDS_PN = "U82";
"DDR0_DQS_DN<12>":   PN = "K75"  !CDS_PN = "K75";
"DDR0_DQS_DN<13>":   PN = "A40"  !CDS_PN = "A40";
"DDR0_DQS_DN<14>":   PN = "J36"  !CDS_PN = "J36";
"DDR0_DQS_DN<15>":   PN = "J30"  !CDS_PN = "J30";
"DDR0_DQS_DN<16>":   PN = "J24"  !CDS_PN = "J24";
"DDR0_DQS_DN<17>":   PN = "AB67"  !CDS_PN = "AB67";
"DDR0_DQS_DP<0>":   PN = "AH85"  !CDS_PN = "AH85";
"DDR0_DQS_DP<1>":   PN = "P85"  !CDS_PN = "P85";
"DDR0_DQS_DP<2>":   PN = "R80"  !CDS_PN = "R80";
"DDR0_DQS_DP<3>":   PN = "P75"  !CDS_PN = "P75";
"DDR0_DQS_DP<4>":   PN = "E40"  !CDS_PN = "E40";
"DDR0_DQS_DP<5>":   PN = "N36"  !CDS_PN = "N36";
"DDR0_DQS_DP<6>":   PN = "N30"  !CDS_PN = "N30";
"DDR0_DQS_DP<7>":   PN = "R24"  !CDS_PN = "R24";
"DDR0_DQS_DP<8>":   PN = "AF67"  !CDS_PN = "AF67";
"DDR0_DQS_DP<9>":   PN = "AM85"  !CDS_PN = "AM85";
"DDR0_DQS_DP<10>":   PN = "V85"  !CDS_PN = "V85";
"DDR0_DQS_DP<11>":   PN = "T81"  !CDS_PN = "T81";
"DDR0_DQS_DP<12>":   PN = "M75"  !CDS_PN = "M75";
"DDR0_DQS_DP<13>":   PN = "C40"  !CDS_PN = "C40";
"DDR0_DQS_DP<14>":   PN = "L36"  !CDS_PN = "L36";
"DDR0_DQS_DP<15>":   PN = "L30"  !CDS_PN = "L30";
"DDR0_DQS_DP<16>":   PN = "L24"  !CDS_PN = "L24";
"DDR0_DQS_DP<17>":   PN = "AD67"  !CDS_PN = "AD67";
"DDR0_ECC<0>":   PN = "AC68"  !CDS_PN = "AC68";
"DDR0_ECC<1>":   PN = "AG68"  !CDS_PN = "AG68";
"DDR0_ECC<2>":   PN = "AD65"  !CDS_PN = "AD65";
"DDR0_ECC<3>":   PN = "AF65"  !CDS_PN = "AF65";
"DDR0_ECC<4>":   PN = "AD69"  !CDS_PN = "AD69";
"DDR0_ECC<5>":   PN = "AF69"  !CDS_PN = "AF69";
"DDR0_ECC<6>":   PN = "AC66"  !CDS_PN = "AC66";
"DDR0_ECC<7>":   PN = "AG66"  !CDS_PN = "AG66";
"DDR0_MA<0>":   PN = "F53"  !CDS_PN = "F53";
"DDR0_MA<1>":   PN = "F57"  !CDS_PN = "F57";
"DDR0_MA<2>":   PN = "D57"  !CDS_PN = "D57";
"DDR0_MA<3>":   PN = "C58"  !CDS_PN = "C58";
"DDR0_MA<4>":   PN = "G58"  !CDS_PN = "G58";
"DDR0_MA<5>":   PN = "F59"  !CDS_PN = "F59";
"DDR0_MA<6>":   PN = "D59"  !CDS_PN = "D59";
"DDR0_MA<7>":   PN = "G60"  !CDS_PN = "G60";
"DDR0_MA<8>":   PN = "C60"  !CDS_PN = "C60";
"DDR0_MA<9>":   PN = "F61"  !CDS_PN = "F61";
"DDR0_MA<10>":   PN = "J54"  !CDS_PN = "J54";
"DDR0_MA<11>":   PN = "G62"  !CDS_PN = "G62";
"DDR0_MA<12>":   PN = "J64"  !CDS_PN = "J64";
"DDR0_MA<13>":   PN = "J48"  !CDS_PN = "J48";
"DDR0_MA<14>":   PN = "F51"  !CDS_PN = "F51";
"DDR0_MA<15>":   PN = "K49"  !CDS_PN = "K49";
"DDR0_MA<16>":   PN = "D51"  !CDS_PN = "D51";
"DDR0_MA<17>":   PN = "K47"  !CDS_PN = "K47";
"DDR0_ODT<0>":   PN = "C50"  !CDS_PN = "C50";
"DDR0_ODT<1>":   PN = "C48"  !CDS_PN = "C48";
"DDR0_ODT<2>":   PN = "G50"  !CDS_PN = "G50";
"DDR0_ODT<3>":   PN = "G48"  !CDS_PN = "G48";
"DDR0_PAR":   PN = "D53"  !CDS_PN = "D53";
DRAWING = "@baseboard_fab2_lib.baseboard_fab2(sch_1):page24";
BODY = "SKX_EXT_B","I172": #LOCATION = "U5D1" !CDS_LOCATION = "U5D1" #SEC = "4" !CDS_SEC = "4";
"DDR1_ACT_N":   PN = "T63"  !CDS_PN = "T63";
"DDR1_ALERT_N":   PN = "W62"  !CDS_PN = "W62";
"DDR1_BA<0>":   PN = "T53"  !CDS_PN = "T53";
"DDR1_BA<1>":   PN = "K55"  !CDS_PN = "K55";
"DDR1_BG<0>":   PN = "M61"  !CDS_PN = "M61";
"DDR1_BG<1>":   PN = "N60"  !CDS_PN = "N60";
"DDR1_CID<2>":   PN = "M47"  !CDS_PN = "M47";
"DDR1_CKE<0>":   PN = "N62"  !CDS_PN = "N62";
"DDR1_CKE<1>":   PN = "R64"  !CDS_PN = "R64";
"DDR1_CKE<2>":   PN = "K63"  !CDS_PN = "K63";
"DDR1_CKE<3>":   PN = "L64"  !CDS_PN = "L64";
"DDR1_CLK_DN<0>":   PN = "M53"  !CDS_PN = "M53";
"DDR1_CLK_DN<1>":   PN = "R54"  !CDS_PN = "R54";
"DDR1_CLK_DN<2>":   PN = "N56"  !CDS_PN = "N56";
"DDR1_CLK_DN<3>":   PN = "R56"  !CDS_PN = "R56";
"DDR1_CLK_DP<0>":   PN = "N54"  !CDS_PN = "N54";
"DDR1_CLK_DP<1>":   PN = "T55"  !CDS_PN = "T55";
"DDR1_CLK_DP<2>":   PN = "M57"  !CDS_PN = "M57";
"DDR1_CLK_DP<3>":   PN = "T57"  !CDS_PN = "T57";
"DDR1_CS<0>_N":   PN = "K51"  !CDS_PN = "K51";
"DDR1_CS<1>_N":   PN = "R50"  !CDS_PN = "R50";
"DDR1_CS<2>_N":   PN = "N46"  !CDS_PN = "N46";
"DDR1_CS<3>_N":   PN = "V47"  !CDS_PN = "V47";
"DDR1_CS<4>_N":   PN = "J50"  !CDS_PN = "J50";
"DDR1_CS<5>_N":   PN = "T49"  !CDS_PN = "T49";
"DDR1_CS<6>_N":   PN = "M45"  !CDS_PN = "M45";
"DDR1_CS<7>_N":   PN = "R46"  !CDS_PN = "R46";
"DDR1_DQ<0>":   PN = "AV81"  !CDS_PN = "AV81";
"DDR1_DQ<1>":   PN = "AT79"  !CDS_PN = "AT79";
"DDR1_DQ<2>":   PN = "AN82"  !CDS_PN = "AN82";
"DDR1_DQ<3>":   PN = "AM81"  !CDS_PN = "AM81";
"DDR1_DQ<4>":   PN = "AW80"  !CDS_PN = "AW80";
"DDR1_DQ<5>":   PN = "AV79"  !CDS_PN = "AV79";
"DDR1_DQ<6>":   PN = "AR82"  !CDS_PN = "AR82";
"DDR1_DQ<7>":   PN = "AN80"  !CDS_PN = "AN80";
"DDR1_DQ<8>":   PN = "AH81"  !CDS_PN = "AH81";
"DDR1_DQ<9>":   PN = "AF79"  !CDS_PN = "AF79";
"DDR1_DQ<10>":   PN = "AC82"  !CDS_PN = "AC82";
"DDR1_DQ<11>":   PN = "AB81"  !CDS_PN = "AB81";
"DDR1_DQ<12>":   PN = "AJ80"  !CDS_PN = "AJ80";
"DDR1_DQ<13>":   PN = "AH79"  !CDS_PN = "AH79";
"DDR1_DQ<14>":   PN = "AE82"  !CDS_PN = "AE82";
"DDR1_DQ<15>":   PN = "AC80"  !CDS_PN = "AC80";
"DDR1_DQ<16>":   PN = "E80"  !CDS_PN = "E80";
"DDR1_DQ<17>":   PN = "J80"  !CDS_PN = "J80";
"DDR1_DQ<18>":   PN = "F77"  !CDS_PN = "F77";
"DDR1_DQ<19>":   PN = "H77"  !CDS_PN = "H77";
"DDR1_DQ<20>":   PN = "F81"  !CDS_PN = "F81";
"DDR1_DQ<21>":   PN = "H81"  !CDS_PN = "H81";
"DDR1_DQ<22>":   PN = "E78"  !CDS_PN = "E78";
"DDR1_DQ<23>":   PN = "J78"  !CDS_PN = "J78";
"DDR1_DQ<24>":   PN = "D75"  !CDS_PN = "D75";
"DDR1_DQ<25>":   PN = "C74"  !CDS_PN = "C74";
"DDR1_DQ<26>":   PN = "D71"  !CDS_PN = "D71";
"DDR1_DQ<27>":   PN = "F71"  !CDS_PN = "F71";
"DDR1_DQ<28>":   PN = "F75"  !CDS_PN = "F75";
"DDR1_DQ<29>":   PN = "G74"  !CDS_PN = "G74";
"DDR1_DQ<30>":   PN = "C72"  !CDS_PN = "C72";
"DDR1_DQ<31>":   PN = "G72"  !CDS_PN = "G72";
"DDR1_DQ<32>":   PN = "K43"  !CDS_PN = "K43";
"DDR1_DQ<33>":   PN = "H43"  !CDS_PN = "H43";
"DDR1_DQ<34>":   PN = "L40"  !CDS_PN = "L40";
"DDR1_DQ<35>":   PN = "N40"  !CDS_PN = "N40";
"DDR1_DQ<36>":   PN = "P43"  !CDS_PN = "P43";
"DDR1_DQ<37>":   PN = "T43"  !CDS_PN = "T43";
"DDR1_DQ<38>":   PN = "K41"  !CDS_PN = "K41";
"DDR1_DQ<39>":   PN = "P41"  !CDS_PN = "P41";
"DDR1_DQ<40>":   PN = "C36"  !CDS_PN = "C36";
"DDR1_DQ<41>":   PN = "B35"  !CDS_PN = "B35";
"DDR1_DQ<42>":   PN = "C32"  !CDS_PN = "C32";
"DDR1_DQ<43>":   PN = "E32"  !CDS_PN = "E32";
"DDR1_DQ<44>":   PN = "E36"  !CDS_PN = "E36";
"DDR1_DQ<45>":   PN = "F35"  !CDS_PN = "F35";
"DDR1_DQ<46>":   PN = "B33"  !CDS_PN = "B33";
"DDR1_DQ<47>":   PN = "F33"  !CDS_PN = "F33";
"DDR1_DQ<48>":   PN = "C30"  !CDS_PN = "C30";
"DDR1_DQ<49>":   PN = "B29"  !CDS_PN = "B29";
"DDR1_DQ<50>":   PN = "C26"  !CDS_PN = "C26";
"DDR1_DQ<51>":   PN = "E26"  !CDS_PN = "E26";
"DDR1_DQ<52>":   PN = "E30"  !CDS_PN = "E30";
"DDR1_DQ<53>":   PN = "F29"  !CDS_PN = "F29";
"DDR1_DQ<54>":   PN = "B27"  !CDS_PN = "B27";
"DDR1_DQ<55>":   PN = "F27"  !CDS_PN = "F27";
"DDR1_DQ<56>":   PN = "U28"  !CDS_PN = "U28";
"DDR1_DQ<57>":   PN = "AA28"  !CDS_PN = "AA28";
"DDR1_DQ<58>":   PN = "V25"  !CDS_PN = "V25";
"DDR1_DQ<59>":   PN = "Y25"  !CDS_PN = "Y25";
"DDR1_DQ<60>":   PN = "V29"  !CDS_PN = "V29";
"DDR1_DQ<61>":   PN = "Y29"  !CDS_PN = "Y29";
"DDR1_DQ<62>":   PN = "U26"  !CDS_PN = "U26";
"DDR1_DQ<63>":   PN = "AA26"  !CDS_PN = "AA26";
"DDR1_DQS_DN<0>":   PN = "AP79"  !CDS_PN = "AP79";
"DDR1_DQS_DN<1>":   PN = "AD79"  !CDS_PN = "AD79";
"DDR1_DQS_DN<2>":   PN = "K79"  !CDS_PN = "K79";
"DDR1_DQS_DN<3>":   PN = "H73"  !CDS_PN = "H73";
"DDR1_DQS_DN<4>":   PN = "N42"  !CDS_PN = "N42";
"DDR1_DQS_DN<5>":   PN = "G34"  !CDS_PN = "G34";
"DDR1_DQS_DN<6>":   PN = "G28"  !CDS_PN = "G28";
"DDR1_DQS_DN<7>":   PN = "AB27"  !CDS_PN = "AB27";
"DDR1_DQS_DN<8>":   PN = "N68"  !CDS_PN = "N68";
"DDR1_DQS_DN<9>":   PN = "AU82"  !CDS_PN = "AU82";
"DDR1_DQS_DN<10>":   PN = "AG82"  !CDS_PN = "AG82";
"DDR1_DQS_DN<11>":   PN = "D79"  !CDS_PN = "D79";
"DDR1_DQS_DN<12>":   PN = "B73"  !CDS_PN = "B73";
"DDR1_DQS_DN<13>":   PN = "J42"  !CDS_PN = "J42";
"DDR1_DQS_DN<14>":   PN = "A34"  !CDS_PN = "A34";
"DDR1_DQS_DN<15>":   PN = "A28"  !CDS_PN = "A28";
"DDR1_DQS_DN<16>":   PN = "T27"  !CDS_PN = "T27";
"DDR1_DQS_DN<17>":   PN = "G68"  !CDS_PN = "G68";
"DDR1_DQS_DP<0>":   PN = "AR80"  !CDS_PN = "AR80";
"DDR1_DQS_DP<1>":   PN = "AE80"  !CDS_PN = "AE80";
"DDR1_DQS_DP<2>":   PN = "H79"  !CDS_PN = "H79";
"DDR1_DQS_DP<3>":   PN = "F73"  !CDS_PN = "F73";
"DDR1_DQS_DP<4>":   PN = "R42"  !CDS_PN = "R42";
"DDR1_DQS_DP<5>":   PN = "E34"  !CDS_PN = "E34";
"DDR1_DQS_DP<6>":   PN = "E28"  !CDS_PN = "E28";
"DDR1_DQS_DP<7>":   PN = "Y27"  !CDS_PN = "Y27";
"DDR1_DQS_DP<8>":   PN = "L68"  !CDS_PN = "L68";
"DDR1_DQS_DP<9>":   PN = "AT81"  !CDS_PN = "AT81";
"DDR1_DQS_DP<10>":   PN = "AF81"  !CDS_PN = "AF81";
"DDR1_DQS_DP<11>":   PN = "F79"  !CDS_PN = "F79";
"DDR1_DQS_DP<12>":   PN = "D73"  !CDS_PN = "D73";
"DDR1_DQS_DP<13>":   PN = "L42"  !CDS_PN = "L42";
"DDR1_DQS_DP<14>":   PN = "C34"  !CDS_PN = "C34";
"DDR1_DQS_DP<15>":   PN = "C28"  !CDS_PN = "C28";
"DDR1_DQS_DP<16>":   PN = "V27"  !CDS_PN = "V27";
"DDR1_DQS_DP<17>":   PN = "J68"  !CDS_PN = "J68";
"DDR1_ECC<0>":   PN = "J70"  !CDS_PN = "J70";
"DDR1_ECC<1>":   PN = "H69"  !CDS_PN = "H69";
"DDR1_ECC<2>":   PN = "J66"  !CDS_PN = "J66";
"DDR1_ECC<3>":   PN = "L66"  !CDS_PN = "L66";
"DDR1_ECC<4>":   PN = "L70"  !CDS_PN = "L70";
"DDR1_ECC<5>":   PN = "M69"  !CDS_PN = "M69";
"DDR1_ECC<6>":   PN = "H67"  !CDS_PN = "H67";
"DDR1_ECC<7>":   PN = "M67"  !CDS_PN = "M67";
"DDR1_MA<0>":   PN = "J52"  !CDS_PN = "J52";
"DDR1_MA<1>":   PN = "J58"  !CDS_PN = "J58";
"DDR1_MA<2>":   PN = "K57"  !CDS_PN = "K57";
"DDR1_MA<3>":   PN = "N58"  !CDS_PN = "N58";
"DDR1_MA<4>":   PN = "M59"  !CDS_PN = "M59";
"DDR1_MA<5>":   PN = "R58"  !CDS_PN = "R58";
"DDR1_MA<6>":   PN = "T59"  !CDS_PN = "T59";
"DDR1_MA<7>":   PN = "V61"  !CDS_PN = "V61";
"DDR1_MA<8>":   PN = "W60"  !CDS_PN = "W60";
"DDR1_MA<9>":   PN = "K59"  !CDS_PN = "K59";
"DDR1_MA<10>":   PN = "M55"  !CDS_PN = "M55";
"DDR1_MA<11>":   PN = "R60"  !CDS_PN = "R60";
"DDR1_MA<12>":   PN = "T61"  !CDS_PN = "T61";
"DDR1_MA<13>":   PN = "M51"  !CDS_PN = "M51";
"DDR1_MA<14>":   PN = "T51"  !CDS_PN = "T51";
"DDR1_MA<15>":   PN = "N52"  !CDS_PN = "N52";
"DDR1_MA<16>":   PN = "R52"  !CDS_PN = "R52";
"DDR1_MA<17>":   PN = "N48"  !CDS_PN = "N48";
"DDR1_ODT<0>":   PN = "N50"  !CDS_PN = "N50";
"DDR1_ODT<1>":   PN = "R48"  !CDS_PN = "R48";
"DDR1_ODT<2>":   PN = "M49"  !CDS_PN = "M49";
"DDR1_ODT<3>":   PN = "T47"  !CDS_PN = "T47";
"DDR1_PAR":   PN = "K53"  !CDS_PN = "K53";
DRAWING = "@baseboard_fab2_lib.baseboard_fab2(sch_1):page25";
BODY = "SKX_EXT_B","I172": #LOCATION = "U5D1" !CDS_LOCATION = "U5D1" #SEC = "5" !CDS_SEC = "5";
"DDR2_ACT_N":   PN = "AB61"  !CDS_PN = "AB61";
"DDR2_ALERT_N":   PN = "AD61"  !CDS_PN = "AD61";
"DDR2_BA<0>":   PN = "W52"  !CDS_PN = "W52";
"DDR2_BA<1>":   PN = "AE56"  !CDS_PN = "AE56";
"DDR2_BG<0>":   PN = "AA60"  !CDS_PN = "AA60";
"DDR2_BG<1>":   PN = "AE62"  !CDS_PN = "AE62";
"DDR2_CID<2>":   PN = "AB45"  !CDS_PN = "AB45";
"DDR2_CKE<0>":   PN = "AA62"  !CDS_PN = "AA62";
"DDR2_CKE<1>":   PN = "AD63"  !CDS_PN = "AD63";
"DDR2_CKE<2>":   PN = "V63"  !CDS_PN = "V63";
"DDR2_CKE<3>":   PN = "AB63"  !CDS_PN = "AB63";
"DDR2_CLK_DN<0>":   PN = "AA54"  !CDS_PN = "AA54";
"DDR2_CLK_DN<1>":   PN = "W54"  !CDS_PN = "W54";
"DDR2_CLK_DN<2>":   PN = "AA56"  !CDS_PN = "AA56";
"DDR2_CLK_DN<3>":   PN = "W56"  !CDS_PN = "W56";
"DDR2_CLK_DP<0>":   PN = "AB55"  !CDS_PN = "AB55";
"DDR2_CLK_DP<1>":   PN = "V55"  !CDS_PN = "V55";
"DDR2_CLK_DP<2>":   PN = "AB57"  !CDS_PN = "AB57";
"DDR2_CLK_DP<3>":   PN = "V57"  !CDS_PN = "V57";
"DDR2_CS<0>_N":   PN = "V51"  !CDS_PN = "V51";
"DDR2_CS<1>_N":   PN = "AB49"  !CDS_PN = "AB49";
"DDR2_CS<2>_N":   PN = "W46"  !CDS_PN = "W46";
"DDR2_CS<3>_N":   PN = "AA46"  !CDS_PN = "AA46";
"DDR2_CS<4>_N":   PN = "AB51"  !CDS_PN = "AB51";
"DDR2_CS<5>_N":   PN = "W48"  !CDS_PN = "W48";
"DDR2_CS<6>_N":   PN = "T45"  !CDS_PN = "T45";
"DDR2_CS<7>_N":   PN = "V45"  !CDS_PN = "V45";
"DDR2_DQ<0>":   PN = "AR76"  !CDS_PN = "AR76";
"DDR2_DQ<1>":   PN = "AN74"  !CDS_PN = "AN74";
"DDR2_DQ<2>":   PN = "AK77"  !CDS_PN = "AK77";
"DDR2_DQ<3>":   PN = "AJ76"  !CDS_PN = "AJ76";
"DDR2_DQ<4>":   PN = "AT75"  !CDS_PN = "AT75";
"DDR2_DQ<5>":   PN = "AR74"  !CDS_PN = "AR74";
"DDR2_DQ<6>":   PN = "AM77"  !CDS_PN = "AM77";
"DDR2_DQ<7>":   PN = "AK75"  !CDS_PN = "AK75";
"DDR2_DQ<8>":   PN = "AE76"  !CDS_PN = "AE76";
"DDR2_DQ<9>":   PN = "AC74"  !CDS_PN = "AC74";
"DDR2_DQ<10>":   PN = "Y77"  !CDS_PN = "Y77";
"DDR2_DQ<11>":   PN = "W76"  !CDS_PN = "W76";
"DDR2_DQ<12>":   PN = "AF75"  !CDS_PN = "AF75";
"DDR2_DQ<13>":   PN = "AE74"  !CDS_PN = "AE74";
"DDR2_DQ<14>":   PN = "AB77"  !CDS_PN = "AB77";
"DDR2_DQ<15>":   PN = "Y75"  !CDS_PN = "Y75";
"DDR2_DQ<16>":   PN = "W72"  !CDS_PN = "W72";
"DDR2_DQ<17>":   PN = "AA70"  !CDS_PN = "AA70";
"DDR2_DQ<18>":   PN = "R70"  !CDS_PN = "R70";
"DDR2_DQ<19>":   PN = "T69"  !CDS_PN = "T69";
"DDR2_DQ<20>":   PN = "AA72"  !CDS_PN = "AA72";
"DDR2_DQ<21>":   PN = "AB71"  !CDS_PN = "AB71";
"DDR2_DQ<22>":   PN = "T71"  !CDS_PN = "T71";
"DDR2_DQ<23>":   PN = "V69"  !CDS_PN = "V69";
"DDR2_DQ<24>":   PN = "AM67"  !CDS_PN = "AM67";
"DDR2_DQ<25>":   PN = "AT67"  !CDS_PN = "AT67";
"DDR2_DQ<26>":   PN = "AN64"  !CDS_PN = "AN64";
"DDR2_DQ<27>":   PN = "AR64"  !CDS_PN = "AR64";
"DDR2_DQ<28>":   PN = "AN68"  !CDS_PN = "AN68";
"DDR2_DQ<29>":   PN = "AR68"  !CDS_PN = "AR68";
"DDR2_DQ<30>":   PN = "AM65"  !CDS_PN = "AM65";
"DDR2_DQ<31>":   PN = "AT65"  !CDS_PN = "AT65";
"DDR2_DQ<32>":   PN = "U40"  !CDS_PN = "U40";
"DDR2_DQ<33>":   PN = "AA40"  !CDS_PN = "AA40";
"DDR2_DQ<34>":   PN = "V37"  !CDS_PN = "V37";
"DDR2_DQ<35>":   PN = "Y37"  !CDS_PN = "Y37";
"DDR2_DQ<36>":   PN = "V41"  !CDS_PN = "V41";
"DDR2_DQ<37>":   PN = "Y41"  !CDS_PN = "Y41";
"DDR2_DQ<38>":   PN = "U38"  !CDS_PN = "U38";
"DDR2_DQ<39>":   PN = "AA38"  !CDS_PN = "AA38";
"DDR2_DQ<40>":   PN = "U34"  !CDS_PN = "U34";
"DDR2_DQ<41>":   PN = "AA34"  !CDS_PN = "AA34";
"DDR2_DQ<42>":   PN = "V31"  !CDS_PN = "V31";
"DDR2_DQ<43>":   PN = "Y31"  !CDS_PN = "Y31";
"DDR2_DQ<44>":   PN = "V35"  !CDS_PN = "V35";
"DDR2_DQ<45>":   PN = "Y35"  !CDS_PN = "Y35";
"DDR2_DQ<46>":   PN = "U32"  !CDS_PN = "U32";
"DDR2_DQ<47>":   PN = "AA32"  !CDS_PN = "AA32";
"DDR2_DQ<48>":   PN = "AD31"  !CDS_PN = "AD31";
"DDR2_DQ<49>":   PN = "AH31"  !CDS_PN = "AH31";
"DDR2_DQ<50>":   PN = "AE28"  !CDS_PN = "AE28";
"DDR2_DQ<51>":   PN = "AG28"  !CDS_PN = "AG28";
"DDR2_DQ<52>":   PN = "AE32"  !CDS_PN = "AE32";
"DDR2_DQ<53>":   PN = "AG32"  !CDS_PN = "AG32";
"DDR2_DQ<54>":   PN = "AD29"  !CDS_PN = "AD29";
"DDR2_DQ<55>":   PN = "AH29"  !CDS_PN = "AH29";
"DDR2_DQ<56>":   PN = "AD25"  !CDS_PN = "AD25";
"DDR2_DQ<57>":   PN = "AH25"  !CDS_PN = "AH25";
"DDR2_DQ<58>":   PN = "AE22"  !CDS_PN = "AE22";
"DDR2_DQ<59>":   PN = "AG22"  !CDS_PN = "AG22";
"DDR2_DQ<60>":   PN = "AE26"  !CDS_PN = "AE26";
"DDR2_DQ<61>":   PN = "AG26"  !CDS_PN = "AG26";
"DDR2_DQ<62>":   PN = "AD23"  !CDS_PN = "AD23";
"DDR2_DQ<63>":   PN = "AH23"  !CDS_PN = "AH23";
"DDR2_DQS_DN<0>":   PN = "AL74"  !CDS_PN = "AL74";
"DDR2_DQS_DN<1>":   PN = "AA74"  !CDS_PN = "AA74";
"DDR2_DQS_DN<2>":   PN = "Y69"  !CDS_PN = "Y69";
"DDR2_DQS_DN<3>":   PN = "AU66"  !CDS_PN = "AU66";
"DDR2_DQS_DN<4>":   PN = "AB39"  !CDS_PN = "AB39";
"DDR2_DQS_DN<5>":   PN = "AB33"  !CDS_PN = "AB33";
"DDR2_DQS_DN<6>":   PN = "AJ30"  !CDS_PN = "AJ30";
"DDR2_DQS_DN<7>":   PN = "AJ24"  !CDS_PN = "AJ24";
"DDR2_DQS_DN<8>":   PN = "BB71"  !CDS_PN = "BB71";
"DDR2_DQS_DN<9>":   PN = "AP77"  !CDS_PN = "AP77";
"DDR2_DQS_DN<10>":   PN = "AD77"  !CDS_PN = "AD77";
"DDR2_DQS_DN<11>":   PN = "U72"  !CDS_PN = "U72";
"DDR2_DQS_DN<12>":   PN = "AL66"  !CDS_PN = "AL66";
"DDR2_DQS_DN<13>":   PN = "T39"  !CDS_PN = "T39";
"DDR2_DQS_DN<14>":   PN = "T33"  !CDS_PN = "T33";
"DDR2_DQS_DN<15>":   PN = "AC30"  !CDS_PN = "AC30";
"DDR2_DQS_DN<16>":   PN = "AC24"  !CDS_PN = "AC24";
"DDR2_DQS_DN<17>":   PN = "AT71"  !CDS_PN = "AT71";
"DDR2_DQS_DP<0>":   PN = "AM75"  !CDS_PN = "AM75";
"DDR2_DQS_DP<1>":   PN = "AB75"  !CDS_PN = "AB75";
"DDR2_DQS_DP<2>":   PN = "W70"  !CDS_PN = "W70";
"DDR2_DQS_DP<3>":   PN = "AR66"  !CDS_PN = "AR66";
"DDR2_DQS_DP<4>":   PN = "Y39"  !CDS_PN = "Y39";
"DDR2_DQS_DP<5>":   PN = "Y33"  !CDS_PN = "Y33";
"DDR2_DQS_DP<6>":   PN = "AG30"  !CDS_PN = "AG30";
"DDR2_DQS_DP<7>":   PN = "AG24"  !CDS_PN = "AG24";
"DDR2_DQS_DP<8>":   PN = "AY71"  !CDS_PN = "AY71";
"DDR2_DQS_DP<9>":   PN = "AN76"  !CDS_PN = "AN76";
"DDR2_DQS_DP<10>":   PN = "AC76"  !CDS_PN = "AC76";
"DDR2_DQS_DP<11>":   PN = "V71"  !CDS_PN = "V71";
"DDR2_DQS_DP<12>":   PN = "AN66"  !CDS_PN = "AN66";
"DDR2_DQS_DP<13>":   PN = "V39"  !CDS_PN = "V39";
"DDR2_DQS_DP<14>":   PN = "V33"  !CDS_PN = "V33";
"DDR2_DQS_DP<15>":   PN = "AE30"  !CDS_PN = "AE30";
"DDR2_DQS_DP<16>":   PN = "AE24"  !CDS_PN = "AE24";
"DDR2_DQS_DP<17>":   PN = "AV71"  !CDS_PN = "AV71";
"DDR2_ECC<0>":   PN = "AU72"  !CDS_PN = "AU72";
"DDR2_ECC<1>":   PN = "BA72"  !CDS_PN = "BA72";
"DDR2_ECC<2>":   PN = "AV69"  !CDS_PN = "AV69";
"DDR2_ECC<3>":   PN = "AY69"  !CDS_PN = "AY69";
"DDR2_ECC<4>":   PN = "AV73"  !CDS_PN = "AV73";
"DDR2_ECC<5>":   PN = "AY73"  !CDS_PN = "AY73";
"DDR2_ECC<6>":   PN = "AU70"  !CDS_PN = "AU70";
"DDR2_ECC<7>":   PN = "BA70"  !CDS_PN = "BA70";
"DDR2_MA<0>":   PN = "AB53"  !CDS_PN = "AB53";
"DDR2_MA<1>":   PN = "AE58"  !CDS_PN = "AE58";
"DDR2_MA<2>":   PN = "AD57"  !CDS_PN = "AD57";
"DDR2_MA<3>":   PN = "W58"  !CDS_PN = "W58";
"DDR2_MA<4>":   PN = "AA58"  !CDS_PN = "AA58";
"DDR2_MA<5>":   PN = "V59"  !CDS_PN = "V59";
"DDR2_MA<6>":   PN = "AB59"  !CDS_PN = "AB59";
"DDR2_MA<7>":   PN = "AE60"  !CDS_PN = "AE60";
"DDR2_MA<8>":   PN = "AD59"  !CDS_PN = "AD59";
"DDR2_MA<9>":   PN = "AG58"  !CDS_PN = "AG58";
"DDR2_MA<10>":   PN = "AD55"  !CDS_PN = "AD55";
"DDR2_MA<11>":   PN = "AG60"  !CDS_PN = "AG60";
"DDR2_MA<12>":   PN = "AG62"  !CDS_PN = "AG62";
"DDR2_MA<13>":   PN = "AD53"  !CDS_PN = "AD53";
"DDR2_MA<14>":   PN = "W50"  !CDS_PN = "W50";
"DDR2_MA<15>":   PN = "AE54"  !CDS_PN = "AE54";
"DDR2_MA<16>":   PN = "AA52"  !CDS_PN = "AA52";
"DDR2_MA<17>":   PN = "AC46"  !CDS_PN = "AC46";
"DDR2_ODT<0>":   PN = "AA50"  !CDS_PN = "AA50";
"DDR2_ODT<1>":   PN = "AA48"  !CDS_PN = "AA48";
"DDR2_ODT<2>":   PN = "V49"  !CDS_PN = "V49";
"DDR2_ODT<3>":   PN = "AB47"  !CDS_PN = "AB47";
"DDR2_PAR":   PN = "V53"  !CDS_PN = "V53";
DRAWING = "@baseboard_fab2_lib.baseboard_fab2(sch_1):page26";
BODY = "SKX_EXT_B","I172": #LOCATION = "U5D1" !CDS_LOCATION = "U5D1" #SEC = "6" !CDS_SEC = "6";
"DDR3_ACT_N":   PN = "DW60"  !CDS_PN = "DW60";
"DDR3_ALERT_N":   PN = "ED63"  !CDS_PN = "ED63";
"DDR3_BA<0>":   PN = "EE52"  !CDS_PN = "EE52";
"DDR3_BA<1>":   PN = "EA54"  !CDS_PN = "EA54";
"DDR3_BG<0>":   PN = "ED61"  !CDS_PN = "ED61";
"DDR3_BG<1>":   PN = "DW62"  !CDS_PN = "DW62";
"DDR3_CID<2>":   PN = "DV47"  !CDS_PN = "DV47";
"DDR3_CKE<0>":   PN = "EE62"  !CDS_PN = "EE62";
"DDR3_CKE<1>":   PN = "EF63"  !CDS_PN = "EF63";
"DDR3_CKE<2>":   PN = "EA62"  !CDS_PN = "EA62";
"DDR3_CKE<3>":   PN = "EB63"  !CDS_PN = "EB63";
"DDR3_CLK_DN<0>":   PN = "ED55"  !CDS_PN = "ED55";
"DDR3_CLK_DN<1>":   PN = "EF55"  !CDS_PN = "EF55";
"DDR3_CLK_DN<2>":   PN = "DW56"  !CDS_PN = "DW56";
"DDR3_CLK_DN<3>":   PN = "EF57"  !CDS_PN = "EF57";
"DDR3_CLK_DP<0>":   PN = "EB55"  !CDS_PN = "EB55";
"DDR3_CLK_DP<1>":   PN = "EE54"  !CDS_PN = "EE54";
"DDR3_CLK_DP<2>":   PN = "EA56"  !CDS_PN = "EA56";
"DDR3_CLK_DP<3>":   PN = "EE56"  !CDS_PN = "EE56";
"DDR3_CS<0>_N":   PN = "EF51"  !CDS_PN = "EF51";
"DDR3_CS<1>_N":   PN = "ED49"  !CDS_PN = "ED49";
"DDR3_CS<2>_N":   PN = "ED47"  !CDS_PN = "ED47";
"DDR3_CS<3>_N":   PN = "EB47"  !CDS_PN = "EB47";
"DDR3_CS<4>_N":   PN = "EB51"  !CDS_PN = "EB51";
"DDR3_CS<5>_N":   PN = "EB49"  !CDS_PN = "EB49";
"DDR3_CS<6>_N":   PN = "DV45"  !CDS_PN = "DV45";
"DDR3_CS<7>_N":   PN = "EB45"  !CDS_PN = "EB45";
"DDR3_DQ<0>":   PN = "CN84"  !CDS_PN = "CN84";
"DDR3_DQ<1>":   PN = "CN86"  !CDS_PN = "CN86";
"DDR3_DQ<2>":   PN = "DA86"  !CDS_PN = "DA86";
"DDR3_DQ<3>":   PN = "DA84"  !CDS_PN = "DA84";
"DDR3_DQ<4>":   PN = "CL84"  !CDS_PN = "CL84";
"DDR3_DQ<5>":   PN = "CL86"  !CDS_PN = "CL86";
"DDR3_DQ<6>":   PN = "CW86"  !CDS_PN = "CW86";
"DDR3_DQ<7>":   PN = "CW84"  !CDS_PN = "CW84";
"DDR3_DQ<8>":   PN = "DG84"  !CDS_PN = "DG84";
"DDR3_DQ<9>":   PN = "DH85"  !CDS_PN = "DH85";
"DDR3_DQ<10>":   PN = "DV83"  !CDS_PN = "DV83";
"DDR3_DQ<11>":   PN = "DY83"  !CDS_PN = "DY83";
"DDR3_DQ<12>":   PN = "DD85"  !CDS_PN = "DD85";
"DDR3_DQ<13>":   PN = "DE84"  !CDS_PN = "DE84";
"DDR3_DQ<14>":   PN = "DR84"  !CDS_PN = "DR84";
"DDR3_DQ<15>":   PN = "DV85"  !CDS_PN = "DV85";
"DDR3_DQ<16>":   PN = "DM79"  !CDS_PN = "DM79";
"DDR3_DQ<17>":   PN = "DK81"  !CDS_PN = "DK81";
"DDR3_DQ<18>":   PN = "DT81"  !CDS_PN = "DT81";
"DDR3_DQ<19>":   PN = "DR82"  !CDS_PN = "DR82";
"DDR3_DQ<20>":   PN = "DK79"  !CDS_PN = "DK79";
"DDR3_DQ<21>":   PN = "DJ80"  !CDS_PN = "DJ80";
"DDR3_DQ<22>":   PN = "DR80"  !CDS_PN = "DR80";
"DDR3_DQ<23>":   PN = "DN82"  !CDS_PN = "DN82";
"DDR3_DQ<24>":   PN = "DN76"  !CDS_PN = "DN76";
"DDR3_DQ<25>":   PN = "DU76"  !CDS_PN = "DU76";
"DDR3_DQ<26>":   PN = "DP73"  !CDS_PN = "DP73";
"DDR3_DQ<27>":   PN = "DT73"  !CDS_PN = "DT73";
"DDR3_DQ<28>":   PN = "DP77"  !CDS_PN = "DP77";
"DDR3_DQ<29>":   PN = "DT77"  !CDS_PN = "DT77";
"DDR3_DQ<30>":   PN = "DN74"  !CDS_PN = "DN74";
"DDR3_DQ<31>":   PN = "DU74"  !CDS_PN = "DU74";
"DDR3_DQ<32>":   PN = "EC40"  !CDS_PN = "EC40";
"DDR3_DQ<33>":   PN = "ED39"  !CDS_PN = "ED39";
"DDR3_DQ<34>":   PN = "EA36"  !CDS_PN = "EA36";
"DDR3_DQ<35>":   PN = "EC36"  !CDS_PN = "EC36";
"DDR3_DQ<36>":   PN = "DY39"  !CDS_PN = "DY39";
"DDR3_DQ<37>":   PN = "EA40"  !CDS_PN = "EA40";
"DDR3_DQ<38>":   PN = "DY37"  !CDS_PN = "DY37";
"DDR3_DQ<39>":   PN = "ED37"  !CDS_PN = "ED37";
"DDR3_DQ<40>":   PN = "DN36"  !CDS_PN = "DN36";
"DDR3_DQ<41>":   PN = "DU36"  !CDS_PN = "DU36";
"DDR3_DQ<42>":   PN = "DP33"  !CDS_PN = "DP33";
"DDR3_DQ<43>":   PN = "DT33"  !CDS_PN = "DT33";
"DDR3_DQ<44>":   PN = "DP37"  !CDS_PN = "DP37";
"DDR3_DQ<45>":   PN = "DT37"  !CDS_PN = "DT37";
"DDR3_DQ<46>":   PN = "DN34"  !CDS_PN = "DN34";
"DDR3_DQ<47>":   PN = "DU34"  !CDS_PN = "DU34";
"DDR3_DQ<48>":   PN = "DN30"  !CDS_PN = "DN30";
"DDR3_DQ<49>":   PN = "DU30"  !CDS_PN = "DU30";
"DDR3_DQ<50>":   PN = "DP27"  !CDS_PN = "DP27";
"DDR3_DQ<51>":   PN = "DT27"  !CDS_PN = "DT27";
"DDR3_DQ<52>":   PN = "DP31"  !CDS_PN = "DP31";
"DDR3_DQ<53>":   PN = "DT31"  !CDS_PN = "DT31";
"DDR3_DQ<54>":   PN = "DN28"  !CDS_PN = "DN28";
"DDR3_DQ<55>":   PN = "DU28"  !CDS_PN = "DU28";
"DDR3_DQ<56>":   PN = "DN24"  !CDS_PN = "DN24";
"DDR3_DQ<57>":   PN = "DU24"  !CDS_PN = "DU24";
"DDR3_DQ<58>":   PN = "DY21"  !CDS_PN = "DY21";
"DDR3_DQ<59>":   PN = "EB21"  !CDS_PN = "EB21";
"DDR3_DQ<60>":   PN = "DP25"  !CDS_PN = "DP25";
"DDR3_DQ<61>":   PN = "DT25"  !CDS_PN = "DT25";
"DDR3_DQ<62>":   PN = "EC22"  !CDS_PN = "EC22";
"DDR3_DQ<63>":   PN = "DW22"  !CDS_PN = "DW22";
"DDR3_DQS_DN<0>":   PN = "CU84"  !CDS_PN = "CU84";
"DDR3_DQS_DN<1>":   PN = "DN84"  !CDS_PN = "DN84";
"DDR3_DQS_DN<2>":   PN = "DL82"  !CDS_PN = "DL82";
"DDR3_DQS_DN<3>":   PN = "DV75"  !CDS_PN = "DV75";
"DDR3_DQS_DN<4>":   PN = "EE38"  !CDS_PN = "EE38";
"DDR3_DQS_DN<5>":   PN = "DV35"  !CDS_PN = "DV35";
"DDR3_DQS_DN<6>":   PN = "DV29"  !CDS_PN = "DV29";
"DDR3_DQS_DN<7>":   PN = "DV23"  !CDS_PN = "DV23";
"DDR3_DQS_DN<8>":   PN = "DF67"  !CDS_PN = "DF67";
"DDR3_DQS_DN<9>":   PN = "CR84"  !CDS_PN = "CR84";
"DDR3_DQS_DN<10>":   PN = "DM85"  !CDS_PN = "DM85";
"DDR3_DQS_DN<11>":   PN = "DN80"  !CDS_PN = "DN80";
"DDR3_DQS_DN<12>":   PN = "DP75"  !CDS_PN = "DP75";
"DDR3_DQS_DN<13>":   PN = "EA38"  !CDS_PN = "EA38";
"DDR3_DQS_DN<14>":   PN = "DP35"  !CDS_PN = "DP35";
"DDR3_DQS_DN<15>":   PN = "DM29"  !CDS_PN = "DM29";
"DDR3_DQS_DN<16>":   PN = "DM23"  !CDS_PN = "DM23";
"DDR3_DQS_DN<17>":   PN = "DB67"  !CDS_PN = "DB67";
"DDR3_DQS_DP<0>":   PN = "CV85"  !CDS_PN = "CV85";
"DDR3_DQS_DP<1>":   PN = "DP85"  !CDS_PN = "DP85";
"DDR3_DQS_DP<2>":   PN = "DM81"  !CDS_PN = "DM81";
"DDR3_DQS_DP<3>":   PN = "DT75"  !CDS_PN = "DT75";
"DDR3_DQS_DP<4>":   PN = "EC38"  !CDS_PN = "EC38";
"DDR3_DQS_DP<5>":   PN = "DT35"  !CDS_PN = "DT35";
"DDR3_DQS_DP<6>":   PN = "DT29"  !CDS_PN = "DT29";
"DDR3_DQS_DP<7>":   PN = "DT23"  !CDS_PN = "DT23";
"DDR3_DQS_DP<8>":   PN = "DD67"  !CDS_PN = "DD67";
"DDR3_DQS_DP<9>":   PN = "CP85"  !CDS_PN = "CP85";
"DDR3_DQS_DP<10>":   PN = "DL84"  !CDS_PN = "DL84";
"DDR3_DQS_DP<11>":   PN = "DP79"  !CDS_PN = "DP79";
"DDR3_DQS_DP<12>":   PN = "DM75"  !CDS_PN = "DM75";
"DDR3_DQS_DP<13>":   PN = "DW38"  !CDS_PN = "DW38";
"DDR3_DQS_DP<14>":   PN = "DM35"  !CDS_PN = "DM35";
"DDR3_DQS_DP<15>":   PN = "DP29"  !CDS_PN = "DP29";
"DDR3_DQS_DP<16>":   PN = "DP23"  !CDS_PN = "DP23";
"DDR3_DQS_DP<17>":   PN = "CY67"  !CDS_PN = "CY67";
"DDR3_ECC<0>":   PN = "DA68"  !CDS_PN = "DA68";
"DDR3_ECC<1>":   PN = "DE68"  !CDS_PN = "DE68";
"DDR3_ECC<2>":   PN = "DB65"  !CDS_PN = "DB65";
"DDR3_ECC<3>":   PN = "DD65"  !CDS_PN = "DD65";
"DDR3_ECC<4>":   PN = "DB69"  !CDS_PN = "DB69";
"DDR3_ECC<5>":   PN = "DD69"  !CDS_PN = "DD69";
"DDR3_ECC<6>":   PN = "DA66"  !CDS_PN = "DA66";
"DDR3_ECC<7>":   PN = "DE66"  !CDS_PN = "DE66";
"DDR3_MA<0>":   PN = "EB53"  !CDS_PN = "EB53";
"DDR3_MA<1>":   PN = "ED57"  !CDS_PN = "ED57";
"DDR3_MA<2>":   PN = "EE58"  !CDS_PN = "EE58";
"DDR3_MA<3>":   PN = "EB57"  !CDS_PN = "EB57";
"DDR3_MA<4>":   PN = "ED59"  !CDS_PN = "ED59";
"DDR3_MA<5>":   PN = "EA58"  !CDS_PN = "EA58";
"DDR3_MA<6>":   PN = "EE60"  !CDS_PN = "EE60";
"DDR3_MA<7>":   PN = "EA60"  !CDS_PN = "EA60";
"DDR3_MA<8>":   PN = "EB59"  !CDS_PN = "EB59";
"DDR3_MA<9>":   PN = "EF61"  !CDS_PN = "EF61";
"DDR3_MA<10>":   PN = "DW54"  !CDS_PN = "DW54";
"DDR3_MA<11>":   PN = "EB61"  !CDS_PN = "EB61";
"DDR3_MA<12>":   PN = "DT63"  !CDS_PN = "DT63";
"DDR3_MA<13>":   PN = "DW48"  !CDS_PN = "DW48";
"DDR3_MA<14>":   PN = "ED51"  !CDS_PN = "ED51";
"DDR3_MA<15>":   PN = "DV49"  !CDS_PN = "DV49";
"DDR3_MA<16>":   PN = "EA52"  !CDS_PN = "EA52";
"DDR3_MA<17>":   PN = "EA46"  !CDS_PN = "EA46";
"DDR3_ODT<0>":   PN = "EE50"  !CDS_PN = "EE50";
"DDR3_ODT<1>":   PN = "EE48"  !CDS_PN = "EE48";
"DDR3_ODT<2>":   PN = "EA50"  !CDS_PN = "EA50";
"DDR3_ODT<3>":   PN = "EA48"  !CDS_PN = "EA48";
"DDR3_PAR":   PN = "ED53"  !CDS_PN = "ED53";
DRAWING = "@baseboard_fab2_lib.baseboard_fab2(sch_1):page27";
BODY = "SKX_EXT_B","I172": #LOCATION = "U5D1" !CDS_LOCATION = "U5D1" #SEC = "7" !CDS_SEC = "7";
"DDR4_ACT_N":   PN = "DR62"  !CDS_PN = "DR62";
"DDR4_ALERT_N":   PN = "DT61"  !CDS_PN = "DT61";
"DDR4_BA<0>":   PN = "DM53"  !CDS_PN = "DM53";
"DDR4_BA<1>":   PN = "DV55"  !CDS_PN = "DV55";
"DDR4_BG<0>":   PN = "DJ62"  !CDS_PN = "DJ62";
"DDR4_BG<1>":   PN = "DM61"  !CDS_PN = "DM61";
"DDR4_CID<2>":   PN = "DT47"  !CDS_PN = "DT47";
"DDR4_CKE<0>":   PN = "DM63"  !CDS_PN = "DM63";
"DDR4_CKE<1>":   PN = "DN64"  !CDS_PN = "DN64";
"DDR4_CKE<2>":   PN = "DL64"  !CDS_PN = "DL64";
"DDR4_CKE<3>":   PN = "DR64"  !CDS_PN = "DR64";
"DDR4_CLK_DN<0>":   PN = "DM55"  !CDS_PN = "DM55";
"DDR4_CLK_DN<1>":   PN = "DR54"  !CDS_PN = "DR54";
"DDR4_CLK_DN<2>":   PN = "DM57"  !CDS_PN = "DM57";
"DDR4_CLK_DN<3>":   PN = "DT57"  !CDS_PN = "DT57";
"DDR4_CLK_DP<0>":   PN = "DN54"  !CDS_PN = "DN54";
"DDR4_CLK_DP<1>":   PN = "DT53"  !CDS_PN = "DT53";
"DDR4_CLK_DP<2>":   PN = "DN56"  !CDS_PN = "DN56";
"DDR4_CLK_DP<3>":   PN = "DR56"  !CDS_PN = "DR56";
"DDR4_CS<0>_N":   PN = "DV51"  !CDS_PN = "DV51";
"DDR4_CS<1>_N":   PN = "DN50"  !CDS_PN = "DN50";
"DDR4_CS<2>_N":   PN = "DR46"  !CDS_PN = "DR46";
"DDR4_CS<3>_N":   PN = "DK47"  !CDS_PN = "DK47";
"DDR4_CS<4>_N":   PN = "DW50"  !CDS_PN = "DW50";
"DDR4_CS<5>_N":   PN = "DM49"  !CDS_PN = "DM49";
"DDR4_CS<6>_N":   PN = "DT45"  !CDS_PN = "DT45";
"DDR4_CS<7>_N":   PN = "DN46"  !CDS_PN = "DN46";
"DDR4_DQ<0>":   PN = "CM79"  !CDS_PN = "CM79";
"DDR4_DQ<1>":   PN = "CK81"  !CDS_PN = "CK81";
"DDR4_DQ<2>":   PN = "CT81"  !CDS_PN = "CT81";
"DDR4_DQ<3>":   PN = "CR82"  !CDS_PN = "CR82";
"DDR4_DQ<4>":   PN = "CK79"  !CDS_PN = "CK79";
"DDR4_DQ<5>":   PN = "CJ80"  !CDS_PN = "CJ80";
"DDR4_DQ<6>":   PN = "CR80"  !CDS_PN = "CR80";
"DDR4_DQ<7>":   PN = "CN82"  !CDS_PN = "CN82";
"DDR4_DQ<8>":   PN = "DB79"  !CDS_PN = "DB79";
"DDR4_DQ<9>":   PN = "CY81"  !CDS_PN = "CY81";
"DDR4_DQ<10>":   PN = "DE80"  !CDS_PN = "DE80";
"DDR4_DQ<11>":   PN = "DF81"  !CDS_PN = "DF81";
"DDR4_DQ<12>":   PN = "CY79"  !CDS_PN = "CY79";
"DDR4_DQ<13>":   PN = "CW80"  !CDS_PN = "CW80";
"DDR4_DQ<14>":   PN = "DC82"  !CDS_PN = "DC82";
"DDR4_DQ<15>":   PN = "DE82"  !CDS_PN = "DE82";
"DDR4_DQ<16>":   PN = "DW80"  !CDS_PN = "DW80";
"DDR4_DQ<17>":   PN = "EC80"  !CDS_PN = "EC80";
"DDR4_DQ<18>":   PN = "DY77"  !CDS_PN = "DY77";
"DDR4_DQ<19>":   PN = "EB77"  !CDS_PN = "EB77";
"DDR4_DQ<20>":   PN = "DY81"  !CDS_PN = "DY81";
"DDR4_DQ<21>":   PN = "EB81"  !CDS_PN = "EB81";
"DDR4_DQ<22>":   PN = "DW78"  !CDS_PN = "DW78";
"DDR4_DQ<23>":   PN = "EC78"  !CDS_PN = "EC78";
"DDR4_DQ<24>":   PN = "ED75"  !CDS_PN = "ED75";
"DDR4_DQ<25>":   PN = "EE74"  !CDS_PN = "EE74";
"DDR4_DQ<26>":   PN = "EB71"  !CDS_PN = "EB71";
"DDR4_DQ<27>":   PN = "ED71"  !CDS_PN = "ED71";
"DDR4_DQ<28>":   PN = "EA74"  !CDS_PN = "EA74";
"DDR4_DQ<29>":   PN = "EB75"  !CDS_PN = "EB75";
"DDR4_DQ<30>":   PN = "EA72"  !CDS_PN = "EA72";
"DDR4_DQ<31>":   PN = "EE72"  !CDS_PN = "EE72";
"DDR4_DQ<32>":   PN = "DU42"  !CDS_PN = "DU42";
"DDR4_DQ<33>":   PN = "DW42"  !CDS_PN = "DW42";
"DDR4_DQ<34>":   PN = "DP39"  !CDS_PN = "DP39";
"DDR4_DQ<35>":   PN = "DT39"  !CDS_PN = "DT39";
"DDR4_DQ<36>":   PN = "DL42"  !CDS_PN = "DL42";
"DDR4_DQ<37>":   PN = "DN42"  !CDS_PN = "DN42";
"DDR4_DQ<38>":   PN = "DN40"  !CDS_PN = "DN40";
"DDR4_DQ<39>":   PN = "DU40"  !CDS_PN = "DU40";
"DDR4_DQ<40>":   PN = "EC34"  !CDS_PN = "EC34";
"DDR4_DQ<41>":   PN = "ED33"  !CDS_PN = "ED33";
"DDR4_DQ<42>":   PN = "EA30"  !CDS_PN = "EA30";
"DDR4_DQ<43>":   PN = "EC30"  !CDS_PN = "EC30";
"DDR4_DQ<44>":   PN = "DY33"  !CDS_PN = "DY33";
"DDR4_DQ<45>":   PN = "EA34"  !CDS_PN = "EA34";
"DDR4_DQ<46>":   PN = "DY31"  !CDS_PN = "DY31";
"DDR4_DQ<47>":   PN = "ED31"  !CDS_PN = "ED31";
"DDR4_DQ<48>":   PN = "EC28"  !CDS_PN = "EC28";
"DDR4_DQ<49>":   PN = "ED27"  !CDS_PN = "ED27";
"DDR4_DQ<50>":   PN = "EA24"  !CDS_PN = "EA24";
"DDR4_DQ<51>":   PN = "EC24"  !CDS_PN = "EC24";
"DDR4_DQ<52>":   PN = "DY27"  !CDS_PN = "DY27";
"DDR4_DQ<53>":   PN = "EA28"  !CDS_PN = "EA28";
"DDR4_DQ<54>":   PN = "DY25"  !CDS_PN = "DY25";
"DDR4_DQ<55>":   PN = "ED25"  !CDS_PN = "ED25";
"DDR4_DQ<56>":   PN = "DF27"  !CDS_PN = "DF27";
"DDR4_DQ<57>":   PN = "DK27"  !CDS_PN = "DK27";
"DDR4_DQ<58>":   PN = "DD25"  !CDS_PN = "DD25";
"DDR4_DQ<59>":   PN = "DJ24"  !CDS_PN = "DJ24";
"DDR4_DQ<60>":   PN = "DG28"  !CDS_PN = "DG28";
"DDR4_DQ<61>":   PN = "DJ28"  !CDS_PN = "DJ28";
"DDR4_DQ<62>":   PN = "DF25"  !CDS_PN = "DF25";
"DDR4_DQ<63>":   PN = "DK25"  !CDS_PN = "DK25";
"DDR4_DQS_DN<0>":   PN = "CL82"  !CDS_PN = "CL82";
"DDR4_DQS_DN<1>":   PN = "DA82"  !CDS_PN = "DA82";
"DDR4_DQS_DN<2>":   PN = "ED79"  !CDS_PN = "ED79";
"DDR4_DQS_DN<3>":   PN = "EF73"  !CDS_PN = "EF73";
"DDR4_DQS_DN<4>":   PN = "DV41"  !CDS_PN = "DV41";
"DDR4_DQS_DN<5>":   PN = "EE32"  !CDS_PN = "EE32";
"DDR4_DQS_DN<6>":   PN = "EE26"  !CDS_PN = "EE26";
"DDR4_DQS_DN<7>":   PN = "DL26"  !CDS_PN = "DL26";
"DDR4_DQS_DN<8>":   PN = "EB67"  !CDS_PN = "EB67";
"DDR4_DQS_DN<9>":   PN = "CN80"  !CDS_PN = "CN80";
"DDR4_DQS_DN<10>":   PN = "DC80"  !CDS_PN = "DC80";
"DDR4_DQS_DN<11>":   PN = "DY79"  !CDS_PN = "DY79";
"DDR4_DQS_DN<12>":   PN = "EB73"  !CDS_PN = "EB73";
"DDR4_DQS_DN<13>":   PN = "DP41"  !CDS_PN = "DP41";
"DDR4_DQS_DN<14>":   PN = "EA32"  !CDS_PN = "EA32";
"DDR4_DQS_DN<15>":   PN = "EA26"  !CDS_PN = "EA26";
"DDR4_DQS_DN<16>":   PN = "DG26"  !CDS_PN = "DG26";
"DDR4_DQS_DN<17>":   PN = "DV67"  !CDS_PN = "DV67";
"DDR4_DQS_DP<0>":   PN = "CM81"  !CDS_PN = "CM81";
"DDR4_DQS_DP<1>":   PN = "DB81"  !CDS_PN = "DB81";
"DDR4_DQS_DP<2>":   PN = "EB79"  !CDS_PN = "EB79";
"DDR4_DQS_DP<3>":   PN = "ED73"  !CDS_PN = "ED73";
"DDR4_DQS_DP<4>":   PN = "DT41"  !CDS_PN = "DT41";
"DDR4_DQS_DP<5>":   PN = "EC32"  !CDS_PN = "EC32";
"DDR4_DQS_DP<6>":   PN = "EC26"  !CDS_PN = "EC26";
"DDR4_DQS_DP<7>":   PN = "DJ26"  !CDS_PN = "DJ26";
"DDR4_DQS_DP<8>":   PN = "DY67"  !CDS_PN = "DY67";
"DDR4_DQS_DP<9>":   PN = "CP79"  !CDS_PN = "CP79";
"DDR4_DQS_DP<10>":   PN = "DD79"  !CDS_PN = "DD79";
"DDR4_DQS_DP<11>":   PN = "DV79"  !CDS_PN = "DV79";
"DDR4_DQS_DP<12>":   PN = "DY73"  !CDS_PN = "DY73";
"DDR4_DQS_DP<13>":   PN = "DM41"  !CDS_PN = "DM41";
"DDR4_DQS_DP<14>":   PN = "DW32"  !CDS_PN = "DW32";
"DDR4_DQS_DP<15>":   PN = "DW26"  !CDS_PN = "DW26";
"DDR4_DQS_DP<16>":   PN = "DE26"  !CDS_PN = "DE26";
"DDR4_DQS_DP<17>":   PN = "DT67"  !CDS_PN = "DT67";
"DDR4_ECC<0>":   PN = "DY69"  !CDS_PN = "DY69";
"DDR4_ECC<1>":   PN = "EA68"  !CDS_PN = "EA68";
"DDR4_ECC<2>":   PN = "DV65"  !CDS_PN = "DV65";
"DDR4_ECC<3>":   PN = "DY65"  !CDS_PN = "DY65";
"DDR4_ECC<4>":   PN = "DU68"  !CDS_PN = "DU68";
"DDR4_ECC<5>":   PN = "DV69"  !CDS_PN = "DV69";
"DDR4_ECC<6>":   PN = "DU66"  !CDS_PN = "DU66";
"DDR4_ECC<7>":   PN = "EA66"  !CDS_PN = "EA66";
"DDR4_MA<0>":   PN = "DW52"  !CDS_PN = "DW52";
"DDR4_MA<1>":   PN = "DW58"  !CDS_PN = "DW58";
"DDR4_MA<2>":   PN = "DV57"  !CDS_PN = "DV57";
"DDR4_MA<3>":   PN = "DR58"  !CDS_PN = "DR58";
"DDR4_MA<4>":   PN = "DT59"  !CDS_PN = "DT59";
"DDR4_MA<5>":   PN = "DN58"  !CDS_PN = "DN58";
"DDR4_MA<6>":   PN = "DM59"  !CDS_PN = "DM59";
"DDR4_MA<7>":   PN = "DK61"  !CDS_PN = "DK61";
"DDR4_MA<8>":   PN = "DJ60"  !CDS_PN = "DJ60";
"DDR4_MA<9>":   PN = "DV59"  !CDS_PN = "DV59";
"DDR4_MA<10>":   PN = "DT55"  !CDS_PN = "DT55";
"DDR4_MA<11>":   PN = "DR60"  !CDS_PN = "DR60";
"DDR4_MA<12>":   PN = "DN60"  !CDS_PN = "DN60";
"DDR4_MA<13>":   PN = "DT51"  !CDS_PN = "DT51";
"DDR4_MA<14>":   PN = "DM51"  !CDS_PN = "DM51";
"DDR4_MA<15>":   PN = "DR52"  !CDS_PN = "DR52";
"DDR4_MA<16>":   PN = "DN52"  !CDS_PN = "DN52";
"DDR4_MA<17>":   PN = "DR48"  !CDS_PN = "DR48";
"DDR4_ODT<0>":   PN = "DR50"  !CDS_PN = "DR50";
"DDR4_ODT<1>":   PN = "DN48"  !CDS_PN = "DN48";
"DDR4_ODT<2>":   PN = "DT49"  !CDS_PN = "DT49";
"DDR4_ODT<3>":   PN = "DM47"  !CDS_PN = "DM47";
"DDR4_PAR":   PN = "DV53"  !CDS_PN = "DV53";
DRAWING = "@baseboard_fab2_lib.baseboard_fab2(sch_1):page28";
BODY = "SKX_EXT_B","I172": #LOCATION = "U5D1" !CDS_LOCATION = "U5D1" #SEC = "8" !CDS_SEC = "8";
"DDR5_ACT_N":   PN = "DC62"  !CDS_PN = "DC62";
"DDR5_ALERT_N":   PN = "DD61"  !CDS_PN = "DD61";
"DDR5_BA<0>":   PN = "DJ52"  !CDS_PN = "DJ52";
"DDR5_BA<1>":   PN = "DC56"  !CDS_PN = "DC56";
"DDR5_BG<0>":   PN = "DA62"  !CDS_PN = "DA62";
"DDR5_BG<1>":   PN = "DF61"  !CDS_PN = "DF61";
"DDR5_CID<2>":   PN = "DF45"  !CDS_PN = "DF45";
"DDR5_CKE<0>":   PN = "DG62"  !CDS_PN = "DG62";
"DDR5_CKE<1>":   PN = "DD63"  !CDS_PN = "DD63";
"DDR5_CKE<2>":   PN = "DK63"  !CDS_PN = "DK63";
"DDR5_CKE<3>":   PN = "DF63"  !CDS_PN = "DF63";
"DDR5_CLK_DN<0>":   PN = "DK55"  !CDS_PN = "DK55";
"DDR5_CLK_DN<1>":   PN = "DF55"  !CDS_PN = "DF55";
"DDR5_CLK_DN<2>":   PN = "DK57"  !CDS_PN = "DK57";
"DDR5_CLK_DN<3>":   PN = "DF57"  !CDS_PN = "DF57";
"DDR5_CLK_DP<0>":   PN = "DJ54"  !CDS_PN = "DJ54";
"DDR5_CLK_DP<1>":   PN = "DG54"  !CDS_PN = "DG54";
"DDR5_CLK_DP<2>":   PN = "DJ56"  !CDS_PN = "DJ56";
"DDR5_CLK_DP<3>":   PN = "DG56"  !CDS_PN = "DG56";
"DDR5_CS<0>_N":   PN = "DK51"  !CDS_PN = "DK51";
"DDR5_CS<1>_N":   PN = "DF49"  !CDS_PN = "DF49";
"DDR5_CS<2>_N":   PN = "DJ46"  !CDS_PN = "DJ46";
"DDR5_CS<3>_N":   PN = "DG46"  !CDS_PN = "DG46";
"DDR5_CS<4>_N":   PN = "DF51"  !CDS_PN = "DF51";
"DDR5_CS<5>_N":   PN = "DJ48"  !CDS_PN = "DJ48";
"DDR5_CS<6>_N":   PN = "DM45"  !CDS_PN = "DM45";
"DDR5_CS<7>_N":   PN = "DK45"  !CDS_PN = "DK45";
"DDR5_DQ<0>":   PN = "CR74"  !CDS_PN = "CR74";
"DDR5_DQ<1>":   PN = "CN76"  !CDS_PN = "CN76";
"DDR5_DQ<2>":   PN = "CW76"  !CDS_PN = "CW76";
"DDR5_DQ<3>":   PN = "CV77"  !CDS_PN = "CV77";
"DDR5_DQ<4>":   PN = "CN74"  !CDS_PN = "CN74";
"DDR5_DQ<5>":   PN = "CM75"  !CDS_PN = "CM75";
"DDR5_DQ<6>":   PN = "CV75"  !CDS_PN = "CV75";
"DDR5_DQ<7>":   PN = "CT77"  !CDS_PN = "CT77";
"DDR5_DQ<8>":   PN = "DE74"  !CDS_PN = "DE74";
"DDR5_DQ<9>":   PN = "DC76"  !CDS_PN = "DC76";
"DDR5_DQ<10>":   PN = "DH75"  !CDS_PN = "DH75";
"DDR5_DQ<11>":   PN = "DJ76"  !CDS_PN = "DJ76";
"DDR5_DQ<12>":   PN = "DC74"  !CDS_PN = "DC74";
"DDR5_DQ<13>":   PN = "DB75"  !CDS_PN = "DB75";
"DDR5_DQ<14>":   PN = "DF77"  !CDS_PN = "DF77";
"DDR5_DQ<15>":   PN = "DH77"  !CDS_PN = "DH77";
"DDR5_DQ<16>":   PN = "DG70"  !CDS_PN = "DG70";
"DDR5_DQ<17>":   PN = "DJ72"  !CDS_PN = "DJ72";
"DDR5_DQ<18>":   PN = "DM69"  !CDS_PN = "DM69";
"DDR5_DQ<19>":   PN = "DN70"  !CDS_PN = "DN70";
"DDR5_DQ<20>":   PN = "DF71"  !CDS_PN = "DF71";
"DDR5_DQ<21>":   PN = "DG72"  !CDS_PN = "DG72";
"DDR5_DQ<22>":   PN = "DK69"  !CDS_PN = "DK69";
"DDR5_DQ<23>":   PN = "DM71"  !CDS_PN = "DM71";
"DDR5_DQ<24>":   PN = "CN66"  !CDS_PN = "CN66";
"DDR5_DQ<25>":   PN = "CU66"  !CDS_PN = "CU66";
"DDR5_DQ<26>":   PN = "CP63"  !CDS_PN = "CP63";
"DDR5_DQ<27>":   PN = "CT63"  !CDS_PN = "CT63";
"DDR5_DQ<28>":   PN = "CP67"  !CDS_PN = "CP67";
"DDR5_DQ<29>":   PN = "CT67"  !CDS_PN = "CT67";
"DDR5_DQ<30>":   PN = "CN64"  !CDS_PN = "CN64";
"DDR5_DQ<31>":   PN = "CU64"  !CDS_PN = "CU64";
"DDR5_DQ<32>":   PN = "DD41"  !CDS_PN = "DD41";
"DDR5_DQ<33>":   PN = "DG42"  !CDS_PN = "DG42";
"DDR5_DQ<34>":   PN = "DE38"  !CDS_PN = "DE38";
"DDR5_DQ<35>":   PN = "DG38"  !CDS_PN = "DG38";
"DDR5_DQ<36>":   PN = "DA42"  !CDS_PN = "DA42";
"DDR5_DQ<37>":   PN = "DE42"  !CDS_PN = "DE42";
"DDR5_DQ<38>":   PN = "DD39"  !CDS_PN = "DD39";
"DDR5_DQ<39>":   PN = "DH39"  !CDS_PN = "DH39";
"DDR5_DQ<40>":   PN = "DF33"  !CDS_PN = "DF33";
"DDR5_DQ<41>":   PN = "DK33"  !CDS_PN = "DK33";
"DDR5_DQ<42>":   PN = "DG30"  !CDS_PN = "DG30";
"DDR5_DQ<43>":   PN = "DJ30"  !CDS_PN = "DJ30";
"DDR5_DQ<44>":   PN = "DG34"  !CDS_PN = "DG34";
"DDR5_DQ<45>":   PN = "DJ34"  !CDS_PN = "DJ34";
"DDR5_DQ<46>":   PN = "DF31"  !CDS_PN = "DF31";
"DDR5_DQ<47>":   PN = "DK31"  !CDS_PN = "DK31";
"DDR5_DQ<48>":   PN = "CW36"  !CDS_PN = "CW36";
"DDR5_DQ<49>":   PN = "DC36"  !CDS_PN = "DC36";
"DDR5_DQ<50>":   PN = "CY33"  !CDS_PN = "CY33";
"DDR5_DQ<51>":   PN = "DB33"  !CDS_PN = "DB33";
"DDR5_DQ<52>":   PN = "CY37"  !CDS_PN = "CY37";
"DDR5_DQ<53>":   PN = "DB37"  !CDS_PN = "DB37";
"DDR5_DQ<54>":   PN = "CW34"  !CDS_PN = "CW34";
"DDR5_DQ<55>":   PN = "DC34"  !CDS_PN = "DC34";
"DDR5_DQ<56>":   PN = "CW30"  !CDS_PN = "CW30";
"DDR5_DQ<57>":   PN = "DC30"  !CDS_PN = "DC30";
"DDR5_DQ<58>":   PN = "CY27"  !CDS_PN = "CY27";
"DDR5_DQ<59>":   PN = "DB27"  !CDS_PN = "DB27";
"DDR5_DQ<60>":   PN = "CY31"  !CDS_PN = "CY31";
"DDR5_DQ<61>":   PN = "DB31"  !CDS_PN = "DB31";
"DDR5_DQ<62>":   PN = "CW28"  !CDS_PN = "CW28";
"DDR5_DQ<63>":   PN = "DC28"  !CDS_PN = "DC28";
"DDR5_DQS_DN<0>":   PN = "CP77"  !CDS_PN = "CP77";
"DDR5_DQS_DN<1>":   PN = "DD77"  !CDS_PN = "DD77";
"DDR5_DQS_DN<2>":   PN = "DL72"  !CDS_PN = "DL72";
"DDR5_DQS_DN<3>":   PN = "CV65"  !CDS_PN = "CV65";
"DDR5_DQS_DN<4>":   PN = "DG40"  !CDS_PN = "DG40";
"DDR5_DQS_DN<5>":   PN = "DL32"  !CDS_PN = "DL32";
"DDR5_DQS_DN<6>":   PN = "DD35"  !CDS_PN = "DD35";
"DDR5_DQS_DN<7>":   PN = "DD29"  !CDS_PN = "DD29";
"DDR5_DQS_DN<8>":   PN = "CN70"  !CDS_PN = "CN70";
"DDR5_DQS_DN<9>":   PN = "CT75"  !CDS_PN = "CT75";
"DDR5_DQS_DN<10>":   PN = "DF75"  !CDS_PN = "DF75";
"DDR5_DQS_DN<11>":   PN = "DJ70"  !CDS_PN = "DJ70";
"DDR5_DQS_DN<12>":   PN = "CP65"  !CDS_PN = "CP65";
"DDR5_DQS_DN<13>":   PN = "DE40"  !CDS_PN = "DE40";
"DDR5_DQS_DN<14>":   PN = "DG32"  !CDS_PN = "DG32";
"DDR5_DQS_DN<15>":   PN = "CY35"  !CDS_PN = "CY35";
"DDR5_DQS_DN<16>":   PN = "CY29"  !CDS_PN = "CY29";
"DDR5_DQS_DN<17>":   PN = "CJ70"  !CDS_PN = "CJ70";
"DDR5_DQS_DP<0>":   PN = "CR76"  !CDS_PN = "CR76";
"DDR5_DQS_DP<1>":   PN = "DE76"  !CDS_PN = "DE76";
"DDR5_DQS_DP<2>":   PN = "DK71"  !CDS_PN = "DK71";
"DDR5_DQS_DP<3>":   PN = "CT65"  !CDS_PN = "CT65";
"DDR5_DQS_DP<4>":   PN = "DJ40"  !CDS_PN = "DJ40";
"DDR5_DQS_DP<5>":   PN = "DJ32"  !CDS_PN = "DJ32";
"DDR5_DQS_DP<6>":   PN = "DB35"  !CDS_PN = "DB35";
"DDR5_DQS_DP<7>":   PN = "DB29"  !CDS_PN = "DB29";
"DDR5_DQS_DP<8>":   PN = "CL70"  !CDS_PN = "CL70";
"DDR5_DQS_DP<9>":   PN = "CU74"  !CDS_PN = "CU74";
"DDR5_DQS_DP<10>":   PN = "DG74"  !CDS_PN = "DG74";
"DDR5_DQS_DP<11>":   PN = "DH69"  !CDS_PN = "DH69";
"DDR5_DQS_DP<12>":   PN = "CM65"  !CDS_PN = "CM65";
"DDR5_DQS_DP<13>":   PN = "DC40"  !CDS_PN = "DC40";
"DDR5_DQS_DP<14>":   PN = "DE32"  !CDS_PN = "DE32";
"DDR5_DQS_DP<15>":   PN = "CV35"  !CDS_PN = "CV35";
"DDR5_DQS_DP<16>":   PN = "CV29"  !CDS_PN = "CV29";
"DDR5_DQS_DP<17>":   PN = "CG70"  !CDS_PN = "CG70";
"DDR5_ECC<0>":   PN = "CH71"  !CDS_PN = "CH71";
"DDR5_ECC<1>":   PN = "CM71"  !CDS_PN = "CM71";
"DDR5_ECC<2>":   PN = "CJ68"  !CDS_PN = "CJ68";
"DDR5_ECC<3>":   PN = "CL68"  !CDS_PN = "CL68";
"DDR5_ECC<4>":   PN = "CJ72"  !CDS_PN = "CJ72";
"DDR5_ECC<5>":   PN = "CL72"  !CDS_PN = "CL72";
"DDR5_ECC<6>":   PN = "CH69"  !CDS_PN = "CH69";
"DDR5_ECC<7>":   PN = "CM69"  !CDS_PN = "CM69";
"DDR5_MA<0>":   PN = "DF53"  !CDS_PN = "DF53";
"DDR5_MA<1>":   PN = "DC58"  !CDS_PN = "DC58";
"DDR5_MA<2>":   PN = "DD57"  !CDS_PN = "DD57";
"DDR5_MA<3>":   PN = "DG58"  !CDS_PN = "DG58";
"DDR5_MA<4>":   PN = "DJ58"  !CDS_PN = "DJ58";
"DDR5_MA<5>":   PN = "DF59"  !CDS_PN = "DF59";
"DDR5_MA<6>":   PN = "DK59"  !CDS_PN = "DK59";
"DDR5_MA<7>":   PN = "DC60"  !CDS_PN = "DC60";
"DDR5_MA<8>":   PN = "DD59"  !CDS_PN = "DD59";
"DDR5_MA<9>":   PN = "DA58"  !CDS_PN = "DA58";
"DDR5_MA<10>":   PN = "DD55"  !CDS_PN = "DD55";
"DDR5_MA<11>":   PN = "DA60"  !CDS_PN = "DA60";
"DDR5_MA<12>":   PN = "DG60"  !CDS_PN = "DG60";
"DDR5_MA<13>":   PN = "DD53"  !CDS_PN = "DD53";
"DDR5_MA<14>":   PN = "DJ50"  !CDS_PN = "DJ50";
"DDR5_MA<15>":   PN = "DC54"  !CDS_PN = "DC54";
"DDR5_MA<16>":   PN = "DG52"  !CDS_PN = "DG52";
"DDR5_MA<17>":   PN = "DE46"  !CDS_PN = "DE46";
"DDR5_ODT<0>":   PN = "DG50"  !CDS_PN = "DG50";
"DDR5_ODT<1>":   PN = "DG48"  !CDS_PN = "DG48";
"DDR5_ODT<2>":   PN = "DK49"  !CDS_PN = "DK49";
"DDR5_ODT<3>":   PN = "DF47"  !CDS_PN = "DF47";
"DDR5_PAR":   PN = "DK53"  !CDS_PN = "DK53";
DRAWING = "@baseboard_fab2_lib.baseboard_fab2(sch_1):page29";
BODY = "SKX_EXT_B","I61": #LOCATION = "U5D1" !CDS_LOCATION = "U5D1" #SEC = "9" !CDS_SEC = "9";
"CD_HFI0_I2CCLK":   PN = "BN22"  !CDS_PN = "BN22";
"CD_HFI0_I2CDAT":   PN = "BP23"  !CDS_PN = "BP23";
"CD_HFI0_INT_N":   PN = "BP19"  !CDS_PN = "BP19";
"CD_HFI0_LED_N":   PN = "BK21"  !CDS_PN = "BK21";
"CD_HFI0_MODPRST_N":   PN = "BR20"  !CDS_PN = "BR20";
"CD_HFI0_RESET_N":   PN = "BN24"  !CDS_PN = "BN24";
"CD_HFI1_I2CCLK":   PN = "BJ22"  !CDS_PN = "BJ22";
"CD_HFI1_I2CDAT":   PN = "BH23"  !CDS_PN = "BH23";
"CD_HFI1_INT_N":   PN = "BM21"  !CDS_PN = "BM21";
"CD_HFI1_LED_N":   PN = "BM23"  !CDS_PN = "BM23";
"CD_HFI1_MODPRST_N":   PN = "BT19"  !CDS_PN = "BT19";
"CD_HFI1_RESET_N":   PN = "BK23"  !CDS_PN = "BK23";
"CD_HFI_REFCLK_DN":   PN = "BE16"  !CDS_PN = "BE16";
"CD_HFI_REFCLK_DP":   PN = "BG16"  !CDS_PN = "BG16";
"CD_PE_REFCLK_DN":   PN = "BU24"  !CDS_PN = "BU24";
"CD_PE_REFCLK_DP":   PN = "BW24"  !CDS_PN = "BW24";
"CD_POR_N":   PN = "CF25"  !CDS_PN = "CF25";
"CD_TCLK":   PN = "CB23"  !CDS_PN = "CB23";
"CD_TDI":   PN = "BY21"  !CDS_PN = "BY21";
"CD_TDO":   PN = "CC22"  !CDS_PN = "CC22";
"CD_TMS":   PN = "CE24"  !CDS_PN = "CE24";
"CD_TRST_N":   PN = "CD23"  !CDS_PN = "CD23";
"DMI_RX_DN<0>":   PN = "CK9"  !CDS_PN = "CK9";
"DMI_RX_DN<1>":   PN = "CM11"  !CDS_PN = "CM11";
"DMI_RX_DN<2>":   PN = "CR12"  !CDS_PN = "CR12";
"DMI_RX_DN<3>":   PN = "CT11"  !CDS_PN = "CT11";
"DMI_RX_DP<0>":   PN = "CL10"  !CDS_PN = "CL10";
"DMI_RX_DP<1>":   PN = "CN10"  !CDS_PN = "CN10";
"DMI_RX_DP<2>":   PN = "CP11"  !CDS_PN = "CP11";
"DMI_RX_DP<3>":   PN = "CV11"  !CDS_PN = "CV11";
"DMI_TX_DN<0>":   PN = "CG4"  !CDS_PN = "CG4";
"DMI_TX_DN<1>":   PN = "CJ4"  !CDS_PN = "CJ4";
"DMI_TX_DN<2>":   PN = "CN4"  !CDS_PN = "CN4";
"DMI_TX_DN<3>":   PN = "CP5"  !CDS_PN = "CP5";
"DMI_TX_DP<0>":   PN = "CH5"  !CDS_PN = "CH5";
"DMI_TX_DP<1>":   PN = "CL4"  !CDS_PN = "CL4";
"DMI_TX_DP<2>":   PN = "CM3"  !CDS_PN = "CM3";
"DMI_TX_DP<3>":   PN = "CR4"  !CDS_PN = "CR4";
"RSVD<172>":   PN = "BA76"  !CDS_PN = "BA76";
"RSVD<173>":   PN = "BA66"  !CDS_PN = "BA66";
"RSVD<174>":   PN = "BA64"  !CDS_PN = "BA64";
"RSVD<175>":   PN = "BA22"  !CDS_PN = "BA22";
"RSVD<176>":   PN = "BA18"  !CDS_PN = "BA18";
"RSVD<177>":   PN = "BA16"  !CDS_PN = "BA16";
"RSVD<178>":   PN = "BA14"  !CDS_PN = "BA14";
"RSVD<179>":   PN = "AY77"  !CDS_PN = "AY77";
"RSVD<180>":   PN = "AY75"  !CDS_PN = "AY75";
"RSVD<181>":   PN = "AY67"  !CDS_PN = "AY67";
"RSVD<182>":   PN = "AY65"  !CDS_PN = "AY65";
"RSVD<183>":   PN = "AW76"  !CDS_PN = "AW76";
"RSVD<184>":   PN = "AW64"  !CDS_PN = "AW64";
"RSVD<186>":   PN = "AV77"  !CDS_PN = "AV77";
"RSVD<187>":   PN = "AT25"  !CDS_PN = "AT25";
"RSVD<188>":   PN = "AT23"  !CDS_PN = "AT23";
"RSVD<189>":   PN = "AT13"  !CDS_PN = "AT13";
"RSVD<190>":   PN = "AR62"  !CDS_PN = "AR62";
"RSVD<191>":   PN = "AR26"  !CDS_PN = "AR26";
"RSVD<192>":   PN = "AR22"  !CDS_PN = "AR22";
"RSVD<193>":   PN = "AR20"  !CDS_PN = "AR20";
DRAWING = "@baseboard_fab2_lib.baseboard_fab2(sch_1):page30";
BODY = "SKX_EXT_B","I84": #LOCATION = "U5D1" !CDS_LOCATION = "U5D1" #SEC = "10" !CDS_SEC = "10";
"PE1_RX_DN<0>":   PN = "CW8"  !CDS_PN = "CW8";
"PE1_RX_DN<1>":   PN = "DA8"  !CDS_PN = "DA8";
"PE1_RX_DN<2>":   PN = "DC8"  !CDS_PN = "DC8";
"PE1_RX_DN<3>":   PN = "DC10"  !CDS_PN = "DC10";
"PE1_RX_DN<4>":   PN = "DE10"  !CDS_PN = "DE10";
"PE1_RX_DN<5>":   PN = "DH9"  !CDS_PN = "DH9";
"PE1_RX_DN<6>":   PN = "DK9"  !CDS_PN = "DK9";
"PE1_RX_DN<7>":   PN = "DM9"  !CDS_PN = "DM9";
"PE1_RX_DN<8>":   PN = "DM11"  !CDS_PN = "DM11";
"PE1_RX_DN<9>":   PN = "DP11"  !CDS_PN = "DP11";
"PE1_RX_DN<10>":   PN = "DT11"  !CDS_PN = "DT11";
"PE1_RX_DN<11>":   PN = "DT13"  !CDS_PN = "DT13";
"PE1_RX_DN<12>":   PN = "DV13"  !CDS_PN = "DV13";
"PE1_RX_DN<13>":   PN = "DW14"  !CDS_PN = "DW14";
"PE1_RX_DN<14>":   PN = "DY15"  !CDS_PN = "DY15";
"PE1_RX_DN<15>":   PN = "DU16"  !CDS_PN = "DU16";
"PE1_RX_DP<0>":   PN = "CU8"  !CDS_PN = "CU8";
"PE1_RX_DP<1>":   PN = "CY7"  !CDS_PN = "CY7";
"PE1_RX_DP<2>":   PN = "DB9"  !CDS_PN = "DB9";
"PE1_RX_DP<3>":   PN = "DA10"  !CDS_PN = "DA10";
"PE1_RX_DP<4>":   PN = "DD9"  !CDS_PN = "DD9";
"PE1_RX_DP<5>":   PN = "DF9"  !CDS_PN = "DF9";
"PE1_RX_DP<6>":   PN = "DJ8"  !CDS_PN = "DJ8";
"PE1_RX_DP<7>":   PN = "DL10"  !CDS_PN = "DL10";
"PE1_RX_DP<8>":   PN = "DK11"  !CDS_PN = "DK11";
"PE1_RX_DP<9>":   PN = "DN10"  !CDS_PN = "DN10";
"PE1_RX_DP<10>":   PN = "DR12"  !CDS_PN = "DR12";
"PE1_RX_DP<11>":   PN = "DP13"  !CDS_PN = "DP13";
"PE1_RX_DP<12>":   PN = "DU12"  !CDS_PN = "DU12";
"PE1_RX_DP<13>":   PN = "DY13"  !CDS_PN = "DY13";
"PE1_RX_DP<14>":   PN = "DV15"  !CDS_PN = "DV15";
"PE1_RX_DP<15>":   PN = "DT15"  !CDS_PN = "DT15";
"PE1_TX_DN<0>":   PN = "DA2"  !CDS_PN = "DA2";
"PE1_TX_DN<1>":   PN = "DC2"  !CDS_PN = "DC2";
"PE1_TX_DN<2>":   PN = "DE2"  !CDS_PN = "DE2";
"PE1_TX_DN<3>":   PN = "DE4"  !CDS_PN = "DE4";
"PE1_TX_DN<4>":   PN = "DG4"  !CDS_PN = "DG4";
"PE1_TX_DN<5>":   PN = "DK3"  !CDS_PN = "DK3";
"PE1_TX_DN<6>":   PN = "DM3"  !CDS_PN = "DM3";
"PE1_TX_DN<7>":   PN = "DN4"  !CDS_PN = "DN4";
"PE1_TX_DN<8>":   PN = "DT5"  !CDS_PN = "DT5";
"PE1_TX_DN<9>":   PN = "DV3"  !CDS_PN = "DV3";
"PE1_TX_DN<10>":   PN = "DW4"  !CDS_PN = "DW4";
"PE1_TX_DN<11>":   PN = "DU6"  !CDS_PN = "DU6";
"PE1_TX_DN<12>":   PN = "DV7"  !CDS_PN = "DV7";
"PE1_TX_DN<13>":   PN = "DY7"  !CDS_PN = "DY7";
"PE1_TX_DN<14>":   PN = "EA8"  !CDS_PN = "EA8";
"PE1_TX_DN<15>":   PN = "ED9"  !CDS_PN = "ED9";
"PE1_TX_DP<0>":   PN = "CW2"  !CDS_PN = "CW2";
"PE1_TX_DP<1>":   PN = "DB1"  !CDS_PN = "DB1";
"PE1_TX_DP<2>":   PN = "DD3"  !CDS_PN = "DD3";
"PE1_TX_DP<3>":   PN = "DC4"  !CDS_PN = "DC4";
"PE1_TX_DP<4>":   PN = "DF3"  !CDS_PN = "DF3";
"PE1_TX_DP<5>":   PN = "DH3"  !CDS_PN = "DH3";
"PE1_TX_DP<6>":   PN = "DL2"  !CDS_PN = "DL2";
"PE1_TX_DP<7>":   PN = "DP3"  !CDS_PN = "DP3";
"PE1_TX_DP<8>":   PN = "DR4"  !CDS_PN = "DR4";
"PE1_TX_DP<9>":   PN = "DU2"  !CDS_PN = "DU2";
"PE1_TX_DP<10>":   PN = "DU4"  !CDS_PN = "DU4";
"PE1_TX_DP<11>":   PN = "DV5"  !CDS_PN = "DV5";
"PE1_TX_DP<12>":   PN = "DT7"  !CDS_PN = "DT7";
"PE1_TX_DP<13>":   PN = "DW6"  !CDS_PN = "DW6";
"PE1_TX_DP<14>":   PN = "EB7"  !CDS_PN = "EB7";
"PE1_TX_DP<15>":   PN = "EC8"  !CDS_PN = "EC8";
DRAWING = "@baseboard_fab2_lib.baseboard_fab2(sch_1):page31";
BODY = "SKX_EXT_B","I106": #LOCATION = "U5D1" !CDS_LOCATION = "U5D1" #SEC = "11" !CDS_SEC = "11";
"PE2_RX_DN<0>":   PN = "CT9"  !CDS_PN = "CT9";
"PE2_RX_DN<1>":   PN = "CP9"  !CDS_PN = "CP9";
"PE2_RX_DN<2>":   PN = "CP7"  !CDS_PN = "CP7";
"PE2_RX_DN<3>":   PN = "CM7"  !CDS_PN = "CM7";
"PE2_RX_DN<4>":   PN = "CK7"  !CDS_PN = "CK7";
"PE2_RX_DN<5>":   PN = "CG8"  !CDS_PN = "CG8";
"PE2_RX_DN<6>":   PN = "CE6"  !CDS_PN = "CE6";
"PE2_RX_DN<7>":   PN = "CE8"  !CDS_PN = "CE8";
"PE2_RX_DN<8>":   PN = "BY9"  !CDS_PN = "BY9";
"PE2_RX_DN<9>":   PN = "BY7"  !CDS_PN = "BY7";
"PE2_RX_DN<10>":   PN = "BV7"  !CDS_PN = "BV7";
"PE2_RX_DN<11>":   PN = "BT7"  !CDS_PN = "BT7";
"PE2_RX_DN<12>":   PN = "BR8"  !CDS_PN = "BR8";
"PE2_RX_DN<13>":   PN = "BN8"  !CDS_PN = "BN8";
"PE2_RX_DN<14>":   PN = "BL8"  !CDS_PN = "BL8";
"PE2_RX_DN<15>":   PN = "BK9"  !CDS_PN = "BK9";
"PE2_RX_DP<0>":   PN = "CR8"  !CDS_PN = "CR8";
"PE2_RX_DP<1>":   PN = "CM9"  !CDS_PN = "CM9";
"PE2_RX_DP<2>":   PN = "CN8"  !CDS_PN = "CN8";
"PE2_RX_DP<3>":   PN = "CL6"  !CDS_PN = "CL6";
"PE2_RX_DP<4>":   PN = "CH7"  !CDS_PN = "CH7";
"PE2_RX_DP<5>":   PN = "CF7"  !CDS_PN = "CF7";
"PE2_RX_DP<6>":   PN = "CD7"  !CDS_PN = "CD7";
"PE2_RX_DP<7>":   PN = "CC8"  !CDS_PN = "CC8";
"PE2_RX_DP<8>":   PN = "BV9"  !CDS_PN = "BV9";
"PE2_RX_DP<9>":   PN = "BW8"  !CDS_PN = "BW8";
"PE2_RX_DP<10>":   PN = "BU6"  !CDS_PN = "BU6";
"PE2_RX_DP<11>":   PN = "BP7"  !CDS_PN = "BP7";
"PE2_RX_DP<12>":   PN = "BP9"  !CDS_PN = "BP9";
"PE2_RX_DP<13>":   PN = "BM7"  !CDS_PN = "BM7";
"PE2_RX_DP<14>":   PN = "BJ8"  !CDS_PN = "BJ8";
"PE2_RX_DP<15>":   PN = "BJ10"  !CDS_PN = "BJ10";
"PE2_TX_DN<0>":   PN = "CY3"  !CDS_PN = "CY3";
"PE2_TX_DN<1>":   PN = "CV3"  !CDS_PN = "CV3";
"PE2_TX_DN<2>":   PN = "CT1"  !CDS_PN = "CT1";
"PE2_TX_DN<3>":   PN = "CT3"  !CDS_PN = "CT3";
"PE2_TX_DN<4>":   PN = "CM1"  !CDS_PN = "CM1";
"PE2_TX_DN<5>":   PN = "CL2"  !CDS_PN = "CL2";
"PE2_TX_DN<6>":   PN = "CG2"  !CDS_PN = "CG2";
"PE2_TX_DN<7>":   PN = "CF3"  !CDS_PN = "CF3";
"PE2_TX_DN<8>":   PN = "CC2"  !CDS_PN = "CC2";
"PE2_TX_DN<9>":   PN = "CB3"  !CDS_PN = "CB3";
"PE2_TX_DN<10>":   PN = "CA4"  !CDS_PN = "CA4";
"PE2_TX_DN<11>":   PN = "BW4"  !CDS_PN = "BW4";
"PE2_TX_DN<12>":   PN = "BU4"  !CDS_PN = "BU4";
"PE2_TX_DN<13>":   PN = "BP5"  !CDS_PN = "BP5";
"PE2_TX_DN<14>":   PN = "BL4"  !CDS_PN = "BL4";
"PE2_TX_DN<15>":   PN = "BM5"  !CDS_PN = "BM5";
"PE2_TX_DP<0>":   PN = "CW4"  !CDS_PN = "CW4";
"PE2_TX_DP<1>":   PN = "CU2"  !CDS_PN = "CU2";
"PE2_TX_DP<2>":   PN = "CR2"  !CDS_PN = "CR2";
"PE2_TX_DP<3>":   PN = "CP3"  !CDS_PN = "CP3";
"PE2_TX_DP<4>":   PN = "CK1"  !CDS_PN = "CK1";
"PE2_TX_DP<5>":   PN = "CK3"  !CDS_PN = "CK3";
"PE2_TX_DP<6>":   PN = "CE2"  !CDS_PN = "CE2";
"PE2_TX_DP<7>":   PN = "CE4"  !CDS_PN = "CE4";
"PE2_TX_DP<8>":   PN = "CD3"  !CDS_PN = "CD3";
"PE2_TX_DP<9>":   PN = "BY3"  !CDS_PN = "BY3";
"PE2_TX_DP<10>":   PN = "BY5"  !CDS_PN = "BY5";
"PE2_TX_DP<11>":   PN = "BV3"  !CDS_PN = "BV3";
"PE2_TX_DP<12>":   PN = "BR4"  !CDS_PN = "BR4";
"PE2_TX_DP<13>":   PN = "BN4"  !CDS_PN = "BN4";
"PE2_TX_DP<14>":   PN = "BM3"  !CDS_PN = "BM3";
"PE2_TX_DP<15>":   PN = "BK5"  !CDS_PN = "BK5";
DRAWING = "@baseboard_fab2_lib.baseboard_fab2(sch_1):page32";
BODY = "SKX_EXT_B","I89": #LOCATION = "U5D1" !CDS_LOCATION = "U5D1" #SEC = "12" !CDS_SEC = "12";
"PE3_RX_DN<0>":   PN = "EA18"  !CDS_PN = "EA18";
"PE3_RX_DN<1>":   PN = "DW18"  !CDS_PN = "DW18";
"PE3_RX_DN<2>":   PN = "DW16"  !CDS_PN = "DW16";
"PE3_RX_DN<3>":   PN = "DT19"  !CDS_PN = "DT19";
"PE3_RX_DN<4>":   PN = "DR16"  !CDS_PN = "DR16";
"PE3_RX_DN<5>":   PN = "DR14"  !CDS_PN = "DR14";
"PE3_RX_DN<6>":   PN = "DN14"  !CDS_PN = "DN14";
"PE3_RX_DN<7>":   PN = "DL14"  !CDS_PN = "DL14";
"PE3_RX_DN<8>":   PN = "DL12"  !CDS_PN = "DL12";
"PE3_RX_DN<9>":   PN = "DJ12"  !CDS_PN = "DJ12";
"PE3_RX_DN<10>":   PN = "DG12"  !CDS_PN = "DG12";
"PE3_RX_DN<11>":   PN = "DG10"  !CDS_PN = "DG10";
"PE3_RX_DN<12>":   PN = "DD13"  !CDS_PN = "DD13";
"PE3_RX_DN<13>":   PN = "DB11"  !CDS_PN = "DB11";
"PE3_RX_DN<14>":   PN = "CY11"  !CDS_PN = "CY11";
"PE3_RX_DN<15>":   PN = "CV9"  !CDS_PN = "CV9";
"PE3_RX_DP<0>":   PN = "DY17"  !CDS_PN = "DY17";
"PE3_RX_DP<1>":   PN = "DU18"  !CDS_PN = "DU18";
"PE3_RX_DP<2>":   PN = "DV17"  !CDS_PN = "DV17";
"PE3_RX_DP<3>":   PN = "DR18"  !CDS_PN = "DR18";
"PE3_RX_DP<4>":   PN = "DN16"  !CDS_PN = "DN16";
"PE3_RX_DP<5>":   PN = "DP15"  !CDS_PN = "DP15";
"PE3_RX_DP<6>":   PN = "DM13"  !CDS_PN = "DM13";
"PE3_RX_DP<7>":   PN = "DJ14"  !CDS_PN = "DJ14";
"PE3_RX_DP<8>":   PN = "DK13"  !CDS_PN = "DK13";
"PE3_RX_DP<9>":   PN = "DH11"  !CDS_PN = "DH11";
"PE3_RX_DP<10>":   PN = "DE12"  !CDS_PN = "DE12";
"PE3_RX_DP<11>":   PN = "DF11"  !CDS_PN = "DF11";
"PE3_RX_DP<12>":   PN = "DC12"  !CDS_PN = "DC12";
"PE3_RX_DP<13>":   PN = "DA12"  !CDS_PN = "DA12";
"PE3_RX_DP<14>":   PN = "CW10"  !CDS_PN = "CW10";
"PE3_RX_DP<15>":   PN = "CU10"  !CDS_PN = "CU10";
"PE3_TX_DN<0>":   PN = "EE14"  !CDS_PN = "EE14";
"PE3_TX_DN<1>":   PN = "EE12"  !CDS_PN = "EE12";
"PE3_TX_DN<2>":   PN = "EC12"  !CDS_PN = "EC12";
"PE3_TX_DN<3>":   PN = "DY11"  !CDS_PN = "DY11";
"PE3_TX_DN<4>":   PN = "EB9"  !CDS_PN = "EB9";
"PE3_TX_DN<5>":   PN = "DW10"  !CDS_PN = "DW10";
"PE3_TX_DN<6>":   PN = "DU8"  !CDS_PN = "DU8";
"PE3_TX_DN<7>":   PN = "DR8"  !CDS_PN = "DR8";
"PE3_TX_DN<8>":   PN = "DM7"  !CDS_PN = "DM7";
"PE3_TX_DN<9>":   PN = "DP5"  !CDS_PN = "DP5";
"PE3_TX_DN<10>":   PN = "DL6"  !CDS_PN = "DL6";
"PE3_TX_DN<11>":   PN = "DJ4"  !CDS_PN = "DJ4";
"PE3_TX_DN<12>":   PN = "DJ6"  !CDS_PN = "DJ6";
"PE3_TX_DN<13>":   PN = "DD5"  !CDS_PN = "DD5";
"PE3_TX_DN<14>":   PN = "DB5"  !CDS_PN = "DB5";
"PE3_TX_DN<15>":   PN = "CY5"  !CDS_PN = "CY5";
"PE3_TX_DP<0>":   PN = "EC14"  !CDS_PN = "EC14";
"PE3_TX_DP<1>":   PN = "ED13"  !CDS_PN = "ED13";
"PE3_TX_DP<2>":   PN = "EB11"  !CDS_PN = "EB11";
"PE3_TX_DP<3>":   PN = "EA10"  !CDS_PN = "EA10";
"PE3_TX_DP<4>":   PN = "DY9"  !CDS_PN = "DY9";
"PE3_TX_DP<5>":   PN = "DV9"  !CDS_PN = "DV9";
"PE3_TX_DP<6>":   PN = "DT9"  !CDS_PN = "DT9";
"PE3_TX_DP<7>":   PN = "DP7"  !CDS_PN = "DP7";
"PE3_TX_DP<8>":   PN = "DN6"  !CDS_PN = "DN6";
"PE3_TX_DP<9>":   PN = "DM5"  !CDS_PN = "DM5";
"PE3_TX_DP<10>":   PN = "DK5"  !CDS_PN = "DK5";
"PE3_TX_DP<11>":   PN = "DH5"  !CDS_PN = "DH5";
"PE3_TX_DP<12>":   PN = "DG6"  !CDS_PN = "DG6";
"PE3_TX_DP<13>":   PN = "DC6"  !CDS_PN = "DC6";
"PE3_TX_DP<14>":   PN = "DA4"  !CDS_PN = "DA4";
"PE3_TX_DP<15>":   PN = "CV5"  !CDS_PN = "CV5";
DRAWING = "@baseboard_fab2_lib.baseboard_fab2(sch_1):page33";
BODY = "SKX_EXT_B","I86": #LOCATION = "U5D1" !CDS_LOCATION = "U5D1" #SEC = "13" !CDS_SEC = "13";
"UPI0_RX_DN<0>":   PN = "AC10"  !CDS_PN = "AC10";
"UPI0_RX_DN<1>":   PN = "AA8"  !CDS_PN = "AA8";
"UPI0_RX_DN<2>":   PN = "AB7"  !CDS_PN = "AB7";
"UPI0_RX_DN<3>":   PN = "AD5"  !CDS_PN = "AD5";
"UPI0_RX_DN<4>":   PN = "AE6"  !CDS_PN = "AE6";
"UPI0_RX_DN<5>":   PN = "AG8"  !CDS_PN = "AG8";
"UPI0_RX_DN<6>":   PN = "AJ6"  !CDS_PN = "AJ6";
"UPI0_RX_DN<7>":   PN = "AL6"  !CDS_PN = "AL6";
"UPI0_RX_DN<8>":   PN = "AK7"  !CDS_PN = "AK7";
"UPI0_RX_DN<9>":   PN = "AM9"  !CDS_PN = "AM9";
"UPI0_RX_DN<10>":   PN = "AP7"  !CDS_PN = "AP7";
"UPI0_RX_DN<11>":   PN = "AR8"  !CDS_PN = "AR8";
"UPI0_RX_DN<12>":   PN = "AU10"  !CDS_PN = "AU10";
"UPI0_RX_DN<13>":   PN = "BA8"  !CDS_PN = "BA8";
"UPI0_RX_DN<14>":   PN = "BC6"  !CDS_PN = "BC6";
"UPI0_RX_DN<15>":   PN = "BD7"  !CDS_PN = "BD7";
"UPI0_RX_DN<16>":   PN = "AW8"  !CDS_PN = "AW8";
"UPI0_RX_DN<17>":   PN = "AY9"  !CDS_PN = "AY9";
"UPI0_RX_DN<18>":   PN = "BD9"  !CDS_PN = "BD9";
"UPI0_RX_DN<19>":   PN = "BB11"  !CDS_PN = "BB11";
"UPI0_RX_DP<0>":   PN = "AB9"  !CDS_PN = "AB9";
"UPI0_RX_DP<1>":   PN = "AC8"  !CDS_PN = "AC8";
"UPI0_RX_DP<2>":   PN = "AA6"  !CDS_PN = "AA6";
"UPI0_RX_DP<3>":   PN = "AC6"  !CDS_PN = "AC6";
"UPI0_RX_DP<4>":   PN = "AG6"  !CDS_PN = "AG6";
"UPI0_RX_DP<5>":   PN = "AF7"  !CDS_PN = "AF7";
"UPI0_RX_DP<6>":   PN = "AH7"  !CDS_PN = "AH7";
"UPI0_RX_DP<7>":   PN = "AK5"  !CDS_PN = "AK5";
"UPI0_RX_DP<8>":   PN = "AM7"  !CDS_PN = "AM7";
"UPI0_RX_DP<9>":   PN = "AL8"  !CDS_PN = "AL8";
"UPI0_RX_DP<10>":   PN = "AN8"  !CDS_PN = "AN8";
"UPI0_RX_DP<11>":   PN = "AU8"  !CDS_PN = "AU8";
"UPI0_RX_DP<12>":   PN = "AT9"  !CDS_PN = "AT9";
"UPI0_RX_DP<13>":   PN = "AY7"  !CDS_PN = "AY7";
"UPI0_RX_DP<14>":   PN = "BB7"  !CDS_PN = "BB7";
"UPI0_RX_DP<15>":   PN = "BF7"  !CDS_PN = "BF7";
"UPI0_RX_DP<16>":   PN = "AV9"  !CDS_PN = "AV9";
"UPI0_RX_DP<17>":   PN = "BB9"  !CDS_PN = "BB9";
"UPI0_RX_DP<18>":   PN = "BC10"  !CDS_PN = "BC10";
"UPI0_RX_DP<19>":   PN = "BA10"  !CDS_PN = "BA10";
"UPI0_TX_DN<0>":   PN = "N2"  !CDS_PN = "N2";
"UPI0_TX_DN<1>":   PN = "P1"  !CDS_PN = "P1";
"UPI0_TX_DN<2>":   PN = "V3"  !CDS_PN = "V3";
"UPI0_TX_DN<3>":   PN = "Y1"  !CDS_PN = "Y1";
"UPI0_TX_DN<4>":   PN = "AB3"  !CDS_PN = "AB3";
"UPI0_TX_DN<5>":   PN = "AC2"  !CDS_PN = "AC2";
"UPI0_TX_DN<6>":   PN = "AG4"  !CDS_PN = "AG4";
"UPI0_TX_DN<7>":   PN = "AE2"  !CDS_PN = "AE2";
"UPI0_TX_DN<8>":   PN = "AH3"  !CDS_PN = "AH3";
"UPI0_TX_DN<9>":   PN = "AL2"  !CDS_PN = "AL2";
"UPI0_TX_DN<10>":   PN = "AM3"  !CDS_PN = "AM3";
"UPI0_TX_DN<11>":   PN = "AN4"  !CDS_PN = "AN4";
"UPI0_TX_DN<12>":   PN = "AT1"  !CDS_PN = "AT1";
"UPI0_TX_DN<13>":   PN = "AT3"  !CDS_PN = "AT3";
"UPI0_TX_DN<14>":   PN = "AU4"  !CDS_PN = "AU4";
"UPI0_TX_DN<15>":   PN = "AV5"  !CDS_PN = "AV5";
"UPI0_TX_DN<16>":   PN = "BA4"  !CDS_PN = "BA4";
"UPI0_TX_DN<17>":   PN = "BB3"  !CDS_PN = "BB3";
"UPI0_TX_DN<18>":   PN = "BF3"  !CDS_PN = "BF3";
"UPI0_TX_DN<19>":   PN = "BG4"  !CDS_PN = "BG4";
"UPI0_TX_DP<0>":   PN = "M1"  !CDS_PN = "M1";
"UPI0_TX_DP<1>":   PN = "T1"  !CDS_PN = "T1";
"UPI0_TX_DP<2>":   PN = "Y3"  !CDS_PN = "Y3";
"UPI0_TX_DP<3>":   PN = "W2"  !CDS_PN = "W2";
"UPI0_TX_DP<4>":   PN = "AA2"  !CDS_PN = "AA2";
"UPI0_TX_DP<5>":   PN = "AD1"  !CDS_PN = "AD1";
"UPI0_TX_DP<6>":   PN = "AF3"  !CDS_PN = "AF3";
"UPI0_TX_DP<7>":   PN = "AG2"  !CDS_PN = "AG2";
"UPI0_TX_DP<8>":   PN = "AJ2"  !CDS_PN = "AJ2";
"UPI0_TX_DP<9>":   PN = "AK1"  !CDS_PN = "AK1";
"UPI0_TX_DP<10>":   PN = "AK3"  !CDS_PN = "AK3";
"UPI0_TX_DP<11>":   PN = "AP3"  !CDS_PN = "AP3";
"UPI0_TX_DP<12>":   PN = "AP1"  !CDS_PN = "AP1";
"UPI0_TX_DP<13>":   PN = "AR2"  !CDS_PN = "AR2";
"UPI0_TX_DP<14>":   PN = "AR4"  !CDS_PN = "AR4";
"UPI0_TX_DP<15>":   PN = "AW4"  !CDS_PN = "AW4";
"UPI0_TX_DP<16>":   PN = "AY3"  !CDS_PN = "AY3";
"UPI0_TX_DP<17>":   PN = "BC2"  !CDS_PN = "BC2";
"UPI0_TX_DP<18>":   PN = "BD3"  !CDS_PN = "BD3";
"UPI0_TX_DP<19>":   PN = "BH3"  !CDS_PN = "BH3";
DRAWING = "@baseboard_fab2_lib.baseboard_fab2(sch_1):page34";
BODY = "SKX_EXT_B","I86": #LOCATION = "U5D1" !CDS_LOCATION = "U5D1" #SEC = "14" !CDS_SEC = "14";
"UPI1_RX_DN<0>":   PN = "T5"  !CDS_PN = "T5";
"UPI1_RX_DN<1>":   PN = "P7"  !CDS_PN = "P7";
"UPI1_RX_DN<2>":   PN = "V7"  !CDS_PN = "V7";
"UPI1_RX_DN<3>":   PN = "T9"  !CDS_PN = "T9";
"UPI1_RX_DN<4>":   PN = "P9"  !CDS_PN = "P9";
"UPI1_RX_DN<5>":   PN = "R10"  !CDS_PN = "R10";
"UPI1_RX_DN<6>":   PN = "U12"  !CDS_PN = "U12";
"UPI1_RX_DN<7>":   PN = "L12"  !CDS_PN = "L12";
"UPI1_RX_DN<8>":   PN = "N14"  !CDS_PN = "N14";
"UPI1_RX_DN<9>":   PN = "R12"  !CDS_PN = "R12";
"UPI1_RX_DN<10>":   PN = "R16"  !CDS_PN = "R16";
"UPI1_RX_DN<11>":   PN = "P17"  !CDS_PN = "P17";
"UPI1_RX_DN<12>":   PN = "U16"  !CDS_PN = "U16";
"UPI1_RX_DN<13>":   PN = "W18"  !CDS_PN = "W18";
"UPI1_RX_DN<14>":   PN = "R20"  !CDS_PN = "R20";
"UPI1_RX_DN<15>":   PN = "U18"  !CDS_PN = "U18";
"UPI1_RX_DN<16>":   PN = "P21"  !CDS_PN = "P21";
"UPI1_RX_DN<17>":   PN = "V19"  !CDS_PN = "V19";
"UPI1_RX_DN<18>":   PN = "Y21"  !CDS_PN = "Y21";
"UPI1_RX_DN<19>":   PN = "AB19"  !CDS_PN = "AB19";
"UPI1_RX_DP<0>":   PN = "R6"  !CDS_PN = "R6";
"UPI1_RX_DP<1>":   PN = "T7"  !CDS_PN = "T7";
"UPI1_RX_DP<2>":   PN = "U8"  !CDS_PN = "U8";
"UPI1_RX_DP<3>":   PN = "R8"  !CDS_PN = "R8";
"UPI1_RX_DP<4>":   PN = "N10"  !CDS_PN = "N10";
"UPI1_RX_DP<5>":   PN = "U10"  !CDS_PN = "U10";
"UPI1_RX_DP<6>":   PN = "T11"  !CDS_PN = "T11";
"UPI1_RX_DP<7>":   PN = "N12"  !CDS_PN = "N12";
"UPI1_RX_DP<8>":   PN = "M13"  !CDS_PN = "M13";
"UPI1_RX_DP<9>":   PN = "P13"  !CDS_PN = "P13";
"UPI1_RX_DP<10>":   PN = "T15"  !CDS_PN = "T15";
"UPI1_RX_DP<11>":   PN = "N16"  !CDS_PN = "N16";
"UPI1_RX_DP<12>":   PN = "W16"  !CDS_PN = "W16";
"UPI1_RX_DP<13>":   PN = "V17"  !CDS_PN = "V17";
"UPI1_RX_DP<14>":   PN = "P19"  !CDS_PN = "P19";
"UPI1_RX_DP<15>":   PN = "T19"  !CDS_PN = "T19";
"UPI1_RX_DP<16>":   PN = "T21"  !CDS_PN = "T21";
"UPI1_RX_DP<17>":   PN = "Y19"  !CDS_PN = "Y19";
"UPI1_RX_DP<18>":   PN = "W20"  !CDS_PN = "W20";
"UPI1_RX_DP<19>":   PN = "AA20"  !CDS_PN = "AA20";
"UPI1_TX_DN<0>":   PN = "M3"  !CDS_PN = "M3";
"UPI1_TX_DN<1>":   PN = "L4"  !CDS_PN = "L4";
"UPI1_TX_DN<2>":   PN = "K5"  !CDS_PN = "K5";
"UPI1_TX_DN<3>":   PN = "J6"  !CDS_PN = "J6";
"UPI1_TX_DN<4>":   PN = "G6"  !CDS_PN = "G6";
"UPI1_TX_DN<5>":   PN = "H7"  !CDS_PN = "H7";
"UPI1_TX_DN<6>":   PN = "K9"  !CDS_PN = "K9";
"UPI1_TX_DN<7>":   PN = "D9"  !CDS_PN = "D9";
"UPI1_TX_DN<8>":   PN = "F11"  !CDS_PN = "F11";
"UPI1_TX_DN<9>":   PN = "G10"  !CDS_PN = "G10";
"UPI1_TX_DN<10>":   PN = "E12"  !CDS_PN = "E12";
"UPI1_TX_DN<11>":   PN = "G14"  !CDS_PN = "G14";
"UPI1_TX_DN<12>":   PN = "D15"  !CDS_PN = "D15";
"UPI1_TX_DN<13>":   PN = "F15"  !CDS_PN = "F15";
"UPI1_TX_DN<14>":   PN = "H17"  !CDS_PN = "H17";
"UPI1_TX_DN<15>":   PN = "K19"  !CDS_PN = "K19";
"UPI1_TX_DN<16>":   PN = "G18"  !CDS_PN = "G18";
"UPI1_TX_DN<17>":   PN = "J20"  !CDS_PN = "J20";
"UPI1_TX_DN<18>":   PN = "F21"  !CDS_PN = "F21";
"UPI1_TX_DN<19>":   PN = "H21"  !CDS_PN = "H21";
"UPI1_TX_DP<0>":   PN = "P3"  !CDS_PN = "P3";
"UPI1_TX_DP<1>":   PN = "K3"  !CDS_PN = "K3";
"UPI1_TX_DP<2>":   PN = "M5"  !CDS_PN = "M5";
"UPI1_TX_DP<3>":   PN = "H5"  !CDS_PN = "H5";
"UPI1_TX_DP<4>":   PN = "F7"  !CDS_PN = "F7";
"UPI1_TX_DP<5>":   PN = "K7"  !CDS_PN = "K7";
"UPI1_TX_DP<6>":   PN = "J8"  !CDS_PN = "J8";
"UPI1_TX_DP<7>":   PN = "F9"  !CDS_PN = "F9";
"UPI1_TX_DP<8>":   PN = "E10"  !CDS_PN = "E10";
"UPI1_TX_DP<9>":   PN = "H9"  !CDS_PN = "H9";
"UPI1_TX_DP<10>":   PN = "G12"  !CDS_PN = "G12";
"UPI1_TX_DP<11>":   PN = "F13"  !CDS_PN = "F13";
"UPI1_TX_DP<12>":   PN = "E14"  !CDS_PN = "E14";
"UPI1_TX_DP<13>":   PN = "H15"  !CDS_PN = "H15";
"UPI1_TX_DP<14>":   PN = "G16"  !CDS_PN = "G16";
"UPI1_TX_DP<15>":   PN = "L18"  !CDS_PN = "L18";
"UPI1_TX_DP<16>":   PN = "J18"  !CDS_PN = "J18";
"UPI1_TX_DP<17>":   PN = "H19"  !CDS_PN = "H19";
"UPI1_TX_DP<18>":   PN = "G20"  !CDS_PN = "G20";
"UPI1_TX_DP<19>":   PN = "K21"  !CDS_PN = "K21";
DRAWING = "@baseboard_fab2_lib.baseboard_fab2(sch_1):page35";
BODY = "SKX_EXT_B","I3": #LOCATION = "U5D1" !CDS_LOCATION = "U5D1" #SEC = "15" !CDS_SEC = "15";
"UPI2_RX_DN<0>":   PN = "DF23"  !CDS_PN = "DF23";
"UPI2_RX_DN<1>":   PN = "DE22"  !CDS_PN = "DE22";
"UPI2_RX_DN<2>":   PN = "DC22"  !CDS_PN = "DC22";
"UPI2_RX_DN<3>":   PN = "DB21"  !CDS_PN = "DB21";
"UPI2_RX_DN<4>":   PN = "DD19"  !CDS_PN = "DD19";
"UPI2_RX_DN<5>":   PN = "DA20"  !CDS_PN = "DA20";
"UPI2_RX_DN<6>":   PN = "CW20"  !CDS_PN = "CW20";
"UPI2_RX_DN<7>":   PN = "CV19"  !CDS_PN = "CV19";
"UPI2_RX_DN<8>":   PN = "CT21"  !CDS_PN = "CT21";
"UPI2_RX_DN<9>":   PN = "CR18"  !CDS_PN = "CR18";
"UPI2_RX_DN<10>":   PN = "CN20"  !CDS_PN = "CN20";
"UPI2_RX_DN<11>":   PN = "CP21"  !CDS_PN = "CP21";
"UPI2_RX_DN<12>":   PN = "CL16"  !CDS_PN = "CL16";
"UPI2_RX_DN<13>":   PN = "CJ18"  !CDS_PN = "CJ18";
"UPI2_RX_DN<14>":   PN = "CH17"  !CDS_PN = "CH17";
"UPI2_RX_DN<15>":   PN = "CE16"  !CDS_PN = "CE16";
"UPI2_RX_DN<16>":   PN = "CD15"  !CDS_PN = "CD15";
"UPI2_RX_DN<17>":   PN = "CF17"  !CDS_PN = "CF17";
"UPI2_RX_DN<18>":   PN = "CB15"  !CDS_PN = "CB15";
"UPI2_RX_DN<19>":   PN = "BY17"  !CDS_PN = "BY17";
"UPI2_RX_DP<0>":   PN = "DG22"  !CDS_PN = "DG22";
"UPI2_RX_DP<1>":   PN = "DD21"  !CDS_PN = "DD21";
"UPI2_RX_DP<2>":   PN = "DA22"  !CDS_PN = "DA22";
"UPI2_RX_DP<3>":   PN = "DC20"  !CDS_PN = "DC20";
"UPI2_RX_DP<4>":   PN = "DB19"  !CDS_PN = "DB19";
"UPI2_RX_DP<5>":   PN = "CY19"  !CDS_PN = "CY19";
"UPI2_RX_DP<6>":   PN = "CU20"  !CDS_PN = "CU20";
"UPI2_RX_DP<7>":   PN = "CW18"  !CDS_PN = "CW18";
"UPI2_RX_DP<8>":   PN = "CR20"  !CDS_PN = "CR20";
"UPI2_RX_DP<9>":   PN = "CN18"  !CDS_PN = "CN18";
"UPI2_RX_DP<10>":   PN = "CP19"  !CDS_PN = "CP19";
"UPI2_RX_DP<11>":   PN = "CM21"  !CDS_PN = "CM21";
"UPI2_RX_DP<12>":   PN = "CJ16"  !CDS_PN = "CJ16";
"UPI2_RX_DP<13>":   PN = "CK17"  !CDS_PN = "CK17";
"UPI2_RX_DP<14>":   PN = "CG16"  !CDS_PN = "CG16";
"UPI2_RX_DP<15>":   PN = "CF15"  !CDS_PN = "CF15";
"UPI2_RX_DP<16>":   PN = "CC14"  !CDS_PN = "CC14";
"UPI2_RX_DP<17>":   PN = "CD17"  !CDS_PN = "CD17";
"UPI2_RX_DP<18>":   PN = "BY15"  !CDS_PN = "BY15";
"UPI2_RX_DP<19>":   PN = "CA16"  !CDS_PN = "CA16";
"UPI2_TX_DN<0>":   PN = "DT21"  !CDS_PN = "DT21";
"UPI2_TX_DN<1>":   PN = "DM21"  !CDS_PN = "DM21";
"UPI2_TX_DN<2>":   PN = "DL20"  !CDS_PN = "DL20";
"UPI2_TX_DN<3>":   PN = "DG20"  !CDS_PN = "DG20";
"UPI2_TX_DN<4>":   PN = "DH19"  !CDS_PN = "DH19";
"UPI2_TX_DN<5>":   PN = "DK17"  !CDS_PN = "DK17";
"UPI2_TX_DN<6>":   PN = "DG18"  !CDS_PN = "DG18";
"UPI2_TX_DN<7>":   PN = "DD17"  !CDS_PN = "DD17";
"UPI2_TX_DN<8>":   PN = "DF15"  !CDS_PN = "DF15";
"UPI2_TX_DN<9>":   PN = "DC16"  !CDS_PN = "DC16";
"UPI2_TX_DN<10>":   PN = "DA16"  !CDS_PN = "DA16";
"UPI2_TX_DN<11>":   PN = "CW14"  !CDS_PN = "CW14";
"UPI2_TX_DN<12>":   PN = "CU14"  !CDS_PN = "CU14";
"UPI2_TX_DN<13>":   PN = "CM13"  !CDS_PN = "CM13";
"UPI2_TX_DN<14>":   PN = "CJ14"  !CDS_PN = "CJ14";
"UPI2_TX_DN<15>":   PN = "CF13"  !CDS_PN = "CF13";
"UPI2_TX_DN<16>":   PN = "CH11"  !CDS_PN = "CH11";
"UPI2_TX_DN<17>":   PN = "CE12"  !CDS_PN = "CE12";
"UPI2_TX_DN<18>":   PN = "CC10"  !CDS_PN = "CC10";
"UPI2_TX_DN<19>":   PN = "CC12"  !CDS_PN = "CC12";
"UPI2_TX_DP<0>":   PN = "DP21"  !CDS_PN = "DP21";
"UPI2_TX_DP<1>":   PN = "DN20"  !CDS_PN = "DN20";
"UPI2_TX_DP<2>":   PN = "DK19"  !CDS_PN = "DK19";
"UPI2_TX_DP<3>":   PN = "DJ20"  !CDS_PN = "DJ20";
"UPI2_TX_DP<4>":   PN = "DJ18"  !CDS_PN = "DJ18";
"UPI2_TX_DP<5>":   PN = "DH17"  !CDS_PN = "DH17";
"UPI2_TX_DP<6>":   PN = "DF17"  !CDS_PN = "DF17";
"UPI2_TX_DP<7>":   PN = "DE16"  !CDS_PN = "DE16";
"UPI2_TX_DP<8>":   PN = "DD15"  !CDS_PN = "DD15";
"UPI2_TX_DP<9>":   PN = "DB15"  !CDS_PN = "DB15";
"UPI2_TX_DP<10>":   PN = "CW16"  !CDS_PN = "CW16";
"UPI2_TX_DP<11>":   PN = "CV13"  !CDS_PN = "CV13";
"UPI2_TX_DP<12>":   PN = "CR14"  !CDS_PN = "CR14";
"UPI2_TX_DP<13>":   PN = "CK13"  !CDS_PN = "CK13";
"UPI2_TX_DP<14>":   PN = "CH13"  !CDS_PN = "CH13";
"UPI2_TX_DP<15>":   PN = "CG12"  !CDS_PN = "CG12";
"UPI2_TX_DP<16>":   PN = "CF11"  !CDS_PN = "CF11";
"UPI2_TX_DP<17>":   PN = "CD11"  !CDS_PN = "CD11";
"UPI2_TX_DP<18>":   PN = "CB11"  !CDS_PN = "CB11";
"UPI2_TX_DP<19>":   PN = "CA12"  !CDS_PN = "CA12";
DRAWING = "@baseboard_fab2_lib.baseboard_fab2(sch_1):page36";
BODY = "SKX_EXT_B","I15": #LOCATION = "U5D1" !CDS_LOCATION = "U5D1" #SEC = "16" !CDS_SEC = "16";
"RSVD<92>":   PN = "CH23"  !CDS_PN = "CH23";
"RSVD<93>":   PN = "CH21"  !CDS_PN = "CH21";
"RSVD<94>":   PN = "CG82"  !CDS_PN = "CG82";
"RSVD<95>":   PN = "CG78"  !CDS_PN = "CG78";
"RSVD<96>":   PN = "CG26"  !CDS_PN = "CG26";
"RSVD<97>":   PN = "CG24"  !CDS_PN = "CG24";
"RSVD<98>":   PN = "CG20"  !CDS_PN = "CG20";
"RSVD<99>":   PN = "CG10"  !CDS_PN = "CG10";
"RSVD<100>":   PN = "CF81"  !CDS_PN = "CF81";
"RSVD<101>":   PN = "CF79"  !CDS_PN = "CF79";
"RSVD<102>":   PN = "CF23"  !CDS_PN = "CF23";
"RSVD<103>":   PN = "CF21"  !CDS_PN = "CF21";
"RSVD<104>":   PN = "CF19"  !CDS_PN = "CF19";
"RSVD<105>":   PN = "CE80"  !CDS_PN = "CE80";
"RSVD<106>":   PN = "CE78"  !CDS_PN = "CE78";
"RSVD<107>":   PN = "CE22"  !CDS_PN = "CE22";
"RSVD<108>":   PN = "CD25"  !CDS_PN = "CD25";
"RSVD<109>":   PN = "CD21"  !CDS_PN = "CD21";
"RSVD<110>":   PN = "CD19"  !CDS_PN = "CD19";
"RSVD<111>":   PN = "CC6"  !CDS_PN = "CC6";
"RSVD<112>":   PN = "CC20"  !CDS_PN = "CC20";
"RSVD<113>":   PN = "CB5"  !CDS_PN = "CB5";
"RSVD<114>":   PN = "CB25"  !CDS_PN = "CB25";
"RSVD<115>":   PN = "CB21"  !CDS_PN = "CB21";
"RSVD<116>":   PN = "CB19"  !CDS_PN = "CB19";
"RSVD<117>":   PN = "CA24"  !CDS_PN = "CA24";
"RSVD<118>":   PN = "CA22"  !CDS_PN = "CA22";
"RSVD<119>":   PN = "BY25"  !CDS_PN = "BY25";
"RSVD<120>":   PN = "BY19"  !CDS_PN = "BY19";
"RSVD<121>":   PN = "BW22"  !CDS_PN = "BW22";
"RSVD<122>":   PN = "BW20"  !CDS_PN = "BW20";
"RSVD<123>":   PN = "BW10"  !CDS_PN = "BW10";
"RSVD<124>":   PN = "BV23"  !CDS_PN = "BV23";
"RSVD<125>":   PN = "BV21"  !CDS_PN = "BV21";
"RSVD<126>":   PN = "BV19"  !CDS_PN = "BV19";
"RSVD<127>":   PN = "BU22"  !CDS_PN = "BU22";
"RSVD<128>":   PN = "BU20"  !CDS_PN = "BU20";
"RSVD<129>":   PN = "BU18"  !CDS_PN = "BU18";
"RSVD<130>":   PN = "BR24"  !CDS_PN = "BR24";
"RSVD<131>":   PN = "BR22"  !CDS_PN = "BR22";
"RSVD<132>":   PN = "BP21"  !CDS_PN = "BP21";
"RSVD<133>":   PN = "BP17"  !CDS_PN = "BP17";
"RSVD<134>":   PN = "BN18"  !CDS_PN = "BN18";
"RSVD<135>":   PN = "BM19"  !CDS_PN = "BM19";
"RSVD<136>":   PN = "BM17"  !CDS_PN = "BM17";
"RSVD<137>":   PN = "BL20"  !CDS_PN = "BL20";
"RSVD<138>":   PN = "BL18"  !CDS_PN = "BL18";
"RSVD<139>":   PN = "BK17"  !CDS_PN = "BK17";
"RSVD<140>":   PN = "BJ20"  !CDS_PN = "BJ20";
"RSVD<141>":   PN = "BJ18"  !CDS_PN = "BJ18";
"RSVD<142>":   PN = "BJ16"  !CDS_PN = "BJ16";
"RSVD<143>":   PN = "BH19"  !CDS_PN = "BH19";
"RSVD<144>":   PN = "BG20"  !CDS_PN = "BG20";
"RSVD<145>":   PN = "BG18"  !CDS_PN = "BG18";
"RSVD<146>":   PN = "BF21"  !CDS_PN = "BF21";
"RSVD<147>":   PN = "BE22"  !CDS_PN = "BE22";
"RSVD<148>":   PN = "BE20"  !CDS_PN = "BE20";
"RSVD<149>":   PN = "BE18"  !CDS_PN = "BE18";
"RSVD<150>":   PN = "BD69"  !CDS_PN = "BD69";
"RSVD<151>":   PN = "BD67"  !CDS_PN = "BD67";
"RSVD<152>":   PN = "BD65"  !CDS_PN = "BD65";
"RSVD<153>":   PN = "BD25"  !CDS_PN = "BD25";
"RSVD<154>":   PN = "BD19"  !CDS_PN = "BD19";
"RSVD<155>":   PN = "BD17"  !CDS_PN = "BD17";
"RSVD<156>":   PN = "BC68"  !CDS_PN = "BC68";
"RSVD<157>":   PN = "BC66"  !CDS_PN = "BC66";
"RSVD<158>":   PN = "BC64"  !CDS_PN = "BC64";
"RSVD<159>":   PN = "BC22"  !CDS_PN = "BC22";
"RSVD<160>":   PN = "BC20"  !CDS_PN = "BC20";
"RSVD<161>":   PN = "BC18"  !CDS_PN = "BC18";
"RSVD<162>":   PN = "BC14"  !CDS_PN = "BC14";
"RSVD<163>":   PN = "BB67"  !CDS_PN = "BB67";
"RSVD<164>":   PN = "BB65"  !CDS_PN = "BB65";
"RSVD<165>":   PN = "BB25"  !CDS_PN = "BB25";
"RSVD<166>":   PN = "BB21"  !CDS_PN = "BB21";
"RSVD<167>":   PN = "BB17"  !CDS_PN = "BB17";
"RSVD<168>":   PN = "BB15"  !CDS_PN = "BB15";
"RSVD<169>":   PN = "BB13"  !CDS_PN = "BB13";
"RSVD<170>":   PN = "BA82"  !CDS_PN = "BA82";
"RSVD<171>":   PN = "BA78"  !CDS_PN = "BA78";
"RSVD<255>":   PN = "AY83"  !CDS_PN = "AY83";
BODY = "SKX_EXT_B","I16": #LOCATION = "U5D1" !CDS_LOCATION = "U5D1" #SEC = "17" !CDS_SEC = "17";
"RSVD<81>":   PN = "CL24"  !CDS_PN = "CL24";
"RSVD<82>":   PN = "CK77"  !CDS_PN = "CK77";
"RSVD<83>":   PN = "CK25"  !CDS_PN = "CK25";
"RSVD<84>":   PN = "CK23"  !CDS_PN = "CK23";
"RSVD<85>":   PN = "CK19"  !CDS_PN = "CK19";
"RSVD<86>":   PN = "CJ26"  !CDS_PN = "CJ26";
"RSVD<87>":   PN = "CJ24"  !CDS_PN = "CJ24";
"RSVD<88>":   PN = "CJ22"  !CDS_PN = "CJ22";
"RSVD<89>":   PN = "CJ20"  !CDS_PN = "CJ20";
"RSVD<90>":   PN = "CH77"  !CDS_PN = "CH77";
"RSVD<91>":   PN = "CH25"  !CDS_PN = "CH25";
"TEST_6":   PN = "AR16"  !CDS_PN = "AR16";
"TEST_7":   PN = "AU18"  !CDS_PN = "AU18";
"TEST_8":   PN = "AW16"  !CDS_PN = "AW16";
"TEST_9":   PN = "AW20"  !CDS_PN = "AW20";
"TEST_10":   PN = "AW22"  !CDS_PN = "AW22";
DRAWING = "@baseboard_fab2_lib.baseboard_fab2(sch_1):page37";
BODY = "RES","I303": #LOCATION = "R5D5" !CDS_LOCATION = "R5D5" #SEC = "1" !CDS_SEC = "1";
"A":   PN = "1"  !CDS_PN = "1";
"B":   PN = "2"  !CDS_PN = "2";
BODY = "RES","I309": #LOCATION = "R5P1" !CDS_LOCATION = "R5P1" #SEC = "1" !CDS_SEC = "1";
"A":   PN = "1"  !CDS_PN = "1";
"B":   PN = "2"  !CDS_PN = "2";
BODY = "SKX_EXT_B","I310": #LOCATION = "U5D1" !CDS_LOCATION = "U5D1" #SEC = "18" !CDS_SEC = "18";
"VCCIN<130>":   PN = "BN78"  !CDS_PN = "BN78";
"VCCIN<131>":   PN = "BN76"  !CDS_PN = "BN76";
"VCCIN<132>":   PN = "BN74"  !CDS_PN = "BN74";
"VCCIN<133>":   PN = "BN72"  !CDS_PN = "BN72";
"VCCIN<134>":   PN = "BN70"  !CDS_PN = "BN70";
"VCCIN<135>":   PN = "BN68"  !CDS_PN = "BN68";
"VCCIN<136>":   PN = "BN66"  !CDS_PN = "BN66";
"VCCIN<137>":   PN = "BN64"  !CDS_PN = "BN64";
"VCCIN<138>":   PN = "BN62"  !CDS_PN = "BN62";
"VCCIN<139>":   PN = "BN60"  !CDS_PN = "BN60";
"VCCIN<140>":   PN = "BM83"  !CDS_PN = "BM83";
"VCCIN<141>":   PN = "BM81"  !CDS_PN = "BM81";
"VCCIN<142>":   PN = "BM79"  !CDS_PN = "BM79";
"VCCIN<143>":   PN = "BM77"  !CDS_PN = "BM77";
"VCCIN<144>":   PN = "BM75"  !CDS_PN = "BM75";
"VCCIN<145>":   PN = "BM73"  !CDS_PN = "BM73";
"VCCIN<146>":   PN = "BM71"  !CDS_PN = "BM71";
"VCCIN<147>":   PN = "BM69"  !CDS_PN = "BM69";
"VCCIN<148>":   PN = "BM67"  !CDS_PN = "BM67";
"VCCIN<149>":   PN = "BM65"  !CDS_PN = "BM65";
"VCCIN<150>":   PN = "BM63"  !CDS_PN = "BM63";
"VCCIN<151>":   PN = "BM61"  !CDS_PN = "BM61";
"VCCIN<152>":   PN = "BL84"  !CDS_PN = "BL84";
"VCCIN<153>":   PN = "BL62"  !CDS_PN = "BL62";
"VCCIN<154>":   PN = "BL60"  !CDS_PN = "BL60";
"VCCIN<155>":   PN = "BK83"  !CDS_PN = "BK83";
"VCCIN<156>":   PN = "BK81"  !CDS_PN = "BK81";
"VCCIN<157>":   PN = "BK79"  !CDS_PN = "BK79";
"VCCIN<158>":   PN = "BK77"  !CDS_PN = "BK77";
"VCCIN<159>":   PN = "BK75"  !CDS_PN = "BK75";
"VCCIN<160>":   PN = "BK73"  !CDS_PN = "BK73";
"VCCIN<161>":   PN = "BK71"  !CDS_PN = "BK71";
"VCCIN<162>":   PN = "BK69"  !CDS_PN = "BK69";
"VCCIN<163>":   PN = "BK67"  !CDS_PN = "BK67";
"VCCIN<164>":   PN = "BK65"  !CDS_PN = "BK65";
"VCCIN<165>":   PN = "BK63"  !CDS_PN = "BK63";
"VCCIN<166>":   PN = "BK61"  !CDS_PN = "BK61";
"VCCIN<167>":   PN = "BJ84"  !CDS_PN = "BJ84";
"VCCIN<168>":   PN = "BJ82"  !CDS_PN = "BJ82";
"VCCIN<169>":   PN = "BJ80"  !CDS_PN = "BJ80";
"VCCIN<170>":   PN = "BJ78"  !CDS_PN = "BJ78";
"VCCIN<171>":   PN = "BJ76"  !CDS_PN = "BJ76";
"VCCIN<172>":   PN = "BJ74"  !CDS_PN = "BJ74";
"VCCIN<173>":   PN = "BJ72"  !CDS_PN = "BJ72";
"VCCIN<174>":   PN = "BJ70"  !CDS_PN = "BJ70";
"VCCIN<175>":   PN = "BJ68"  !CDS_PN = "BJ68";
"VCCIN<176>":   PN = "BJ66"  !CDS_PN = "BJ66";
"VCCIN<177>":   PN = "BJ64"  !CDS_PN = "BJ64";
"VCCIN<178>":   PN = "BJ62"  !CDS_PN = "BJ62";
"VCCIN<179>":   PN = "BJ60"  !CDS_PN = "BJ60";
"VCCIN<180>":   PN = "BH83"  !CDS_PN = "BH83";
"VCCIN<181>":   PN = "BH81"  !CDS_PN = "BH81";
"VCCIN<182>":   PN = "BH79"  !CDS_PN = "BH79";
"VCCIN<183>":   PN = "BH77"  !CDS_PN = "BH77";
"VCCIN<184>":   PN = "BH75"  !CDS_PN = "BH75";
"VCCIN<185>":   PN = "BH73"  !CDS_PN = "BH73";
"VCCIN<186>":   PN = "BH71"  !CDS_PN = "BH71";
"VCCIN<187>":   PN = "BH69"  !CDS_PN = "BH69";
"VCCIN<188>":   PN = "BH67"  !CDS_PN = "BH67";
"VCCIN<189>":   PN = "BH65"  !CDS_PN = "BH65";
"VCCIN<190>":   PN = "BH63"  !CDS_PN = "BH63";
"VCCIN<191>":   PN = "BH61"  !CDS_PN = "BH61";
"VCCIN<192>":   PN = "BG84"  !CDS_PN = "BG84";
"VCCIN<193>":   PN = "BG70"  !CDS_PN = "BG70";
"VCCIN<194>":   PN = "BG68"  !CDS_PN = "BG68";
"VCCIN<195>":   PN = "BG66"  !CDS_PN = "BG66";
"VCCIN<196>":   PN = "BG64"  !CDS_PN = "BG64";
"VCCIN<197>":   PN = "BG62"  !CDS_PN = "BG62";
"VCCIN<198>":   PN = "BG60"  !CDS_PN = "BG60";
"VCCIN<199>":   PN = "BF85"  !CDS_PN = "BF85";
"VCCIN<200>":   PN = "BF83"  !CDS_PN = "BF83";
"VCCIN<201>":   PN = "BF81"  !CDS_PN = "BF81";
"VCCIN<202>":   PN = "BF79"  !CDS_PN = "BF79";
"VCCIN<203>":   PN = "BF77"  !CDS_PN = "BF77";
"VCCIN<204>":   PN = "BF75"  !CDS_PN = "BF75";
"VCCIN<205>":   PN = "BF73"  !CDS_PN = "BF73";
"VCCIN<206>":   PN = "BF61"  !CDS_PN = "BF61";
"VCCIN<207>":   PN = "BE84"  !CDS_PN = "BE84";
"VCCIN<208>":   PN = "BE82"  !CDS_PN = "BE82";
"VCCIN<209>":   PN = "BE80"  !CDS_PN = "BE80";
"VCCIN<210>":   PN = "BE78"  !CDS_PN = "BE78";
"VCCIN<211>":   PN = "BE76"  !CDS_PN = "BE76";
"VCCIN<212>":   PN = "BE74"  !CDS_PN = "BE74";
"VCCIN<213>":   PN = "BE72"  !CDS_PN = "BE72";
"VCCIN<214>":   PN = "BE62"  !CDS_PN = "BE62";
"VCCIN<215>":   PN = "BE60"  !CDS_PN = "BE60";
"VCCIN<216>":   PN = "BD85"  !CDS_PN = "BD85";
"VCCIN<217>":   PN = "BD83"  !CDS_PN = "BD83";
"VCCIN<218>":   PN = "BD81"  !CDS_PN = "BD81";
"VCCIN<219>":   PN = "BD79"  !CDS_PN = "BD79";
"VCCIN<220>":   PN = "BD77"  !CDS_PN = "BD77";
"VCCIN<221>":   PN = "BD75"  !CDS_PN = "BD75";
"VCCIN<222>":   PN = "BD73"  !CDS_PN = "BD73";
"VCCIN<223>":   PN = "BD61"  !CDS_PN = "BD61";
"VCCIN<224>":   PN = "BC84"  !CDS_PN = "BC84";
"VCCIN<225>":   PN = "BC62"  !CDS_PN = "BC62";
"VCCIN<226>":   PN = "BC60"  !CDS_PN = "BC60";
"VCCIN<227>":   PN = "BB85"  !CDS_PN = "BB85";
"VCCIN<228>":   PN = "BB61"  !CDS_PN = "BB61";
"VCCIN<229>":   PN = "BA60"  !CDS_PN = "BA60";
"VCCIN<230>":   PN = "AY61"  !CDS_PN = "AY61";
"VCCIN<231>":   PN = "AW60"  !CDS_PN = "AW60";
"VCCIN<232>":   PN = "AV61"  !CDS_PN = "AV61";
"VCCIN<233>":   PN = "AV59"  !CDS_PN = "AV59";
"VCCIN<234>":   PN = "AU60"  !CDS_PN = "AU60";
"VCCIN<235>":   PN = "AU58"  !CDS_PN = "AU58";
"VCCIN<236>":   PN = "AT59"  !CDS_PN = "AT59";
"VCCIN<237>":   PN = "AT57"  !CDS_PN = "AT57";
"VCCIN<238>":   PN = "AR58"  !CDS_PN = "AR58";
"VCCIN<239>":   PN = "AR56"  !CDS_PN = "AR56";
"VCCIN<240>":   PN = "AP57"  !CDS_PN = "AP57";
"VCCIN<241>":   PN = "AP55"  !CDS_PN = "AP55";
"VCCIN<242>":   PN = "AN56"  !CDS_PN = "AN56";
"VCCIN<243>":   PN = "AN54"  !CDS_PN = "AN54";
"VCCIN<244>":   PN = "AN32"  !CDS_PN = "AN32";
"VCCIN<245>":   PN = "AM55"  !CDS_PN = "AM55";
"VCCIN<246>":   PN = "AM53"  !CDS_PN = "AM53";
"VCCIN<247>":   PN = "AM33"  !CDS_PN = "AM33";
"VCCIN<248>":   PN = "AL54"  !CDS_PN = "AL54";
"VCCIN<249>":   PN = "AL52"  !CDS_PN = "AL52";
"VCCIN<250>":   PN = "AL50"  !CDS_PN = "AL50";
"VCCIN<251>":   PN = "AL48"  !CDS_PN = "AL48";
"VCCIN<252>":   PN = "AL46"  !CDS_PN = "AL46";
"VCCIN<253>":   PN = "AL34"  !CDS_PN = "AL34";
"VCCIN<254>":   PN = "AK53"  !CDS_PN = "AK53";
"VCCIN<255>":   PN = "AK51"  !CDS_PN = "AK51";
"VCCIN<256>":   PN = "AK49"  !CDS_PN = "AK49";
"VCCIN<257>":   PN = "AK47"  !CDS_PN = "AK47";
"VCCIN<258>":   PN = "AK45"  !CDS_PN = "AK45";
"VCCIN<259>":   PN = "AK35"  !CDS_PN = "AK35";
"VCCIN<260>":   PN = "AJ36"  !CDS_PN = "AJ36";
"VCCIN<261>":   PN = "AH41"  !CDS_PN = "AH41";
"VCCIN<262>":   PN = "AH39"  !CDS_PN = "AH39";
"VCCIN<263>":   PN = "AH37"  !CDS_PN = "AH37";
"VCCIN<264>":   PN = "AG42"  !CDS_PN = "AG42";
"VCCIN<265>":   PN = "AG40"  !CDS_PN = "AG40";
"VCCIN<266>":   PN = "AG38"  !CDS_PN = "AG38";
"VCCIN<267>":   PN = "AF43"  !CDS_PN = "AF43";
BODY = "SKX_EXT_B","I311": #LOCATION = "U5D1" !CDS_LOCATION = "U5D1" #SEC = "19" !CDS_SEC = "19";
"VCCIN<0>":   PN = "CY49"  !CDS_PN = "CY49";
"VCCIN<1>":   PN = "CY47"  !CDS_PN = "CY47";
"VCCIN<2>":   PN = "CW50"  !CDS_PN = "CW50";
"VCCIN<3>":   PN = "CW48"  !CDS_PN = "CW48";
"VCCIN<4>":   PN = "CW46"  !CDS_PN = "CW46";
"VCCIN<5>":   PN = "CV51"  !CDS_PN = "CV51";
"VCCIN<6>":   PN = "CU54"  !CDS_PN = "CU54";
"VCCIN<7>":   PN = "CU52"  !CDS_PN = "CU52";
"VCCIN<8>":   PN = "CU42"  !CDS_PN = "CU42";
"VCCIN<9>":   PN = "CU40"  !CDS_PN = "CU40";
"VCCIN<10>":   PN = "CU38"  !CDS_PN = "CU38";
"VCCIN<11>":   PN = "CT55"  !CDS_PN = "CT55";
"VCCIN<12>":   PN = "CT53"  !CDS_PN = "CT53";
"VCCIN<13>":   PN = "CT41"  !CDS_PN = "CT41";
"VCCIN<14>":   PN = "CT39"  !CDS_PN = "CT39";
"VCCIN<15>":   PN = "CT37"  !CDS_PN = "CT37";
"VCCIN<16>":   PN = "CR56"  !CDS_PN = "CR56";
"VCCIN<17>":   PN = "CR54"  !CDS_PN = "CR54";
"VCCIN<18>":   PN = "CR34"  !CDS_PN = "CR34";
"VCCIN<19>":   PN = "CP57"  !CDS_PN = "CP57";
"VCCIN<20>":   PN = "CP55"  !CDS_PN = "CP55";
"VCCIN<21>":   PN = "CP33"  !CDS_PN = "CP33";
"VCCIN<22>":   PN = "CN58"  !CDS_PN = "CN58";
"VCCIN<23>":   PN = "CN56"  !CDS_PN = "CN56";
"VCCIN<24>":   PN = "CM59"  !CDS_PN = "CM59";
"VCCIN<25>":   PN = "CM57"  !CDS_PN = "CM57";
"VCCIN<26>":   PN = "CL60"  !CDS_PN = "CL60";
"VCCIN<27>":   PN = "CL58"  !CDS_PN = "CL58";
"VCCIN<28>":   PN = "CK61"  !CDS_PN = "CK61";
"VCCIN<29>":   PN = "CK59"  !CDS_PN = "CK59";
"VCCIN<30>":   PN = "CJ60"  !CDS_PN = "CJ60";
"VCCIN<31>":   PN = "CH85"  !CDS_PN = "CH85";
"VCCIN<32>":   PN = "CH61"  !CDS_PN = "CH61";
"VCCIN<33>":   PN = "CG84"  !CDS_PN = "CG84";
"VCCIN<34>":   PN = "CG60"  !CDS_PN = "CG60";
"VCCIN<35>":   PN = "CF85"  !CDS_PN = "CF85";
"VCCIN<36>":   PN = "CF61"  !CDS_PN = "CF61";
"VCCIN<37>":   PN = "CE84"  !CDS_PN = "CE84";
"VCCIN<38>":   PN = "CE60"  !CDS_PN = "CE60";
"VCCIN<39>":   PN = "CD85"  !CDS_PN = "CD85";
"VCCIN<40>":   PN = "CD83"  !CDS_PN = "CD83";
"VCCIN<41>":   PN = "CD61"  !CDS_PN = "CD61";
"VCCIN<42>":   PN = "CC84"  !CDS_PN = "CC84";
"VCCIN<43>":   PN = "CC62"  !CDS_PN = "CC62";
"VCCIN<44>":   PN = "CC60"  !CDS_PN = "CC60";
"VCCIN<45>":   PN = "CB83"  !CDS_PN = "CB83";
"VCCIN<46>":   PN = "CB81"  !CDS_PN = "CB81";
"VCCIN<47>":   PN = "CB79"  !CDS_PN = "CB79";
"VCCIN<48>":   PN = "CB77"  !CDS_PN = "CB77";
"VCCIN<49>":   PN = "CB75"  !CDS_PN = "CB75";
"VCCIN<50>":   PN = "CB73"  !CDS_PN = "CB73";
"VCCIN<51>":   PN = "CB61"  !CDS_PN = "CB61";
"VCCIN<52>":   PN = "CA84"  !CDS_PN = "CA84";
"VCCIN<53>":   PN = "CA82"  !CDS_PN = "CA82";
"VCCIN<54>":   PN = "CA80"  !CDS_PN = "CA80";
"VCCIN<55>":   PN = "CA78"  !CDS_PN = "CA78";
"VCCIN<56>":   PN = "CA76"  !CDS_PN = "CA76";
"VCCIN<57>":   PN = "CA74"  !CDS_PN = "CA74";
"VCCIN<58>":   PN = "CA72"  !CDS_PN = "CA72";
"VCCIN<59>":   PN = "CA62"  !CDS_PN = "CA62";
"VCCIN<60>":   PN = "CA60"  !CDS_PN = "CA60";
"VCCIN<61>":   PN = "BY83"  !CDS_PN = "BY83";
"VCCIN<62>":   PN = "BY81"  !CDS_PN = "BY81";
"VCCIN<63>":   PN = "BY79"  !CDS_PN = "BY79";
"VCCIN<64>":   PN = "BY77"  !CDS_PN = "BY77";
"VCCIN<65>":   PN = "BY75"  !CDS_PN = "BY75";
"VCCIN<66>":   PN = "BY73"  !CDS_PN = "BY73";
"VCCIN<67>":   PN = "BY61"  !CDS_PN = "BY61";
"VCCIN<68>":   PN = "BW84"  !CDS_PN = "BW84";
"VCCIN<69>":   PN = "BW70"  !CDS_PN = "BW70";
"VCCIN<70>":   PN = "BW68"  !CDS_PN = "BW68";
"VCCIN<71>":   PN = "BW66"  !CDS_PN = "BW66";
"VCCIN<72>":   PN = "BW64"  !CDS_PN = "BW64";
"VCCIN<73>":   PN = "BW62"  !CDS_PN = "BW62";
"VCCIN<74>":   PN = "BW60"  !CDS_PN = "BW60";
"VCCIN<75>":   PN = "BV83"  !CDS_PN = "BV83";
"VCCIN<76>":   PN = "BV81"  !CDS_PN = "BV81";
"VCCIN<77>":   PN = "BV79"  !CDS_PN = "BV79";
"VCCIN<78>":   PN = "BV77"  !CDS_PN = "BV77";
"VCCIN<79>":   PN = "BV75"  !CDS_PN = "BV75";
"VCCIN<80>":   PN = "BV73"  !CDS_PN = "BV73";
"VCCIN<81>":   PN = "BV71"  !CDS_PN = "BV71";
"VCCIN<82>":   PN = "BV69"  !CDS_PN = "BV69";
"VCCIN<83>":   PN = "BV67"  !CDS_PN = "BV67";
"VCCIN<84>":   PN = "BV65"  !CDS_PN = "BV65";
"VCCIN<85>":   PN = "BV63"  !CDS_PN = "BV63";
"VCCIN<86>":   PN = "BV61"  !CDS_PN = "BV61";
"VCCIN<87>":   PN = "BU84"  !CDS_PN = "BU84";
"VCCIN<88>":   PN = "BU82"  !CDS_PN = "BU82";
"VCCIN<89>":   PN = "BU80"  !CDS_PN = "BU80";
"VCCIN<90>":   PN = "BU78"  !CDS_PN = "BU78";
"VCCIN<91>":   PN = "BU76"  !CDS_PN = "BU76";
"VCCIN<92>":   PN = "BU74"  !CDS_PN = "BU74";
"VCCIN<93>":   PN = "BU72"  !CDS_PN = "BU72";
"VCCIN<94>":   PN = "BU70"  !CDS_PN = "BU70";
"VCCIN<95>":   PN = "BU68"  !CDS_PN = "BU68";
"VCCIN<96>":   PN = "BU66"  !CDS_PN = "BU66";
"VCCIN<97>":   PN = "BU64"  !CDS_PN = "BU64";
"VCCIN<98>":   PN = "BU62"  !CDS_PN = "BU62";
"VCCIN<99>":   PN = "BU60"  !CDS_PN = "BU60";
"VCCIN<100>":   PN = "BT83"  !CDS_PN = "BT83";
"VCCIN<101>":   PN = "BT81"  !CDS_PN = "BT81";
"VCCIN<102>":   PN = "BT79"  !CDS_PN = "BT79";
"VCCIN<103>":   PN = "BT77"  !CDS_PN = "BT77";
"VCCIN<104>":   PN = "BT75"  !CDS_PN = "BT75";
"VCCIN<105>":   PN = "BT73"  !CDS_PN = "BT73";
"VCCIN<106>":   PN = "BT71"  !CDS_PN = "BT71";
"VCCIN<107>":   PN = "BT69"  !CDS_PN = "BT69";
"VCCIN<108>":   PN = "BT67"  !CDS_PN = "BT67";
"VCCIN<109>":   PN = "BT65"  !CDS_PN = "BT65";
"VCCIN<110>":   PN = "BT63"  !CDS_PN = "BT63";
"VCCIN<111>":   PN = "BT61"  !CDS_PN = "BT61";
"VCCIN<112>":   PN = "BR84"  !CDS_PN = "BR84";
"VCCIN<113>":   PN = "BR62"  !CDS_PN = "BR62";
"VCCIN<114>":   PN = "BR60"  !CDS_PN = "BR60";
"VCCIN<115>":   PN = "BP83"  !CDS_PN = "BP83";
"VCCIN<116>":   PN = "BP81"  !CDS_PN = "BP81";
"VCCIN<117>":   PN = "BP79"  !CDS_PN = "BP79";
"VCCIN<118>":   PN = "BP77"  !CDS_PN = "BP77";
"VCCIN<119>":   PN = "BP75"  !CDS_PN = "BP75";
"VCCIN<120>":   PN = "BP73"  !CDS_PN = "BP73";
"VCCIN<121>":   PN = "BP71"  !CDS_PN = "BP71";
"VCCIN<122>":   PN = "BP69"  !CDS_PN = "BP69";
"VCCIN<123>":   PN = "BP67"  !CDS_PN = "BP67";
"VCCIN<124>":   PN = "BP65"  !CDS_PN = "BP65";
"VCCIN<125>":   PN = "BP63"  !CDS_PN = "BP63";
"VCCIN<126>":   PN = "BP61"  !CDS_PN = "BP61";
"VCCIN<127>":   PN = "BN84"  !CDS_PN = "BN84";
"VCCIN<128>":   PN = "BN82"  !CDS_PN = "BN82";
"VCCIN<129>":   PN = "BN80"  !CDS_PN = "BN80";
"VCCIN_SENSE":   PN = "BA86"  !CDS_PN = "BA86";
"VCCINPMAX<0>":   PN = "AW86"  !CDS_PN = "AW86";
"VCCINPMAX<1>":   PN = "AV85"  !CDS_PN = "AV85";
"VSENSEPMAX":   PN = "AD41"  !CDS_PN = "AD41";
"VSS_VCCIN_SENSE":   PN = "AY85"  !CDS_PN = "AY85";
BODY = "RES","I312": #LOCATION = "R5D6" !CDS_LOCATION = "R5D6" #SEC = "1" !CDS_SEC = "1";
"A":   PN = "1"  !CDS_PN = "1";
"B":   PN = "2"  !CDS_PN = "2";
DRAWING = "@baseboard_fab2_lib.baseboard_fab2(sch_1):page38";
BODY = "CAP","I19": #LOCATION = "C6D1" !CDS_LOCATION = "C6D1" #SEC = "1" !CDS_SEC = "1";
"A":   PN = "1"  !CDS_PN = "1";
"B":   PN = "2"  !CDS_PN = "2";
BODY = "SKX_EXT_B","I33": #LOCATION = "U5D1" !CDS_LOCATION = "U5D1" #SEC = "20" !CDS_SEC = "20";
"VCCD012<0>":   PN = "B49"  !CDS_PN = "B49";
"VCCD012<1>":   PN = "B53"  !CDS_PN = "B53";
"VCCD012<2>":   PN = "B59"  !CDS_PN = "B59";
"VCCD012<3>":   PN = "E46"  !CDS_PN = "E46";
"VCCD012<4>":   PN = "E48"  !CDS_PN = "E48";
"VCCD012<5>":   PN = "E50"  !CDS_PN = "E50";
"VCCD012<6>":   PN = "E52"  !CDS_PN = "E52";
"VCCD012<7>":   PN = "E54"  !CDS_PN = "E54";
"VCCD012<8>":   PN = "E56"  !CDS_PN = "E56";
"VCCD012<9>":   PN = "E58"  !CDS_PN = "E58";
"VCCD012<10>":   PN = "E60"  !CDS_PN = "E60";
"VCCD012<11>":   PN = "E62"  !CDS_PN = "E62";
"VCCD012<12>":   PN = "E64"  !CDS_PN = "E64";
"VCCD012<13>":   PN = "L46"  !CDS_PN = "L46";
"VCCD012<14>":   PN = "L48"  !CDS_PN = "L48";
"VCCD012<15>":   PN = "L50"  !CDS_PN = "L50";
"VCCD012<16>":   PN = "L52"  !CDS_PN = "L52";
"VCCD012<17>":   PN = "L54"  !CDS_PN = "L54";
"VCCD012<18>":   PN = "L56"  !CDS_PN = "L56";
"VCCD012<19>":   PN = "L58"  !CDS_PN = "L58";
"VCCD012<20>":   PN = "L60"  !CDS_PN = "L60";
"VCCD012<21>":   PN = "L62"  !CDS_PN = "L62";
"VCCD012<22>":   PN = "N64"  !CDS_PN = "N64";
"VCCD012<23>":   PN = "U46"  !CDS_PN = "U46";
"VCCD012<24>":   PN = "U48"  !CDS_PN = "U48";
"VCCD012<25>":   PN = "U50"  !CDS_PN = "U50";
"VCCD012<26>":   PN = "U52"  !CDS_PN = "U52";
"VCCD012<27>":   PN = "U54"  !CDS_PN = "U54";
"VCCD012<28>":   PN = "U56"  !CDS_PN = "U56";
"VCCD012<29>":   PN = "U58"  !CDS_PN = "U58";
"VCCD012<30>":   PN = "U60"  !CDS_PN = "U60";
"VCCD012<31>":   PN = "U62"  !CDS_PN = "U62";
"VCCD012<32>":   PN = "W64"  !CDS_PN = "W64";
"VCCD012<33>":   PN = "Y45"  !CDS_PN = "Y45";
"VCCD012<34>":   PN = "Y47"  !CDS_PN = "Y47";
"VCCD012<35>":   PN = "Y49"  !CDS_PN = "Y49";
"VCCD012<36>":   PN = "Y51"  !CDS_PN = "Y51";
"VCCD012<37>":   PN = "Y53"  !CDS_PN = "Y53";
"VCCD012<38>":   PN = "Y55"  !CDS_PN = "Y55";
"VCCD012<39>":   PN = "Y57"  !CDS_PN = "Y57";
"VCCD012<40>":   PN = "Y59"  !CDS_PN = "Y59";
"VCCD012<41>":   PN = "Y61"  !CDS_PN = "Y61";
"VCCD012<42>":   PN = "Y63"  !CDS_PN = "Y63";
"VCCD012<43>":   PN = "AD45"  !CDS_PN = "AD45";
"VCCD012<44>":   PN = "AF55"  !CDS_PN = "AF55";
"VCCD012<45>":   PN = "AF57"  !CDS_PN = "AF57";
"VCCD012<46>":   PN = "AF59"  !CDS_PN = "AF59";
"VCCD012<47>":   PN = "AF61"  !CDS_PN = "AF61";
"VCCD012<48>":   PN = "AF63"  !CDS_PN = "AF63";
"VCCD012<49>":   PN = "D45"  !CDS_PN = "D45";
"VCCD012<50>":   PN = "C46"  !CDS_PN = "C46";
"VCCD012<51>":   PN = "B47"  !CDS_PN = "B47";
"VCCD345<0>":   PN = "EF59"  !CDS_PN = "EF59";
"VCCD345<1>":   PN = "EF53"  !CDS_PN = "EF53";
"VCCD345<2>":   PN = "EF49"  !CDS_PN = "EF49";
"VCCD345<3>":   PN = "EC62"  !CDS_PN = "EC62";
"VCCD345<4>":   PN = "EC60"  !CDS_PN = "EC60";
"VCCD345<5>":   PN = "EC58"  !CDS_PN = "EC58";
"VCCD345<6>":   PN = "EC56"  !CDS_PN = "EC56";
"VCCD345<7>":   PN = "EC54"  !CDS_PN = "EC54";
"VCCD345<8>":   PN = "EC52"  !CDS_PN = "EC52";
"VCCD345<9>":   PN = "EC50"  !CDS_PN = "EC50";
"VCCD345<10>":   PN = "EC48"  !CDS_PN = "EC48";
"VCCD345<11>":   PN = "EC46"  !CDS_PN = "EC46";
"VCCD345<12>":   PN = "DU64"  !CDS_PN = "DU64";
"VCCD345<13>":   PN = "DU62"  !CDS_PN = "DU62";
"VCCD345<14>":   PN = "DU60"  !CDS_PN = "DU60";
"VCCD345<15>":   PN = "DU58"  !CDS_PN = "DU58";
"VCCD345<16>":   PN = "DU56"  !CDS_PN = "DU56";
"VCCD345<17>":   PN = "DU54"  !CDS_PN = "DU54";
"VCCD345<18>":   PN = "DU52"  !CDS_PN = "DU52";
"VCCD345<19>":   PN = "DU50"  !CDS_PN = "DU50";
"VCCD345<20>":   PN = "DU48"  !CDS_PN = "DU48";
"VCCD345<21>":   PN = "DU46"  !CDS_PN = "DU46";
"VCCD345<22>":   PN = "DL62"  !CDS_PN = "DL62";
"VCCD345<23>":   PN = "DL60"  !CDS_PN = "DL60";
"VCCD345<24>":   PN = "DL58"  !CDS_PN = "DL58";
"VCCD345<25>":   PN = "DL56"  !CDS_PN = "DL56";
"VCCD345<26>":   PN = "DL54"  !CDS_PN = "DL54";
"VCCD345<27>":   PN = "DL52"  !CDS_PN = "DL52";
"VCCD345<28>":   PN = "DL50"  !CDS_PN = "DL50";
"VCCD345<29>":   PN = "DL48"  !CDS_PN = "DL48";
"VCCD345<30>":   PN = "DL46"  !CDS_PN = "DL46";
"VCCD345<31>":   PN = "DJ64"  !CDS_PN = "DJ64";
"VCCD345<32>":   PN = "DH63"  !CDS_PN = "DH63";
"VCCD345<33>":   PN = "DH61"  !CDS_PN = "DH61";
"VCCD345<34>":   PN = "DH59"  !CDS_PN = "DH59";
"VCCD345<35>":   PN = "DH57"  !CDS_PN = "DH57";
"VCCD345<36>":   PN = "DH55"  !CDS_PN = "DH55";
"VCCD345<37>":   PN = "DH53"  !CDS_PN = "DH53";
"VCCD345<38>":   PN = "DH51"  !CDS_PN = "DH51";
"VCCD345<39>":   PN = "DH49"  !CDS_PN = "DH49";
"VCCD345<40>":   PN = "DH47"  !CDS_PN = "DH47";
"VCCD345<41>":   PN = "DH45"  !CDS_PN = "DH45";
"VCCD345<42>":   PN = "DD45"  !CDS_PN = "DD45";
"VCCD345<43>":   PN = "DB63"  !CDS_PN = "DB63";
"VCCD345<44>":   PN = "DB61"  !CDS_PN = "DB61";
"VCCD345<45>":   PN = "DB59"  !CDS_PN = "DB59";
"VCCD345<46>":   PN = "DB57"  !CDS_PN = "DB57";
"VCCD345<47>":   PN = "DB55"  !CDS_PN = "DB55";
"VCCD345<48>":   PN = "DB53"  !CDS_PN = "DB53";
"VCCD345<49>":   PN = "EF45"  !CDS_PN = "EF45";
"VCCD345<50>":   PN = "EE44"  !CDS_PN = "EE44";
BODY = "SKX_EXT_B","I34": #LOCATION = "U5D1" !CDS_LOCATION = "U5D1" #SEC = "21" !CDS_SEC = "21";
"CD_VCC_CORE<0>":   PN = "BL14"  !CDS_PN = "BL14";
"CD_VCC_CORE<1>":   PN = "BK15"  !CDS_PN = "BK15";
"CD_VCC_CORE<2>":   PN = "BK13"  !CDS_PN = "BK13";
"CD_VCC_CORE<3>":   PN = "BJ14"  !CDS_PN = "BJ14";
"CD_VCC_CORE<4>":   PN = "BJ12"  !CDS_PN = "BJ12";
"CD_VCC_CORE<5>":   PN = "BH13"  !CDS_PN = "BH13";
"CD_VCC_CORE<6>":   PN = "BG14"  !CDS_PN = "BG14";
"CD_VCC_CORE<7>":   PN = "BG12"  !CDS_PN = "BG12";
"CD_VCC_CORE<8>":   PN = "BF13"  !CDS_PN = "BF13";
"CD_VCC_CORE<9>":   PN = "BF11"  !CDS_PN = "BF11";
"CD_VCC_CORE<10>":   PN = "BE14"  !CDS_PN = "BE14";
"CD_VCC_CORE<11>":   PN = "BE12"  !CDS_PN = "BE12";
"CD_VCC_CORE<12>":   PN = "BD13"  !CDS_PN = "BD13";
"CD_VCCIN<0>":   PN = "BT27"  !CDS_PN = "BT27";
"CD_VCCIN<1>":   PN = "BU26"  !CDS_PN = "BU26";
"CD_VCCIN<2>":   PN = "BV27"  !CDS_PN = "BV27";
"CD_VCCIN<3>":   PN = "BY27"  !CDS_PN = "BY27";
"CD_VCCP<0>":   PN = "BV15"  !CDS_PN = "BV15";
"CD_VCCP<1>":   PN = "BV13"  !CDS_PN = "BV13";
"CD_VCCP<2>":   PN = "BV11"  !CDS_PN = "BV11";
"CD_VCCP<3>":   PN = "BU14"  !CDS_PN = "BU14";
"CD_VCCP<4>":   PN = "BU12"  !CDS_PN = "BU12";
"CD_VCCP<5>":   PN = "BT15"  !CDS_PN = "BT15";
"CD_VCCP<6>":   PN = "BT13"  !CDS_PN = "BT13";
"CD_VCCP<7>":   PN = "BT11"  !CDS_PN = "BT11";
"CD_VCCP<8>":   PN = "BR14"  !CDS_PN = "BR14";
"CD_VCCP<9>":   PN = "BR12"  !CDS_PN = "BR12";
"CD_VCCP<10>":   PN = "BP15"  !CDS_PN = "BP15";
"CD_VCCP<11>":   PN = "BP13"  !CDS_PN = "BP13";
"CD_VCCP<12>":   PN = "BP11"  !CDS_PN = "BP11";
"CD_VCCP<13>":   PN = "BN14"  !CDS_PN = "BN14";
"CD_VCCP<14>":   PN = "BN12"  !CDS_PN = "BN12";
"CD_VCCP<15>":   PN = "BM11"  !CDS_PN = "BM11";
"CD_VPP<0>":   PN = "B11"  !CDS_PN = "B11";
"CD_VPP<1>":   PN = "A12"  !CDS_PN = "A12";
"CD_VPP<2>":   PN = "A10"  !CDS_PN = "A10";
"CD_VPP<3>":   PN = "A8"  !CDS_PN = "A8";
"VCC33":   PN = "CY55"  !CDS_PN = "CY55";
"VCCIO<20>":   PN = "CM15"  !CDS_PN = "CM15";
"VCCIO<21>":   PN = "CL12"  !CDS_PN = "CL12";
"VCCIO<22>":   PN = "CK5"  !CDS_PN = "CK5";
"VCCIO<23>":   PN = "CV7"  !CDS_PN = "CV7";
"VCCIO<24>":   PN = "CH9"  !CDS_PN = "CH9";
"VCCIO<25>":   PN = "D7"  !CDS_PN = "D7";
"VCCIO<26>":   PN = "CE18"  !CDS_PN = "CE18";
"VCCIO<27>":   PN = "CD9"  !CDS_PN = "CD9";
"VCCIO<28>":   PN = "CB17"  !CDS_PN = "CB17";
"VCCIO<29>":   PN = "CB13"  !CDS_PN = "CB13";
"VCCIO<30>":   PN = "BP25"  !CDS_PN = "BP25";
"VCCIO<31>":   PN = "BJ24"  !CDS_PN = "BJ24";
"VCCIO<32>":   PN = "BF23"  !CDS_PN = "BF23";
"VCCIO<33>":   PN = "DA14"  !CDS_PN = "DA14";
"VCCIO<34>":   PN = "BB5"  !CDS_PN = "BB5";
"VCCIO<35>":   PN = "BA24"  !CDS_PN = "BA24";
"VCCIO<36>":   PN = "AY11"  !CDS_PN = "AY11";
"VCCIO<37>":   PN = "AW6"  !CDS_PN = "AW6";
"VCCIO<38>":   PN = "AT11"  !CDS_PN = "AT11";
"VCCIO<39>":   PN = "DD7"  !CDS_PN = "DD7";
"VCCIO<40>":   PN = "AN10"  !CDS_PN = "AN10";
"VCCIO<41>":   PN = "DF13"  !CDS_PN = "DF13";
"VCCIO<42>":   PN = "AH9"  !CDS_PN = "AH9";
"VCCIO<43>":   PN = "AC4"  !CDS_PN = "AC4";
"VCCIO<44>":   PN = "AC20"  !CDS_PN = "AC20";
"VCCIO<45>":   PN = "AA10"  !CDS_PN = "AA10";
"VCCIO<46>":   PN = "W6"  !CDS_PN = "W6";
"VCCIO<47>":   PN = "W4"  !CDS_PN = "W4";
"VCCIO<48>":   PN = "DF21"  !CDS_PN = "DF21";
"VCCIO<49>":   PN = "U14"  !CDS_PN = "U14";
"VCCIO<50>":   PN = "T3"  !CDS_PN = "T3";
"VCCIO<51>":   PN = "P5"  !CDS_PN = "P5";
"VCCIO<52>":   PN = "M21"  !CDS_PN = "M21";
"VCCIO<53>":   PN = "M11"  !CDS_PN = "M11";
"VCCIO<54>":   PN = "DG8"  !CDS_PN = "DG8";
"VCCIO<55>":   PN = "DH7"  !CDS_PN = "DH7";
"VCCIO<56>":   PN = "L16"  !CDS_PN = "L16";
"VCCIO<57>":   PN = "L14"  !CDS_PN = "L14";
"VCCIO<58>":   PN = "J10"  !CDS_PN = "J10";
"VCCIO<59>":   PN = "H13"  !CDS_PN = "H13";
"VCCIO<60>":   PN = "DJ16"  !CDS_PN = "DJ16";
"VCCIO<61>":   PN = "DM17"  !CDS_PN = "DM17";
"VCCIO<62>":   PN = "DN8"  !CDS_PN = "DN8";
"VCCIO<63>":   PN = "DP19"  !CDS_PN = "DP19";
"VCCIO<64>":   PN = "DR10"  !CDS_PN = "DR10";
"VCCIO<65>":   PN = "DR2"  !CDS_PN = "DR2";
"VCCIO<66>":   PN = "DU20"  !CDS_PN = "DU20";
"VCCIO<67>":   PN = "EA12"  !CDS_PN = "EA12";
"VCCIO<68>":   PN = "EB15"  !CDS_PN = "EB15";
"VCCIO<69>":   PN = "J2"  !CDS_PN = "J2";
"VCCIO<70>":   PN = "K15"  !CDS_PN = "K15";
"VCCIO<71>":   PN = "M7"  !CDS_PN = "M7";
"VCCIO<72>":   PN = "M9"  !CDS_PN = "M9";
"VCCIO<73>":   PN = "N18"  !CDS_PN = "N18";
"VCCIO<74>":   PN = "W10"  !CDS_PN = "W10";
"VCCIO<75>":   PN = "BC26"  !CDS_PN = "BC26";
"VCCIO<76>":   PN = "BB27"  !CDS_PN = "BB27";
"VCCIO<77>":   PN = "BA26"  !CDS_PN = "BA26";
"VCCIO<78>":   PN = "AY27"  !CDS_PN = "AY27";
"VCCIO<79>":   PN = "AW26"  !CDS_PN = "AW26";
"VCCIO<80>":   PN = "AV27"  !CDS_PN = "AV27";
"VCCIO<81>":   PN = "CF27"  !CDS_PN = "CF27";
"VCCIO<82>":   PN = "CD27"  !CDS_PN = "CD27";
"VCCIO<83>":   PN = "CC26"  !CDS_PN = "CC26";
"VCCIO<84>":   PN = "CJ28"  !CDS_PN = "CJ28";
"VCCIO<85>":   PN = "CH27"  !CDS_PN = "CH27";
"VCCIO<86>":   PN = "BM27"  !CDS_PN = "BM27";
"VCCIO<87>":   PN = "BL26"  !CDS_PN = "BL26";
"VCCIO<88>":   PN = "BK27"  !CDS_PN = "BK27";
"VCCIO<89>":   PN = "BK25"  !CDS_PN = "BK25";
"VCCIO<90>":   PN = "BJ26"  !CDS_PN = "BJ26";
"VCCIO<91>":   PN = "BH27"  !CDS_PN = "BH27";
"VCCIO<92>":   PN = "BH25"  !CDS_PN = "BH25";
"VCCIO<93>":   PN = "BG26"  !CDS_PN = "BG26";
"VCCIO<94>":   PN = "BF27"  !CDS_PN = "BF27";
"VCCIO<95>":   PN = "AE36"  !CDS_PN = "AE36";
"VCCIO<96>":   PN = "AD37"  !CDS_PN = "AD37";
"VCCIO<97>":   PN = "AC36"  !CDS_PN = "AC36";
"VCCIO<98>":   PN = "AF35"  !CDS_PN = "AF35";
"VCCIO<99>":   PN = "AD35"  !CDS_PN = "AD35";
"VCCIO<100>":   PN = "AE34"  !CDS_PN = "AE34";
"VCCIO<101>":   PN = "AG34"  !CDS_PN = "AG34";
"VCCIO<102>":   PN = "AM29"  !CDS_PN = "AM29";
"VCCIO<103>":   PN = "AL28"  !CDS_PN = "AL28";
"VCCIO<104>":   PN = "AR28"  !CDS_PN = "AR28";
"VCCSA<0>":   PN = "CJ66"  !CDS_PN = "CJ66";
"VCCSA<1>":   PN = "CJ64"  !CDS_PN = "CJ64";
"VCCSA<2>":   PN = "CH75"  !CDS_PN = "CH75";
"VCCSA<3>":   PN = "CH65"  !CDS_PN = "CH65";
"VCCSA<4>":   PN = "CG74"  !CDS_PN = "CG74";
"VCCSA<5>":   PN = "CG66"  !CDS_PN = "CG66";
"VCCSA<6>":   PN = "CG64"  !CDS_PN = "CG64";
"VCCSA<7>":   PN = "CF75"  !CDS_PN = "CF75";
"VCCSA<8>":   PN = "CF73"  !CDS_PN = "CF73";
"VCCSA<9>":   PN = "CF67"  !CDS_PN = "CF67";
"VCCSA<10>":   PN = "CF65"  !CDS_PN = "CF65";
"VCCSA<11>":   PN = "CE74"  !CDS_PN = "CE74";
"VCCSA<12>":   PN = "CE72"  !CDS_PN = "CE72";
"VCCSA<13>":   PN = "CE68"  !CDS_PN = "CE68";
"VCCSA<14>":   PN = "CE66"  !CDS_PN = "CE66";
"VCCSA<15>":   PN = "CE64"  !CDS_PN = "CE64";
"VCCSA<16>":   PN = "CD71"  !CDS_PN = "CD71";
"VCCSA<17>":   PN = "CD69"  !CDS_PN = "CD69";
"VCCSA<18>":   PN = "CD67"  !CDS_PN = "CD67";
"VCCSA<19>":   PN = "CD65"  !CDS_PN = "CD65";
"VCCSA<20>":   PN = "CC70"  !CDS_PN = "CC70";
"VCCSA<21>":   PN = "CC68"  !CDS_PN = "CC68";
"VCCSA<22>":   PN = "CC66"  !CDS_PN = "CC66";
"VCCSA<23>":   PN = "CB69"  !CDS_PN = "CB69";
"VCCSA<24>":   PN = "CB67"  !CDS_PN = "CB67";
"VCCSA<25>":   PN = "CB65"  !CDS_PN = "CB65";
DRAWING = "@baseboard_fab2_lib.baseboard_fab2(sch_1):page39";
BODY = "SKX_EXT_B","I127": #LOCATION = "U5D1" !CDS_LOCATION = "U5D1" #SEC = "22" !CDS_SEC = "22";
"CD_VCC_CORE_SENSE":   PN = "BN16"  !CDS_PN = "BN16";
"CD_VCCP_SENSE<0>":   PN = "BU16"  !CDS_PN = "BU16";
"CD_VCCP_SENSE<1>":   PN = "BT17"  !CDS_PN = "BT17";
"CD_VSS_VCC_CORE_SENSE":   PN = "BL16"  !CDS_PN = "BL16";
"RSVD<0>":   PN = "EF83"  !CDS_PN = "EF83";
"RSVD<1>":   PN = "EF81"  !CDS_PN = "EF81";
"RSVD<2>":   PN = "EF77"  !CDS_PN = "EF77";
"RSVD<3>":   PN = "EF47"  !CDS_PN = "EF47";
"RSVD<4>":   PN = "EE84"  !CDS_PN = "EE84";
"RSVD<5>":   PN = "EE82"  !CDS_PN = "EE82";
"RSVD<6>":   PN = "EE6"  !CDS_PN = "EE6";
"RSVD<7>":   PN = "EE46"  !CDS_PN = "EE46";
"RSVD<8>":   PN = "EE16"  !CDS_PN = "EE16";
"RSVD<9>":   PN = "ED83"  !CDS_PN = "ED83";
"RSVD<10>":   PN = "ED5"  !CDS_PN = "ED5";
"RSVD<11>":   PN = "ED45"  !CDS_PN = "ED45";
"RSVD<12>":   PN = "EC84"  !CDS_PN = "EC84";
"RSVD<13>":   PN = "EC44"  !CDS_PN = "EC44";
"RSVD<14>":   PN = "EC4"  !CDS_PN = "EC4";
"RSVD<15>":   PN = "EC16"  !CDS_PN = "EC16";
"RSVD<16>":   PN = "EB85"  !CDS_PN = "EB85";
"RSVD<17>":   PN = "EB5"  !CDS_PN = "EB5";
"RSVD<18>":   PN = "EB3"  !CDS_PN = "EB3";
"RSVD<19>":   PN = "EA44"  !CDS_PN = "EA44";
"RSVD<20>":   PN = "EA4"  !CDS_PN = "EA4";
"RSVD<21>":   PN = "DY3"  !CDS_PN = "DY3";
"RSVD<22>":   PN = "DW46"  !CDS_PN = "DW46";
"RSVD<23>":   PN = "DW44"  !CDS_PN = "DW44";
"RSVD<24>":   PN = "DV71"  !CDS_PN = "DV71";
"RSVD<25>":   PN = "DV61"  !CDS_PN = "DV61";
"RSVD<26>":   PN = "DU44"  !CDS_PN = "DU44";
"RSVD<27>":   PN = "DT71"  !CDS_PN = "DT71";
"RSVD<28>":   PN = "DR44"  !CDS_PN = "DR44";
"RSVD<29>":   PN = "DP65"  !CDS_PN = "DP65";
"RSVD<30>":   PN = "DP17"  !CDS_PN = "DP17";
"RSVD<31>":   PN = "DN66"  !CDS_PN = "DN66";
"RSVD<32>":   PN = "DN62"  !CDS_PN = "DN62";
"RSVD<33>":   PN = "DM67"  !CDS_PN = "DM67";
"RSVD<34>":   PN = "DL66"  !CDS_PN = "DL66";
"RSVD<35>":   PN = "DL38"  !CDS_PN = "DL38";
"RSVD<36>":   PN = "DK67"  !CDS_PN = "DK67";
"RSVD<37>":   PN = "DK65"  !CDS_PN = "DK65";
"RSVD<38>":   PN = "DK37"  !CDS_PN = "DK37";
"RSVD<39>":   PN = "DK15"  !CDS_PN = "DK15";
"RSVD<40>":   PN = "DJ66"  !CDS_PN = "DJ66";
"RSVD<41>":   PN = "DJ36"  !CDS_PN = "DJ36";
"RSVD<42>":   PN = "DH65"  !CDS_PN = "DH65";
"RSVD<43>":   PN = "DG64"  !CDS_PN = "DG64";
"RSVD<44>":   PN = "DG36"  !CDS_PN = "DG36";
"RSVD<45>":   PN = "DD51"  !CDS_PN = "DD51";
"RSVD<46>":   PN = "DC52"  !CDS_PN = "DC52";
"RSVD<47>":   PN = "DC46"  !CDS_PN = "DC46";
"RSVD<48>":   PN = "DA56"  !CDS_PN = "DA56";
"RSVD<49>":   PN = "DA54"  !CDS_PN = "DA54";
"RSVD<50>":   PN = "DA52"  !CDS_PN = "DA52";
"RSVD<51>":   PN = "DA40"  !CDS_PN = "DA40";
"RSVD<52>":   PN = "DA24"  !CDS_PN = "DA24";
"RSVD<53>":   PN = "CY73"  !CDS_PN = "CY73";
"RSVD<54>":   PN = "CY63"  !CDS_PN = "CY63";
"RSVD<55>":   PN = "CY57"  !CDS_PN = "CY57";
"RSVD<56>":   PN = "CY53"  !CDS_PN = "CY53";
"RSVD<57>":   PN = "CY39"  !CDS_PN = "CY39";
"RSVD<58>":   PN = "CY25"  !CDS_PN = "CY25";
"RSVD<59>":   PN = "CY23"  !CDS_PN = "CY23";
"RSVD<60>":   PN = "CW62"  !CDS_PN = "CW62";
"RSVD<61>":   PN = "CW60"  !CDS_PN = "CW60";
"RSVD<62>":   PN = "CW24"  !CDS_PN = "CW24";
"RSVD<63>":   PN = "CW22"  !CDS_PN = "CW22";
"RSVD<64>":   PN = "CV69"  !CDS_PN = "CV69";
"RSVD<65>":   PN = "CV23"  !CDS_PN = "CV23";
"RSVD<66>":   PN = "CU60"  !CDS_PN = "CU60";
"RSVD<67>":   PN = "CU6"  !CDS_PN = "CU6";
"RSVD<68>":   PN = "CU24"  !CDS_PN = "CU24";
"RSVD<69>":   PN = "CT69"  !CDS_PN = "CT69";
"RSVD<70>":   PN = "CT5"  !CDS_PN = "CT5";
"RSVD<71>":   PN = "CT23"  !CDS_PN = "CT23";
"RSVD<72>":   PN = "CR60"  !CDS_PN = "CR60";
"RSVD<73>":   PN = "CP31"  !CDS_PN = "CP31";
"RSVD<74>":   PN = "CP23"  !CDS_PN = "CP23";
"RSVD<75>":   PN = "CN28"  !CDS_PN = "CN28";
"RSVD<76>":   PN = "CN24"  !CDS_PN = "CN24";
"RSVD<77>":   PN = "CN22"  !CDS_PN = "CN22";
"RSVD<78>":   PN = "CM25"  !CDS_PN = "CM25";
"RSVD<79>":   PN = "CM23"  !CDS_PN = "CM23";
"RSVD<80>":   PN = "CL26"  !CDS_PN = "CL26";
"VCCIO<0>":   PN = "EE10"  !CDS_PN = "EE10";
"VCCIO<1>":   PN = "AE10"  !CDS_PN = "AE10";
"VCCIO<2>":   PN = "AF5"  !CDS_PN = "AF5";
"VCCIO<3>":   PN = "DV11"  !CDS_PN = "DV11";
"VCCIO<4>":   PN = "AM5"  !CDS_PN = "AM5";
"VCCIO<5>":   PN = "AT5"  !CDS_PN = "AT5";
"VCCIO<6>":   PN = "AT7"  !CDS_PN = "AT7";
"VCCIO<7>":   PN = "BE24"  !CDS_PN = "BE24";
"VCCIO<8>":   PN = "DK21"  !CDS_PN = "DK21";
"VCCIO<9>":   PN = "CF5"  !CDS_PN = "CF5";
"VCCIO<10>":   PN = "CG14"  !CDS_PN = "CG14";
"VCCIO<11>":   PN = "CL20"  !CDS_PN = "CL20";
"VCCIO<12>":   PN = "CP13"  !CDS_PN = "CP13";
"VCCIO<13>":   PN = "DE14"  !CDS_PN = "DE14";
"VCCIO<14>":   PN = "DC18"  !CDS_PN = "DC18";
"VCCIO<15>":   PN = "CY17"  !CDS_PN = "CY17";
"VCCIO<16>":   PN = "CU18"  !CDS_PN = "CU18";
"VCCIO<17>":   PN = "CV21"  !CDS_PN = "CV21";
"VCCIO<18>":   PN = "CU12"  !CDS_PN = "CU12";
"VCCIO<19>":   PN = "CN6"  !CDS_PN = "CN6";
"VCCIO_SENSE":   PN = "BH5"  !CDS_PN = "BH5";
"VCCSA_SENSE":   PN = "CE76"  !CDS_PN = "CE76";
"VSS_VCCIO_SENSE":   PN = "BF5"  !CDS_PN = "BF5";
"VSS_VCCSA_SENSE":   PN = "CG76"  !CDS_PN = "CG76";
DRAWING = "@baseboard_fab2_lib.baseboard_fab2(sch_1):page40";
BODY = "SKX_EXT_B","I20": #LOCATION = "U5D1" !CDS_LOCATION = "U5D1" #SEC = "23" !CDS_SEC = "23";
"VSS<1094>":   PN = "J74"  !CDS_PN = "J74";
"VSS<1095>":   PN = "J72"  !CDS_PN = "J72";
"VSS<1096>":   PN = "J40"  !CDS_PN = "J40";
"VSS<1097>":   PN = "J38"  !CDS_PN = "J38";
"VSS<1098>":   PN = "J34"  !CDS_PN = "J34";
"VSS<1099>":   PN = "J32"  !CDS_PN = "J32";
"VSS<1100>":   PN = "J28"  !CDS_PN = "J28";
"VSS<1101>":   PN = "J26"  !CDS_PN = "J26";
"VSS<1102>":   PN = "J22"  !CDS_PN = "J22";
"VSS<1103>":   PN = "J14"  !CDS_PN = "J14";
"VSS<1104>":   PN = "J12"  !CDS_PN = "J12";
"VSS<1105>":   PN = "J4"  !CDS_PN = "J4";
"VSS<1106>":   PN = "DN44"  !CDS_PN = "DN44";
"VSS<1107>":   PN = "H75"  !CDS_PN = "H75";
"VSS<1108>":   PN = "H71"  !CDS_PN = "H71";
"VSS<1109>":   PN = "H65"  !CDS_PN = "H65";
"VSS<1110>":   PN = "H41"  !CDS_PN = "H41";
"VSS<1111>":   PN = "H39"  !CDS_PN = "H39";
"VSS<1112>":   PN = "H37"  !CDS_PN = "H37";
"VSS<1113>":   PN = "H35"  !CDS_PN = "H35";
"VSS<1114>":   PN = "H33"  !CDS_PN = "H33";
"VSS<1115>":   PN = "H31"  !CDS_PN = "H31";
"VSS<1116>":   PN = "H29"  !CDS_PN = "H29";
"VSS<1117>":   PN = "H27"  !CDS_PN = "H27";
"VSS<1118>":   PN = "H25"  !CDS_PN = "H25";
"VSS<1119>":   PN = "H11"  !CDS_PN = "H11";
"VSS<1120>":   PN = "H3"  !CDS_PN = "H3";
"VSS<1121>":   PN = "G82"  !CDS_PN = "G82";
"VSS<1122>":   PN = "G80"  !CDS_PN = "G80";
"VSS<1123>":   PN = "G78"  !CDS_PN = "G78";
"VSS<1124>":   PN = "G76"  !CDS_PN = "G76";
"VSS<1125>":   PN = "G70"  !CDS_PN = "G70";
"VSS<1126>":   PN = "G66"  !CDS_PN = "G66";
"VSS<1127>":   PN = "G42"  !CDS_PN = "G42";
"VSS<1128>":   PN = "G38"  !CDS_PN = "G38";
"VSS<1129>":   PN = "G36"  !CDS_PN = "G36";
"VSS<1130>":   PN = "G32"  !CDS_PN = "G32";
"VSS<1131>":   PN = "G30"  !CDS_PN = "G30";
"VSS<1132>":   PN = "G26"  !CDS_PN = "G26";
"VSS<1133>":   PN = "G24"  !CDS_PN = "G24";
"VSS<1134>":   PN = "G22"  !CDS_PN = "G22";
"VSS<1135>":   PN = "G8"  !CDS_PN = "G8";
"VSS<1136>":   PN = "G4"  !CDS_PN = "G4";
"VSS<1137>":   PN = "F69"  !CDS_PN = "F69";
"VSS<1138>":   PN = "F67"  !CDS_PN = "F67";
"VSS<1139>":   PN = "F43"  !CDS_PN = "F43";
"VSS<1140>":   PN = "F37"  !CDS_PN = "F37";
"VSS<1141>":   PN = "F31"  !CDS_PN = "F31";
"VSS<1142>":   PN = "F25"  !CDS_PN = "F25";
"VSS<1143>":   PN = "F19"  !CDS_PN = "F19";
"VSS<1144>":   PN = "F17"  !CDS_PN = "F17";
"VSS<1145>":   PN = "F5"  !CDS_PN = "F5";
"VSS<1146>":   PN = "E76"  !CDS_PN = "E76";
"VSS<1147>":   PN = "E74"  !CDS_PN = "E74";
"VSS<1148>":   PN = "E72"  !CDS_PN = "E72";
"VSS<1149>":   PN = "E22"  !CDS_PN = "E22";
"VSS<1150>":   PN = "E20"  !CDS_PN = "E20";
"VSS<1151>":   PN = "E18"  !CDS_PN = "E18";
"VSS<1152>":   PN = "E16"  !CDS_PN = "E16";
"VSS<1153>":   PN = "E8"  !CDS_PN = "E8";
"VSS<1154>":   PN = "E6"  !CDS_PN = "E6";
"VSS<1155>":   PN = "D77"  !CDS_PN = "D77";
"VSS<1156>":   PN = "D43"  !CDS_PN = "D43";
"VSS<1157>":   PN = "D41"  !CDS_PN = "D41";
"VSS<1158>":   PN = "D39"  !CDS_PN = "D39";
"VSS<1159>":   PN = "D37"  !CDS_PN = "D37";
"VSS<1160>":   PN = "D35"  !CDS_PN = "D35";
"VSS<1161>":   PN = "D33"  !CDS_PN = "D33";
"VSS<1162>":   PN = "D31"  !CDS_PN = "D31";
"VSS<1163>":   PN = "D29"  !CDS_PN = "D29";
"VSS<1164>":   PN = "D27"  !CDS_PN = "D27";
"VSS<1165>":   PN = "D25"  !CDS_PN = "D25";
"VSS<1166>":   PN = "D13"  !CDS_PN = "D13";
"VSS<1167>":   PN = "D11"  !CDS_PN = "D11";
"VSS<1168>":   PN = "CM27"  !CDS_PN = "CM27";
"VSS<1169>":   PN = "C78"  !CDS_PN = "C78";
"VSS<1170>":   PN = "C76"  !CDS_PN = "C76";
"VSS<1171>":   PN = "C16"  !CDS_PN = "C16";
"VSS<1172>":   PN = "C14"  !CDS_PN = "C14";
"VSS<1173>":   PN = "C12"  !CDS_PN = "C12";
"VSS<1174>":   PN = "C10"  !CDS_PN = "C10";
"VSS<1175>":   PN = "C8"  !CDS_PN = "C8";
"VSS<1176>":   PN = "B75"  !CDS_PN = "B75";
"VSS<1177>":   PN = "B71"  !CDS_PN = "B71";
"VSS<1178>":   PN = "B37"  !CDS_PN = "B37";
"VSS<1179>":   PN = "B31"  !CDS_PN = "B31";
"VSS<1180>":   PN = "B25"  !CDS_PN = "B25";
"VSS<1181>":   PN = "A38"  !CDS_PN = "A38";
"VSS<1182>":   PN = "A36"  !CDS_PN = "A36";
"VSS<1183>":   PN = "A32"  !CDS_PN = "A32";
"VSS<1184>":   PN = "A30"  !CDS_PN = "A30";
"VSS<1185>":   PN = "A26"  !CDS_PN = "A26";
"VSS<1186>":   PN = "AC58"  !CDS_PN = "AC58";
"VSS<1187>":   PN = "AC60"  !CDS_PN = "AC60";
"VSS<1188>":   PN = "AC62"  !CDS_PN = "AC62";
"VSS<1189>":   PN = "AJ4"  !CDS_PN = "AJ4";
"VSS<1190>":   PN = "AR6"  !CDS_PN = "AR6";
"VSS<1191>":   PN = "CG6"  !CDS_PN = "CG6";
"VSS<1192>":   PN = "CW6"  !CDS_PN = "CW6";
"VSS<1193>":   PN = "DE48"  !CDS_PN = "DE48";
"VSS<1194>":   PN = "DE50"  !CDS_PN = "DE50";
"VSS<1195>":   PN = "DE52"  !CDS_PN = "DE52";
"VSS<1196>":   PN = "DE54"  !CDS_PN = "DE54";
"VSS<1197>":   PN = "DE56"  !CDS_PN = "DE56";
"VSS<1198>":   PN = "DE58"  !CDS_PN = "DE58";
"VSS<1199>":   PN = "DE60"  !CDS_PN = "DE60";
"VSS<1200>":   PN = "DE62"  !CDS_PN = "DE62";
"VSS<1201>":   PN = "DL8"  !CDS_PN = "DL8";
"VSS<1202>":   PN = "DN18"  !CDS_PN = "DN18";
"VSS<1203>":   PN = "DP45"  !CDS_PN = "DP45";
"VSS<1204>":   PN = "DP47"  !CDS_PN = "DP47";
"VSS<1205>":   PN = "DP49"  !CDS_PN = "DP49";
"VSS<1206>":   PN = "DP51"  !CDS_PN = "DP51";
"VSS<1207>":   PN = "DP53"  !CDS_PN = "DP53";
"VSS<1208>":   PN = "DP55"  !CDS_PN = "DP55";
"VSS<1209>":   PN = "DP57"  !CDS_PN = "DP57";
"VSS<1210>":   PN = "DP59"  !CDS_PN = "DP59";
"VSS<1211>":   PN = "DP61"  !CDS_PN = "DP61";
"VSS<1212>":   PN = "DP63"  !CDS_PN = "DP63";
"VSS<1213>":   PN = "DP9"  !CDS_PN = "DP9";
"VSS<1214>":   PN = "DV19"  !CDS_PN = "DV19";
"VSS<1215>":   PN = "DY45"  !CDS_PN = "DY45";
"VSS<1216>":   PN = "DY47"  !CDS_PN = "DY47";
"VSS<1217>":   PN = "DY49"  !CDS_PN = "DY49";
"VSS<1218>":   PN = "DY51"  !CDS_PN = "DY51";
"VSS<1219>":   PN = "DY53"  !CDS_PN = "DY53";
"VSS<1220>":   PN = "DY55"  !CDS_PN = "DY55";
"VSS<1221>":   PN = "DY57"  !CDS_PN = "DY57";
"VSS<1222>":   PN = "DY59"  !CDS_PN = "DY59";
"VSS<1223>":   PN = "DY61"  !CDS_PN = "DY61";
"VSS<1224>":   PN = "DY63"  !CDS_PN = "DY63";
"VSS<1225>":   PN = "EA14"  !CDS_PN = "EA14";
"VSS<1226>":   PN = "L8"  !CDS_PN = "L8";
"VSS<1227>":   PN = "V11"  !CDS_PN = "V11";
"VSS<1228>":   PN = "E66"  !CDS_PN = "E66";
"VSS<1229>":   PN = "ED69"  !CDS_PN = "ED69";
"VSS<1230>":   PN = "EE80"  !CDS_PN = "EE80";
"VSS<1231>":   PN = "EE8"  !CDS_PN = "EE8";
"VSS<1232>":   PN = "EE40"  !CDS_PN = "EE40";
"VSS<1233>":   PN = "ED81"  !CDS_PN = "ED81";
"VSS<1234>":   PN = "ED7"  !CDS_PN = "ED7";
"VSS<1235>":   PN = "ED41"  !CDS_PN = "ED41";
"VSS<1236>":   PN = "EC82"  !CDS_PN = "EC82";
"VSS<1237>":   PN = "EC6"  !CDS_PN = "EC6";
"VSS<1238>":   PN = "EC42"  !CDS_PN = "EC42";
"VSS<1239>":   PN = "DW2"  !CDS_PN = "DW2";
"VSS<1240>":   PN = "EB83"  !CDS_PN = "EB83";
"VSS<1241>":   PN = "EA84"  !CDS_PN = "EA84";
"VSS<1242>":   PN = "DY85"  !CDS_PN = "DY85";
"VSS<1243>":   PN = "J86"  !CDS_PN = "J86";
"VSS<1244>":   PN = "E82"  !CDS_PN = "E82";
"VSS<1245>":   PN = "D81"  !CDS_PN = "D81";
"VSS<1246>":   PN = "D3"  !CDS_PN = "D3";
"VSS<1247>":   PN = "C80"  !CDS_PN = "C80";
"VSS<1248>":   PN = "C4"  !CDS_PN = "C4";
"VSS<1249>":   PN = "B79"  !CDS_PN = "B79";
"VSS<1250>":   PN = "B5"  !CDS_PN = "B5";
"VSS<1251>":   PN = "B43"  !CDS_PN = "B43";
"VSS<1252>":   PN = "A42"  !CDS_PN = "A42";
"VSS<1253>":   PN = "B9"  !CDS_PN = "B9";
BODY = "SKX_EXT_B","I21": #LOCATION = "U5D1" !CDS_LOCATION = "U5D1" #SEC = "24" !CDS_SEC = "24";
"VSS<934>":   PN = "AA16"  !CDS_PN = "AA16";
"VSS<935>":   PN = "AA4"  !CDS_PN = "AA4";
"VSS<936>":   PN = "Y85"  !CDS_PN = "Y85";
"VSS<937>":   PN = "Y83"  !CDS_PN = "Y83";
"VSS<938>":   PN = "Y81"  !CDS_PN = "Y81";
"VSS<939>":   PN = "Y79"  !CDS_PN = "Y79";
"VSS<940>":   PN = "Y73"  !CDS_PN = "Y73";
"VSS<941>":   PN = "Y71"  !CDS_PN = "Y71";
"VSS<942>":   PN = "Y9"  !CDS_PN = "Y9";
"VSS<943>":   PN = "Y7"  !CDS_PN = "Y7";
"VSS<944>":   PN = "Y67"  !CDS_PN = "Y67";
"VSS<945>":   PN = "Y5"  !CDS_PN = "Y5";
"VSS<946>":   PN = "Y17"  !CDS_PN = "Y17";
"VSS<947>":   PN = "Y15"  !CDS_PN = "Y15";
"VSS<948>":   PN = "W82"  !CDS_PN = "W82";
"VSS<949>":   PN = "W78"  !CDS_PN = "W78";
"VSS<950>":   PN = "W74"  !CDS_PN = "W74";
"VSS<951>":   PN = "W68"  !CDS_PN = "W68";
"VSS<952>":   PN = "W42"  !CDS_PN = "W42";
"VSS<953>":   PN = "W40"  !CDS_PN = "W40";
"VSS<954>":   PN = "W38"  !CDS_PN = "W38";
"VSS<955>":   PN = "W36"  !CDS_PN = "W36";
"VSS<956>":   PN = "W34"  !CDS_PN = "W34";
"VSS<957>":   PN = "W32"  !CDS_PN = "W32";
"VSS<958>":   PN = "W30"  !CDS_PN = "W30";
"VSS<959>":   PN = "W28"  !CDS_PN = "W28";
"VSS<960>":   PN = "W26"  !CDS_PN = "W26";
"VSS<961>":   PN = "W24"  !CDS_PN = "W24";
"VSS<962>":   PN = "W22"  !CDS_PN = "W22";
"VSS<963>":   PN = "W12"  !CDS_PN = "W12";
"VSS<964>":   PN = "AC56"  !CDS_PN = "AC56";
"VSS<965>":   PN = "W8"  !CDS_PN = "W8";
"VSS<966>":   PN = "V83"  !CDS_PN = "V83";
"VSS<967>":   PN = "V77"  !CDS_PN = "V77";
"VSS<968>":   PN = "V75"  !CDS_PN = "V75";
"VSS<969>":   PN = "V73"  !CDS_PN = "V73";
"VSS<970>":   PN = "V43"  !CDS_PN = "V43";
"VSS<971>":   PN = "V23"  !CDS_PN = "V23";
"VSS<972>":   PN = "V21"  !CDS_PN = "V21";
"VSS<973>":   PN = "V15"  !CDS_PN = "V15";
"VSS<974>":   PN = "V13"  !CDS_PN = "V13";
"VSS<975>":   PN = "V9"  !CDS_PN = "V9";
"VSS<976>":   PN = "V5"  !CDS_PN = "V5";
"VSS<977>":   PN = "V1"  !CDS_PN = "V1";
"VSS<978>":   PN = "U86"  !CDS_PN = "U86";
"VSS<979>":   PN = "U80"  !CDS_PN = "U80";
"VSS<980>":   PN = "U78"  !CDS_PN = "U78";
"VSS<981>":   PN = "U76"  !CDS_PN = "U76";
"VSS<982>":   PN = "U74"  !CDS_PN = "U74";
"VSS<983>":   PN = "U70"  !CDS_PN = "U70";
"VSS<984>":   PN = "U68"  !CDS_PN = "U68";
"VSS<985>":   PN = "U42"  !CDS_PN = "U42";
"VSS<986>":   PN = "U36"  !CDS_PN = "U36";
"VSS<987>":   PN = "U30"  !CDS_PN = "U30";
"VSS<988>":   PN = "U24"  !CDS_PN = "U24";
"VSS<989>":   PN = "U22"  !CDS_PN = "U22";
"VSS<990>":   PN = "U20"  !CDS_PN = "U20";
"VSS<991>":   PN = "U6"  !CDS_PN = "U6";
"VSS<992>":   PN = "U4"  !CDS_PN = "U4";
"VSS<993>":   PN = "U2"  !CDS_PN = "U2";
"VSS<994>":   PN = "T85"  !CDS_PN = "T85";
"VSS<995>":   PN = "T83"  !CDS_PN = "T83";
"VSS<996>":   PN = "T77"  !CDS_PN = "T77";
"VSS<997>":   PN = "T73"  !CDS_PN = "T73";
"VSS<998>":   PN = "T65"  !CDS_PN = "T65";
"VSS<999>":   PN = "T41"  !CDS_PN = "T41";
"VSS<1000>":   PN = "T37"  !CDS_PN = "T37";
"VSS<1001>":   PN = "T35"  !CDS_PN = "T35";
"VSS<1002>":   PN = "T31"  !CDS_PN = "T31";
"VSS<1003>":   PN = "T29"  !CDS_PN = "T29";
"VSS<1004>":   PN = "T25"  !CDS_PN = "T25";
"VSS<1005>":   PN = "T17"  !CDS_PN = "T17";
"VSS<1006>":   PN = "T13"  !CDS_PN = "T13";
"VSS<1007>":   PN = "R86"  !CDS_PN = "R86";
"VSS<1008>":   PN = "R78"  !CDS_PN = "R78";
"VSS<1009>":   PN = "R72"  !CDS_PN = "R72";
"VSS<1010>":   PN = "R68"  !CDS_PN = "R68";
"VSS<1011>":   PN = "R40"  !CDS_PN = "R40";
"VSS<1012>":   PN = "R38"  !CDS_PN = "R38";
"VSS<1013>":   PN = "R34"  !CDS_PN = "R34";
"VSS<1014>":   PN = "R32"  !CDS_PN = "R32";
"VSS<1015>":   PN = "R28"  !CDS_PN = "R28";
"VSS<1016>":   PN = "R26"  !CDS_PN = "R26";
"VSS<1017>":   PN = "R22"  !CDS_PN = "R22";
"VSS<1018>":   PN = "R4"  !CDS_PN = "R4";
"VSS<1019>":   PN = "R2"  !CDS_PN = "R2";
"VSS<1020>":   PN = "R18"  !CDS_PN = "R18";
"VSS<1021>":   PN = "R14"  !CDS_PN = "R14";
"VSS<1022>":   PN = "P83"  !CDS_PN = "P83";
"VSS<1023>":   PN = "P81"  !CDS_PN = "P81";
"VSS<1024>":   PN = "P71"  !CDS_PN = "P71";
"VSS<1025>":   PN = "P69"  !CDS_PN = "P69";
"VSS<1026>":   PN = "P67"  !CDS_PN = "P67";
"VSS<1027>":   PN = "P39"  !CDS_PN = "P39";
"VSS<1028>":   PN = "P33"  !CDS_PN = "P33";
"VSS<1029>":   PN = "P27"  !CDS_PN = "P27";
"VSS<1030>":   PN = "P15"  !CDS_PN = "P15";
"VSS<1031>":   PN = "P11"  !CDS_PN = "P11";
"VSS<1032>":   PN = "N8"  !CDS_PN = "N8";
"VSS<1033>":   PN = "N4"  !CDS_PN = "N4";
"VSS<1034>":   PN = "N78"  !CDS_PN = "N78";
"VSS<1035>":   PN = "N76"  !CDS_PN = "N76";
"VSS<1036>":   PN = "N74"  !CDS_PN = "N74";
"VSS<1037>":   PN = "N72"  !CDS_PN = "N72";
"VSS<1038>":   PN = "N70"  !CDS_PN = "N70";
"VSS<1039>":   PN = "N66"  !CDS_PN = "N66";
"VSS<1040>":   PN = "N6"  !CDS_PN = "N6";
"VSS<1041>":   PN = "N22"  !CDS_PN = "N22";
"VSS<1042>":   PN = "N20"  !CDS_PN = "N20";
"VSS<1043>":   PN = "DM19"  !CDS_PN = "DM19";
"VSS<1044>":   PN = "M85"  !CDS_PN = "M85";
"VSS<1045>":   PN = "M83"  !CDS_PN = "M83";
"VSS<1046>":   PN = "M79"  !CDS_PN = "M79";
"VSS<1047>":   PN = "M71"  !CDS_PN = "M71";
"VSS<1048>":   PN = "M65"  !CDS_PN = "M65";
"VSS<1049>":   PN = "M43"  !CDS_PN = "M43";
"VSS<1050>":   PN = "M41"  !CDS_PN = "M41";
"VSS<1051>":   PN = "M39"  !CDS_PN = "M39";
"VSS<1052>":   PN = "M37"  !CDS_PN = "M37";
"VSS<1053>":   PN = "M35"  !CDS_PN = "M35";
"VSS<1054>":   PN = "M33"  !CDS_PN = "M33";
"VSS<1055>":   PN = "M31"  !CDS_PN = "M31";
"VSS<1056>":   PN = "M29"  !CDS_PN = "M29";
"VSS<1057>":   PN = "M27"  !CDS_PN = "M27";
"VSS<1058>":   PN = "M25"  !CDS_PN = "M25";
"VSS<1059>":   PN = "M23"  !CDS_PN = "M23";
"VSS<1060>":   PN = "M19"  !CDS_PN = "M19";
"VSS<1061>":   PN = "M17"  !CDS_PN = "M17";
"VSS<1062>":   PN = "M15"  !CDS_PN = "M15";
"VSS<1063>":   PN = "CT7"  !CDS_PN = "CT7";
"VSS<1064>":   PN = "BT9"  !CDS_PN = "BT9";
"VSS<1065>":   PN = "L82"  !CDS_PN = "L82";
"VSS<1066>":   PN = "L80"  !CDS_PN = "L80";
"VSS<1067>":   PN = "L78"  !CDS_PN = "L78";
"VSS<1068>":   PN = "L72"  !CDS_PN = "L72";
"VSS<1069>":   PN = "L22"  !CDS_PN = "L22";
"VSS<1070>":   PN = "L20"  !CDS_PN = "L20";
"VSS<1071>":   PN = "L6"  !CDS_PN = "L6";
"VSS<1072>":   PN = "L2"  !CDS_PN = "L2";
"VSS<1073>":   PN = "L10"  !CDS_PN = "L10";
"VSS<1074>":   PN = "K85"  !CDS_PN = "K85";
"VSS<1075>":   PN = "K83"  !CDS_PN = "K83";
"VSS<1076>":   PN = "K81"  !CDS_PN = "K81";
"VSS<1077>":   PN = "K77"  !CDS_PN = "K77";
"VSS<1078>":   PN = "K73"  !CDS_PN = "K73";
"VSS<1079>":   PN = "K71"  !CDS_PN = "K71";
"VSS<1080>":   PN = "K69"  !CDS_PN = "K69";
"VSS<1081>":   PN = "K67"  !CDS_PN = "K67";
"VSS<1082>":   PN = "K65"  !CDS_PN = "K65";
"VSS<1083>":   PN = "K39"  !CDS_PN = "K39";
"VSS<1084>":   PN = "K33"  !CDS_PN = "K33";
"VSS<1085>":   PN = "K27"  !CDS_PN = "K27";
"VSS<1086>":   PN = "DB7"  !CDS_PN = "DB7";
"VSS<1087>":   PN = "K17"  !CDS_PN = "K17";
"VSS<1088>":   PN = "K13"  !CDS_PN = "K13";
"VSS<1089>":   PN = "K11"  !CDS_PN = "K11";
"VSS<1090>":   PN = "K1"  !CDS_PN = "K1";
"VSS<1091>":   PN = "J84"  !CDS_PN = "J84";
"VSS<1092>":   PN = "J82"  !CDS_PN = "J82";
"VSS<1093>":   PN = "J76"  !CDS_PN = "J76";
BODY = "SKX_EXT_B","I22": #LOCATION = "U5D1" !CDS_LOCATION = "U5D1" #SEC = "25" !CDS_SEC = "25";
"VSS<774>":   PN = "AL68"  !CDS_PN = "AL68";
"VSS<775>":   PN = "AL64"  !CDS_PN = "AL64";
"VSS<776>":   PN = "AL56"  !CDS_PN = "AL56";
"VSS<777>":   PN = "AL32"  !CDS_PN = "AL32";
"VSS<778>":   PN = "AL30"  !CDS_PN = "AL30";
"VSS<779>":   PN = "AL24"  !CDS_PN = "AL24";
"VSS<780>":   PN = "AL10"  !CDS_PN = "AL10";
"VSS<781>":   PN = "AL4"  !CDS_PN = "AL4";
"VSS<782>":   PN = "AK85"  !CDS_PN = "AK85";
"VSS<783>":   PN = "AK83"  !CDS_PN = "AK83";
"VSS<784>":   PN = "AK81"  !CDS_PN = "AK81";
"VSS<785>":   PN = "AK79"  !CDS_PN = "AK79";
"VSS<786>":   PN = "AK73"  !CDS_PN = "AK73";
"VSS<787>":   PN = "AK67"  !CDS_PN = "AK67";
"VSS<788>":   PN = "AK65"  !CDS_PN = "AK65";
"VSS<789>":   PN = "AK55"  !CDS_PN = "AK55";
"VSS<790>":   PN = "AK33"  !CDS_PN = "AK33";
"VSS<791>":   PN = "AK31"  !CDS_PN = "AK31";
"VSS<792>":   PN = "AK29"  !CDS_PN = "AK29";
"VSS<793>":   PN = "AK25"  !CDS_PN = "AK25";
"VSS<794>":   PN = "AK23"  !CDS_PN = "AK23";
"VSS<795>":   PN = "AK19"  !CDS_PN = "AK19";
"VSS<796>":   PN = "AK13"  !CDS_PN = "AK13";
"VSS<797>":   PN = "AK9"  !CDS_PN = "AK9";
"VSS<798>":   PN = "AJ86"  !CDS_PN = "AJ86";
"VSS<799>":   PN = "AJ82"  !CDS_PN = "AJ82";
"VSS<800>":   PN = "AJ78"  !CDS_PN = "AJ78";
"VSS<801>":   PN = "AJ74"  !CDS_PN = "AJ74";
"VSS<802>":   PN = "AJ68"  !CDS_PN = "AJ68";
"VSS<803>":   PN = "AJ66"  !CDS_PN = "AJ66";
"VSS<804>":   PN = "AJ54"  !CDS_PN = "AJ54";
"VSS<805>":   PN = "AJ52"  !CDS_PN = "AJ52";
"VSS<806>":   PN = "AJ50"  !CDS_PN = "AJ50";
"VSS<807>":   PN = "AJ48"  !CDS_PN = "AJ48";
"VSS<808>":   PN = "AJ46"  !CDS_PN = "AJ46";
"VSS<809>":   PN = "AJ34"  !CDS_PN = "AJ34";
"VSS<810>":   PN = "AJ32"  !CDS_PN = "AJ32";
"VSS<811>":   PN = "AJ28"  !CDS_PN = "AJ28";
"VSS<812>":   PN = "AJ26"  !CDS_PN = "AJ26";
"VSS<813>":   PN = "AJ22"  !CDS_PN = "AJ22";
"VSS<814>":   PN = "AJ8"  !CDS_PN = "AJ8";
"VSS<815>":   PN = "AH83"  !CDS_PN = "AH83";
"VSS<816>":   PN = "AH77"  !CDS_PN = "AH77";
"VSS<817>":   PN = "AH75"  !CDS_PN = "AH75";
"VSS<818>":   PN = "AH69"  !CDS_PN = "AH69";
"VSS<819>":   PN = "AH65"  !CDS_PN = "AH65";
"VSS<820>":   PN = "AH61"  !CDS_PN = "AH61";
"VSS<821>":   PN = "AH59"  !CDS_PN = "AH59";
"VSS<822>":   PN = "AH53"  !CDS_PN = "AH53";
"VSS<823>":   PN = "AH51"  !CDS_PN = "AH51";
"VSS<824>":   PN = "AH49"  !CDS_PN = "AH49";
"VSS<825>":   PN = "AH47"  !CDS_PN = "AH47";
"VSS<826>":   PN = "AH45"  !CDS_PN = "AH45";
"VSS<827>":   PN = "AH35"  !CDS_PN = "AH35";
"VSS<828>":   PN = "AH33"  !CDS_PN = "AH33";
"VSS<829>":   PN = "AH27"  !CDS_PN = "AH27";
"VSS<830>":   PN = "AH21"  !CDS_PN = "AH21";
"VSS<831>":   PN = "AH5"  !CDS_PN = "AH5";
"VSS<832>":   PN = "AH1"  !CDS_PN = "AH1";
"VSS<833>":   PN = "AG80"  !CDS_PN = "AG80";
"VSS<834>":   PN = "AG78"  !CDS_PN = "AG78";
"VSS<835>":   PN = "AG76"  !CDS_PN = "AG76";
"VSS<836>":   PN = "AG74"  !CDS_PN = "AG74";
"VSS<837>":   PN = "AG70"  !CDS_PN = "AG70";
"VSS<838>":   PN = "AG64"  !CDS_PN = "AG64";
"VSS<839>":   PN = "AG36"  !CDS_PN = "AG36";
"VSS<840>":   PN = "AG18"  !CDS_PN = "AG18";
"VSS<841>":   PN = "AG14"  !CDS_PN = "AG14";
"VSS<842>":   PN = "AG12"  !CDS_PN = "AG12";
"VSS<843>":   PN = "AF85"  !CDS_PN = "AF85";
"VSS<844>":   PN = "AF83"  !CDS_PN = "AF83";
"VSS<845>":   PN = "AF77"  !CDS_PN = "AF77";
"VSS<846>":   PN = "AF73"  !CDS_PN = "AF73";
"VSS<847>":   PN = "AF41"  !CDS_PN = "AF41";
"VSS<848>":   PN = "AF39"  !CDS_PN = "AF39";
"VSS<849>":   PN = "AF37"  !CDS_PN = "AF37";
"VSS<850>":   PN = "AF33"  !CDS_PN = "AF33";
"VSS<851>":   PN = "AF31"  !CDS_PN = "AF31";
"VSS<852>":   PN = "AF29"  !CDS_PN = "AF29";
"VSS<853>":   PN = "AF27"  !CDS_PN = "AF27";
"VSS<854>":   PN = "AF25"  !CDS_PN = "AF25";
"VSS<855>":   PN = "AF23"  !CDS_PN = "AF23";
"VSS<856>":   PN = "AF21"  !CDS_PN = "AF21";
"VSS<857>":   PN = "AF9"  !CDS_PN = "AF9";
"VSS<858>":   PN = "AC52"  !CDS_PN = "AC52";
"VSS<859>":   PN = "AF1"  !CDS_PN = "AF1";
"VSS<860>":   PN = "AE78"  !CDS_PN = "AE78";
"VSS<861>":   PN = "AE70"  !CDS_PN = "AE70";
"VSS<862>":   PN = "AE68"  !CDS_PN = "AE68";
"VSS<863>":   PN = "AE66"  !CDS_PN = "AE66";
"VSS<864>":   PN = "AE64"  !CDS_PN = "AE64";
"VSS<865>":   PN = "AE42"  !CDS_PN = "AE42";
"VSS<866>":   PN = "AE40"  !CDS_PN = "AE40";
"VSS<867>":   PN = "AE38"  !CDS_PN = "AE38";
"VSS<868>":   PN = "AE16"  !CDS_PN = "AE16";
"VSS<869>":   PN = "AC54"  !CDS_PN = "AC54";
"VSS<870>":   PN = "AE8"  !CDS_PN = "AE8";
"VSS<871>":   PN = "AE4"  !CDS_PN = "AE4";
"VSS<872>":   PN = "AD85"  !CDS_PN = "AD85";
"VSS<873>":   PN = "AD83"  !CDS_PN = "AD83";
"VSS<874>":   PN = "AD81"  !CDS_PN = "AD81";
"VSS<875>":   PN = "AD75"  !CDS_PN = "AD75";
"VSS<876>":   PN = "AD73"  !CDS_PN = "AD73";
"VSS<877>":   PN = "AD71"  !CDS_PN = "AD71";
"VSS<878>":   PN = "AD43"  !CDS_PN = "AD43";
"VSS<879>":   PN = "AD39"  !CDS_PN = "AD39";
"VSS<880>":   PN = "AD33"  !CDS_PN = "AD33";
"VSS<881>":   PN = "AD27"  !CDS_PN = "AD27";
"VSS<882>":   PN = "AD21"  !CDS_PN = "AD21";
"VSS<883>":   PN = "AD19"  !CDS_PN = "AD19";
"VSS<884>":   PN = "AD15"  !CDS_PN = "AD15";
"VSS<885>":   PN = "AD13"  !CDS_PN = "AD13";
"VSS<886>":   PN = "AD11"  !CDS_PN = "AD11";
"VSS<887>":   PN = "AD9"  !CDS_PN = "AD9";
"VSS<888>":   PN = "AD7"  !CDS_PN = "AD7";
"VSS<889>":   PN = "AD3"  !CDS_PN = "AD3";
"VSS<890>":   PN = "AC86"  !CDS_PN = "AC86";
"VSS<891>":   PN = "AC84"  !CDS_PN = "AC84";
"VSS<892>":   PN = "AC78"  !CDS_PN = "AC78";
"VSS<893>":   PN = "AC72"  !CDS_PN = "AC72";
"VSS<894>":   PN = "AC70"  !CDS_PN = "AC70";
"VSS<895>":   PN = "AC64"  !CDS_PN = "AC64";
"VSS<896>":   PN = "AC40"  !CDS_PN = "AC40";
"VSS<897>":   PN = "AC38"  !CDS_PN = "AC38";
"VSS<898>":   PN = "AC34"  !CDS_PN = "AC34";
"VSS<899>":   PN = "AC32"  !CDS_PN = "AC32";
"VSS<900>":   PN = "AC28"  !CDS_PN = "AC28";
"VSS<901>":   PN = "AC26"  !CDS_PN = "AC26";
"VSS<902>":   PN = "AC22"  !CDS_PN = "AC22";
"VSS<903>":   PN = "AC18"  !CDS_PN = "AC18";
"VSS<904>":   PN = "AB85"  !CDS_PN = "AB85";
"VSS<905>":   PN = "AB83"  !CDS_PN = "AB83";
"VSS<906>":   PN = "AB79"  !CDS_PN = "AB79";
"VSS<907>":   PN = "AB73"  !CDS_PN = "AB73";
"VSS<908>":   PN = "AB69"  !CDS_PN = "AB69";
"VSS<909>":   PN = "AB65"  !CDS_PN = "AB65";
"VSS<910>":   PN = "AB41"  !CDS_PN = "AB41";
"VSS<911>":   PN = "AB37"  !CDS_PN = "AB37";
"VSS<912>":   PN = "AB35"  !CDS_PN = "AB35";
"VSS<913>":   PN = "AB31"  !CDS_PN = "AB31";
"VSS<914>":   PN = "AB29"  !CDS_PN = "AB29";
"VSS<915>":   PN = "AB25"  !CDS_PN = "AB25";
"VSS<916>":   PN = "AB23"  !CDS_PN = "AB23";
"VSS<917>":   PN = "AB21"  !CDS_PN = "AB21";
"VSS<918>":   PN = "AB11"  !CDS_PN = "AB11";
"VSS<919>":   PN = "AB5"  !CDS_PN = "AB5";
"VSS<920>":   PN = "AB1"  !CDS_PN = "AB1";
"VSS<921>":   PN = "AA82"  !CDS_PN = "AA82";
"VSS<922>":   PN = "AA80"  !CDS_PN = "AA80";
"VSS<923>":   PN = "AA78"  !CDS_PN = "AA78";
"VSS<924>":   PN = "AA76"  !CDS_PN = "AA76";
"VSS<925>":   PN = "AA68"  !CDS_PN = "AA68";
"VSS<926>":   PN = "AA66"  !CDS_PN = "AA66";
"VSS<927>":   PN = "AA64"  !CDS_PN = "AA64";
"VSS<928>":   PN = "AA42"  !CDS_PN = "AA42";
"VSS<929>":   PN = "AA36"  !CDS_PN = "AA36";
"VSS<930>":   PN = "AA30"  !CDS_PN = "AA30";
"VSS<931>":   PN = "AA24"  !CDS_PN = "AA24";
"VSS<932>":   PN = "AA22"  !CDS_PN = "AA22";
"VSS<933>":   PN = "AA18"  !CDS_PN = "AA18";
BODY = "SKX_EXT_B","I23": #LOCATION = "U5D1" !CDS_LOCATION = "U5D1" #SEC = "26" !CDS_SEC = "26";
"VSS<614>":   PN = "BG72"  !CDS_PN = "BG72";
"VSS<615>":   PN = "BG24"  !CDS_PN = "BG24";
"VSS<616>":   PN = "BG22"  !CDS_PN = "BG22";
"VSS<617>":   PN = "BG10"  !CDS_PN = "BG10";
"VSS<618>":   PN = "BG8"  !CDS_PN = "BG8";
"VSS<619>":   PN = "BG6"  !CDS_PN = "BG6";
"VSS<620>":   PN = "BF71"  !CDS_PN = "BF71";
"VSS<621>":   PN = "BF69"  !CDS_PN = "BF69";
"VSS<622>":   PN = "BF67"  !CDS_PN = "BF67";
"VSS<623>":   PN = "BF65"  !CDS_PN = "BF65";
"VSS<624>":   PN = "BF63"  !CDS_PN = "BF63";
"VSS<625>":   PN = "BF25"  !CDS_PN = "BF25";
"VSS<626>":   PN = "BF19"  !CDS_PN = "BF19";
"VSS<627>":   PN = "BF17"  !CDS_PN = "BF17";
"VSS<628>":   PN = "BF15"  !CDS_PN = "BF15";
"VSS<629>":   PN = "BF9"  !CDS_PN = "BF9";
"VSS<630>":   PN = "BE70"  !CDS_PN = "BE70";
"VSS<631>":   PN = "BE68"  !CDS_PN = "BE68";
"VSS<632>":   PN = "BE66"  !CDS_PN = "BE66";
"VSS<633>":   PN = "BE64"  !CDS_PN = "BE64";
"VSS<634>":   PN = "BE26"  !CDS_PN = "BE26";
"VSS<635>":   PN = "BE10"  !CDS_PN = "BE10";
"VSS<636>":   PN = "BE8"  !CDS_PN = "BE8";
"VSS<637>":   PN = "BE6"  !CDS_PN = "BE6";
"VSS<638>":   PN = "BE4"  !CDS_PN = "BE4";
"VSS<639>":   PN = "BD71"  !CDS_PN = "BD71";
"VSS<640>":   PN = "BD63"  !CDS_PN = "BD63";
"VSS<641>":   PN = "BD27"  !CDS_PN = "BD27";
"VSS<642>":   PN = "BD21"  !CDS_PN = "BD21";
"VSS<643>":   PN = "BD15"  !CDS_PN = "BD15";
"VSS<644>":   PN = "BD11"  !CDS_PN = "BD11";
"VSS<645>":   PN = "BD5"  !CDS_PN = "BD5";
"VSS<646>":   PN = "BC82"  !CDS_PN = "BC82";
"VSS<647>":   PN = "BC80"  !CDS_PN = "BC80";
"VSS<648>":   PN = "BC78"  !CDS_PN = "BC78";
"VSS<649>":   PN = "BC76"  !CDS_PN = "BC76";
"VSS<650>":   PN = "BC74"  !CDS_PN = "BC74";
"VSS<651>":   PN = "BC72"  !CDS_PN = "BC72";
"VSS<652>":   PN = "BC70"  !CDS_PN = "BC70";
"VSS<653>":   PN = "BC16"  !CDS_PN = "BC16";
"VSS<654>":   PN = "BC12"  !CDS_PN = "BC12";
"VSS<655>":   PN = "BC8"  !CDS_PN = "BC8";
"VSS<656>":   PN = "BC4"  !CDS_PN = "BC4";
"VSS<657>":   PN = "BB83"  !CDS_PN = "BB83";
"VSS<658>":   PN = "BB81"  !CDS_PN = "BB81";
"VSS<659>":   PN = "BB79"  !CDS_PN = "BB79";
"VSS<660>":   PN = "BB77"  !CDS_PN = "BB77";
"VSS<661>":   PN = "BB75"  !CDS_PN = "BB75";
"VSS<662>":   PN = "BB73"  !CDS_PN = "BB73";
"VSS<663>":   PN = "BB69"  !CDS_PN = "BB69";
"VSS<664>":   PN = "BB63"  !CDS_PN = "BB63";
"VSS<665>":   PN = "BB23"  !CDS_PN = "BB23";
"VSS<666>":   PN = "BB19"  !CDS_PN = "BB19";
"VSS<667>":   PN = "BA84"  !CDS_PN = "BA84";
"VSS<668>":   PN = "BA80"  !CDS_PN = "BA80";
"VSS<669>":   PN = "BA74"  !CDS_PN = "BA74";
"VSS<670>":   PN = "BA68"  !CDS_PN = "BA68";
"VSS<671>":   PN = "BA62"  !CDS_PN = "BA62";
"VSS<672>":   PN = "BA12"  !CDS_PN = "BA12";
"VSS<673>":   PN = "BA6"  !CDS_PN = "BA6";
"VSS<674>":   PN = "BA2"  !CDS_PN = "BA2";
"VSS<675>":   PN = "AY81"  !CDS_PN = "AY81";
"VSS<676>":   PN = "AY79"  !CDS_PN = "AY79";
"VSS<677>":   PN = "AY63"  !CDS_PN = "AY63";
"VSS<678>":   PN = "AY25"  !CDS_PN = "AY25";
"VSS<679>":   PN = "AY23"  !CDS_PN = "AY23";
"VSS<680>":   PN = "AY21"  !CDS_PN = "AY21";
"VSS<681>":   PN = "AY17"  !CDS_PN = "AY17";
"VSS<682>":   PN = "AY15"  !CDS_PN = "AY15";
"VSS<683>":   PN = "AY5"  !CDS_PN = "AY5";
"VSS<684>":   PN = "AW84"  !CDS_PN = "AW84";
"VSS<685>":   PN = "AW82"  !CDS_PN = "AW82";
"VSS<686>":   PN = "AW78"  !CDS_PN = "AW78";
"VSS<687>":   PN = "AW74"  !CDS_PN = "AW74";
"VSS<688>":   PN = "AW72"  !CDS_PN = "AW72";
"VSS<689>":   PN = "AW70"  !CDS_PN = "AW70";
"VSS<690>":   PN = "AW68"  !CDS_PN = "AW68";
"VSS<691>":   PN = "AW66"  !CDS_PN = "AW66";
"VSS<692>":   PN = "AW62"  !CDS_PN = "AW62";
"VSS<693>":   PN = "AW10"  !CDS_PN = "AW10";
"VSS<694>":   PN = "AW2"  !CDS_PN = "AW2";
"VSS<695>":   PN = "AV83"  !CDS_PN = "AV83";
"VSS<696>":   PN = "AV75"  !CDS_PN = "AV75";
"VSS<697>":   PN = "AV67"  !CDS_PN = "AV67";
"VSS<698>":   PN = "AV65"  !CDS_PN = "AV65";
"VSS<699>":   PN = "AV63"  !CDS_PN = "AV63";
"VSS<700>":   PN = "AV25"  !CDS_PN = "AV25";
"VSS<701>":   PN = "AV23"  !CDS_PN = "AV23";
"VSS<702>":   PN = "AV19"  !CDS_PN = "AV19";
"VSS<703>":   PN = "AV13"  !CDS_PN = "AV13";
"VSS<704>":   PN = "AV11"  !CDS_PN = "AV11";
"VSS<705>":   PN = "AV7"  !CDS_PN = "AV7";
"VSS<706>":   PN = "AV3"  !CDS_PN = "AV3";
"VSS<707>":   PN = "AV1"  !CDS_PN = "AV1";
"VSS<708>":   PN = "AU86"  !CDS_PN = "AU86";
"VSS<709>":   PN = "AU84"  !CDS_PN = "AU84";
"VSS<710>":   PN = "AU80"  !CDS_PN = "AU80";
"VSS<711>":   PN = "AU78"  !CDS_PN = "AU78";
"VSS<712>":   PN = "AU76"  !CDS_PN = "AU76";
"VSS<713>":   PN = "AU74"  !CDS_PN = "AU74";
"VSS<714>":   PN = "AU68"  !CDS_PN = "AU68";
"VSS<715>":   PN = "AU64"  !CDS_PN = "AU64";
"VSS<716>":   PN = "AU62"  !CDS_PN = "AU62";
"VSS<717>":   PN = "AU28"  !CDS_PN = "AU28";
"VSS<718>":   PN = "AU26"  !CDS_PN = "AU26";
"VSS<719>":   PN = "AU6"  !CDS_PN = "AU6";
"VSS<720>":   PN = "AU2"  !CDS_PN = "AU2";
"VSS<721>":   PN = "AT85"  !CDS_PN = "AT85";
"VSS<722>":   PN = "AT83"  !CDS_PN = "AT83";
"VSS<723>":   PN = "AT77"  !CDS_PN = "AT77";
"VSS<724>":   PN = "AT73"  !CDS_PN = "AT73";
"VSS<725>":   PN = "AT69"  !CDS_PN = "AT69";
"VSS<726>":   PN = "AT63"  !CDS_PN = "AT63";
"VSS<727>":   PN = "AT61"  !CDS_PN = "AT61";
"VSS<728>":   PN = "AT27"  !CDS_PN = "AT27";
"VSS<729>":   PN = "AT21"  !CDS_PN = "AT21";
"VSS<730>":   PN = "AT17"  !CDS_PN = "AT17";
"VSS<731>":   PN = "AT15"  !CDS_PN = "AT15";
"VSS<732>":   PN = "P63"  !CDS_PN = "P63";
"VSS<733>":   PN = "AC48"  !CDS_PN = "AC48";
"VSS<734>":   PN = "AR78"  !CDS_PN = "AR78";
"VSS<735>":   PN = "AR72"  !CDS_PN = "AR72";
"VSS<736>":   PN = "AR60"  !CDS_PN = "AR60";
"VSS<737>":   PN = "AR30"  !CDS_PN = "AR30";
"VSS<738>":   PN = "AR24"  !CDS_PN = "AR24";
"VSS<739>":   PN = "AR10"  !CDS_PN = "AR10";
"VSS<740>":   PN = "AP85"  !CDS_PN = "AP85";
"VSS<741>":   PN = "AP83"  !CDS_PN = "AP83";
"VSS<742>":   PN = "AP81"  !CDS_PN = "AP81";
"VSS<743>":   PN = "AP75"  !CDS_PN = "AP75";
"VSS<744>":   PN = "AP73"  !CDS_PN = "AP73";
"VSS<745>":   PN = "AP69"  !CDS_PN = "AP69";
"VSS<746>":   PN = "AP67"  !CDS_PN = "AP67";
"VSS<747>":   PN = "AP65"  !CDS_PN = "AP65";
"VSS<748>":   PN = "AP63"  !CDS_PN = "AP63";
"VSS<749>":   PN = "AP59"  !CDS_PN = "AP59";
"VSS<750>":   PN = "AP31"  !CDS_PN = "AP31";
"VSS<751>":   PN = "AP19"  !CDS_PN = "AP19";
"VSS<752>":   PN = "AP13"  !CDS_PN = "AP13";
"VSS<753>":   PN = "AP9"  !CDS_PN = "AP9";
"VSS<754>":   PN = "AP5"  !CDS_PN = "AP5";
"VSS<755>":   PN = "AN78"  !CDS_PN = "AN78";
"VSS<756>":   PN = "AN58"  !CDS_PN = "AN58";
"VSS<757>":   PN = "AN28"  !CDS_PN = "AN28";
"VSS<758>":   PN = "AN6"  !CDS_PN = "AN6";
"VSS<759>":   PN = "AN2"  !CDS_PN = "AN2";
"VSS<760>":   PN = "AM83"  !CDS_PN = "AM83";
"VSS<761>":   PN = "AM79"  !CDS_PN = "AM79";
"VSS<762>":   PN = "AM73"  !CDS_PN = "AM73";
"VSS<763>":   PN = "AM69"  !CDS_PN = "AM69";
"VSS<764>":   PN = "AM63"  !CDS_PN = "AM63";
"VSS<765>":   PN = "AM57"  !CDS_PN = "AM57";
"VSS<766>":   PN = "AM31"  !CDS_PN = "AM31";
"VSS<767>":   PN = "AC50"  !CDS_PN = "AC50";
"VSS<768>":   PN = "AM1"  !CDS_PN = "AM1";
"VSS<769>":   PN = "AL86"  !CDS_PN = "AL86";
"VSS<770>":   PN = "AL82"  !CDS_PN = "AL82";
"VSS<771>":   PN = "AL80"  !CDS_PN = "AL80";
"VSS<772>":   PN = "AL78"  !CDS_PN = "AL78";
"VSS<773>":   PN = "AL76"  !CDS_PN = "AL76";
DRAWING = "@baseboard_fab2_lib.baseboard_fab2(sch_1):page41";
BODY = "SKX_EXT_B","I283": #LOCATION = "U5D1" !CDS_LOCATION = "U5D1" #SEC = "27" !CDS_SEC = "27";
"VSS<454>":   PN = "P49"  !CDS_PN = "P49";
"VSS<455>":   PN = "CJ12"  !CDS_PN = "CJ12";
"VSS<456>":   PN = "CJ10"  !CDS_PN = "CJ10";
"VSS<457>":   PN = "CJ8"  !CDS_PN = "CJ8";
"VSS<458>":   PN = "CJ6"  !CDS_PN = "CJ6";
"VSS<459>":   PN = "CJ2"  !CDS_PN = "CJ2";
"VSS<460>":   PN = "CH83"  !CDS_PN = "CH83";
"VSS<461>":   PN = "CH81"  !CDS_PN = "CH81";
"VSS<462>":   PN = "CH79"  !CDS_PN = "CH79";
"VSS<463>":   PN = "CH73"  !CDS_PN = "CH73";
"VSS<464>":   PN = "CH67"  !CDS_PN = "CH67";
"VSS<465>":   PN = "CH63"  !CDS_PN = "CH63";
"VSS<466>":   PN = "CH19"  !CDS_PN = "CH19";
"VSS<467>":   PN = "CH15"  !CDS_PN = "CH15";
"VSS<468>":   PN = "CH3"  !CDS_PN = "CH3";
"VSS<469>":   PN = "CH1"  !CDS_PN = "CH1";
"VSS<470>":   PN = "CG80"  !CDS_PN = "CG80";
"VSS<471>":   PN = "CG72"  !CDS_PN = "CG72";
"VSS<472>":   PN = "CG68"  !CDS_PN = "CG68";
"VSS<473>":   PN = "CG62"  !CDS_PN = "CG62";
"VSS<474>":   PN = "CG22"  !CDS_PN = "CG22";
"VSS<475>":   PN = "CG18"  !CDS_PN = "CG18";
"VSS<476>":   PN = "P51"  !CDS_PN = "P51";
"VSS<477>":   PN = "CF83"  !CDS_PN = "CF83";
"VSS<478>":   PN = "CF77"  !CDS_PN = "CF77";
"VSS<479>":   PN = "CF71"  !CDS_PN = "CF71";
"VSS<480>":   PN = "CF69"  !CDS_PN = "CF69";
"VSS<481>":   PN = "CF63"  !CDS_PN = "CF63";
"VSS<482>":   PN = "CF9"  !CDS_PN = "CF9";
"VSS<483>":   PN = "P53"  !CDS_PN = "P53";
"VSS<484>":   PN = "CE82"  !CDS_PN = "CE82";
"VSS<485>":   PN = "CE70"  !CDS_PN = "CE70";
"VSS<486>":   PN = "CE62"  !CDS_PN = "CE62";
"VSS<487>":   PN = "CE26"  !CDS_PN = "CE26";
"VSS<488>":   PN = "CE20"  !CDS_PN = "CE20";
"VSS<489>":   PN = "CE14"  !CDS_PN = "CE14";
"VSS<490>":   PN = "CE10"  !CDS_PN = "CE10";
"VSS<491>":   PN = "CD81"  !CDS_PN = "CD81";
"VSS<492>":   PN = "CD79"  !CDS_PN = "CD79";
"VSS<493>":   PN = "CD77"  !CDS_PN = "CD77";
"VSS<494>":   PN = "CD75"  !CDS_PN = "CD75";
"VSS<495>":   PN = "CD73"  !CDS_PN = "CD73";
"VSS<496>":   PN = "CD63"  !CDS_PN = "CD63";
"VSS<497>":   PN = "CD13"  !CDS_PN = "CD13";
"VSS<498>":   PN = "CD5"  !CDS_PN = "CD5";
"VSS<499>":   PN = "CC82"  !CDS_PN = "CC82";
"VSS<500>":   PN = "CC80"  !CDS_PN = "CC80";
"VSS<501>":   PN = "CC78"  !CDS_PN = "CC78";
"VSS<502>":   PN = "CC76"  !CDS_PN = "CC76";
"VSS<503>":   PN = "CC74"  !CDS_PN = "CC74";
"VSS<504>":   PN = "CC72"  !CDS_PN = "CC72";
"VSS<505>":   PN = "CC64"  !CDS_PN = "CC64";
"VSS<506>":   PN = "CC24"  !CDS_PN = "CC24";
"VSS<507>":   PN = "CC18"  !CDS_PN = "CC18";
"VSS<508>":   PN = "CC16"  !CDS_PN = "CC16";
"VSS<509>":   PN = "CC4"  !CDS_PN = "CC4";
"VSS<510>":   PN = "CB71"  !CDS_PN = "CB71";
"VSS<511>":   PN = "CB63"  !CDS_PN = "CB63";
"VSS<512>":   PN = "CB27"  !CDS_PN = "CB27";
"VSS<513>":   PN = "CB9"  !CDS_PN = "CB9";
"VSS<514>":   PN = "CB7"  !CDS_PN = "CB7";
"VSS<515>":   PN = "CA70"  !CDS_PN = "CA70";
"VSS<516>":   PN = "CA68"  !CDS_PN = "CA68";
"VSS<517>":   PN = "CA66"  !CDS_PN = "CA66";
"VSS<518>":   PN = "CA64"  !CDS_PN = "CA64";
"VSS<519>":   PN = "CA26"  !CDS_PN = "CA26";
"VSS<520>":   PN = "CA18"  !CDS_PN = "CA18";
"VSS<521>":   PN = "CA14"  !CDS_PN = "CA14";
"VSS<522>":   PN = "CA10"  !CDS_PN = "CA10";
"VSS<523>":   PN = "CA8"  !CDS_PN = "CA8";
"VSS<524>":   PN = "CA6"  !CDS_PN = "CA6";
"VSS<525>":   PN = "CA2"  !CDS_PN = "CA2";
"VSS<526>":   PN = "BY71"  !CDS_PN = "BY71";
"VSS<527>":   PN = "BY69"  !CDS_PN = "BY69";
"VSS<528>":   PN = "BY67"  !CDS_PN = "BY67";
"VSS<529>":   PN = "BY65"  !CDS_PN = "BY65";
"VSS<530>":   PN = "BY63"  !CDS_PN = "BY63";
"VSS<531>":   PN = "BY23"  !CDS_PN = "BY23";
"VSS<532>":   PN = "BY13"  !CDS_PN = "BY13";
"VSS<533>":   PN = "BY11"  !CDS_PN = "BY11";
"VSS<534>":   PN = "BW82"  !CDS_PN = "BW82";
"VSS<535>":   PN = "BW80"  !CDS_PN = "BW80";
"VSS<536>":   PN = "BW78"  !CDS_PN = "BW78";
"VSS<537>":   PN = "BW76"  !CDS_PN = "BW76";
"VSS<538>":   PN = "BW74"  !CDS_PN = "BW74";
"VSS<539>":   PN = "BW72"  !CDS_PN = "BW72";
"VSS<540>":   PN = "BW26"  !CDS_PN = "BW26";
"VSS<541>":   PN = "BW18"  !CDS_PN = "BW18";
"VSS<542>":   PN = "BW16"  !CDS_PN = "BW16";
"VSS<543>":   PN = "BW14"  !CDS_PN = "BW14";
"VSS<544>":   PN = "BW12"  !CDS_PN = "BW12";
"VSS<545>":   PN = "P55"  !CDS_PN = "P55";
"VSS<546>":   PN = "BW6"  !CDS_PN = "BW6";
"VSS<547>":   PN = "BV25"  !CDS_PN = "BV25";
"VSS<548>":   PN = "BV17"  !CDS_PN = "BV17";
"VSS<549>":   PN = "BU10"  !CDS_PN = "BU10";
"VSS<550>":   PN = "BV5"  !CDS_PN = "BV5";
"VSS<551>":   PN = "BU8"  !CDS_PN = "BU8";
"VSS<552>":   PN = "BT25"  !CDS_PN = "BT25";
"VSS<553>":   PN = "BT23"  !CDS_PN = "BT23";
"VSS<554>":   PN = "BT21"  !CDS_PN = "BT21";
"VSS<555>":   PN = "BT5"  !CDS_PN = "BT5";
"VSS<556>":   PN = "BT3"  !CDS_PN = "BT3";
"VSS<557>":   PN = "BR82"  !CDS_PN = "BR82";
"VSS<558>":   PN = "BR80"  !CDS_PN = "BR80";
"VSS<559>":   PN = "BR78"  !CDS_PN = "BR78";
"VSS<560>":   PN = "BR76"  !CDS_PN = "BR76";
"VSS<561>":   PN = "BR74"  !CDS_PN = "BR74";
"VSS<562>":   PN = "BR72"  !CDS_PN = "BR72";
"VSS<563>":   PN = "BR70"  !CDS_PN = "BR70";
"VSS<564>":   PN = "BR68"  !CDS_PN = "BR68";
"VSS<565>":   PN = "BR66"  !CDS_PN = "BR66";
"VSS<566>":   PN = "BR64"  !CDS_PN = "BR64";
"VSS<567>":   PN = "P57"  !CDS_PN = "P57";
"VSS<568>":   PN = "BR16"  !CDS_PN = "BR16";
"VSS<569>":   PN = "BR10"  !CDS_PN = "BR10";
"VSS<570>":   PN = "BR6"  !CDS_PN = "BR6";
"VSS<571>":   PN = "BP27"  !CDS_PN = "BP27";
"VSS<572>":   PN = "BP3"  !CDS_PN = "BP3";
"VSS<573>":   PN = "BN26"  !CDS_PN = "BN26";
"VSS<574>":   PN = "BN20"  !CDS_PN = "BN20";
"VSS<575>":   PN = "BN10"  !CDS_PN = "BN10";
"VSS<576>":   PN = "BN6"  !CDS_PN = "BN6";
"VSS<577>":   PN = "BM25"  !CDS_PN = "BM25";
"VSS<578>":   PN = "P59"  !CDS_PN = "P59";
"VSS<579>":   PN = "BM15"  !CDS_PN = "BM15";
"VSS<580>":   PN = "BM13"  !CDS_PN = "BM13";
"VSS<581>":   PN = "BM9"  !CDS_PN = "BM9";
"VSS<582>":   PN = "BL82"  !CDS_PN = "BL82";
"VSS<583>":   PN = "BL80"  !CDS_PN = "BL80";
"VSS<584>":   PN = "BL78"  !CDS_PN = "BL78";
"VSS<585>":   PN = "BL76"  !CDS_PN = "BL76";
"VSS<586>":   PN = "BL74"  !CDS_PN = "BL74";
"VSS<587>":   PN = "BL72"  !CDS_PN = "BL72";
"VSS<588>":   PN = "BL70"  !CDS_PN = "BL70";
"VSS<589>":   PN = "BL68"  !CDS_PN = "BL68";
"VSS<590>":   PN = "BL66"  !CDS_PN = "BL66";
"VSS<591>":   PN = "BL64"  !CDS_PN = "BL64";
"VSS<592>":   PN = "BL24"  !CDS_PN = "BL24";
"VSS<593>":   PN = "BL22"  !CDS_PN = "BL22";
"VSS<594>":   PN = "P61"  !CDS_PN = "P61";
"VSS<595>":   PN = "BL12"  !CDS_PN = "BL12";
"VSS<596>":   PN = "BL10"  !CDS_PN = "BL10";
"VSS<597>":   PN = "BL6"  !CDS_PN = "BL6";
"VSS<598>":   PN = "BK19"  !CDS_PN = "BK19";
"VSS<599>":   PN = "BK11"  !CDS_PN = "BK11";
"VSS<600>":   PN = "BK7"  !CDS_PN = "BK7";
"VSS<601>":   PN = "BK3"  !CDS_PN = "BK3";
"VSS<602>":   PN = "BJ6"  !CDS_PN = "BJ6";
"VSS<603>":   PN = "BJ4"  !CDS_PN = "BJ4";
"VSS<604>":   PN = "BH21"  !CDS_PN = "BH21";
"VSS<605>":   PN = "BH15"  !CDS_PN = "BH15";
"VSS<606>":   PN = "BH11"  !CDS_PN = "BH11";
"VSS<607>":   PN = "BH9"  !CDS_PN = "BH9";
"VSS<608>":   PN = "BH7"  !CDS_PN = "BH7";
"VSS<609>":   PN = "BG82"  !CDS_PN = "BG82";
"VSS<610>":   PN = "BG80"  !CDS_PN = "BG80";
"VSS<611>":   PN = "BG78"  !CDS_PN = "BG78";
"VSS<612>":   PN = "BG76"  !CDS_PN = "BG76";
"VSS<613>":   PN = "BG74"  !CDS_PN = "BG74";
BODY = "SKX_EXT_B","I284": #LOCATION = "U5D1" !CDS_LOCATION = "U5D1" #SEC = "28" !CDS_SEC = "28";
"VSS<294>":   PN = "DA46"  !CDS_PN = "DA46";
"VSS<295>":   PN = "DA44"  !CDS_PN = "DA44";
"VSS<296>":   PN = "DA38"  !CDS_PN = "DA38";
"VSS<297>":   PN = "DA36"  !CDS_PN = "DA36";
"VSS<298>":   PN = "DA34"  !CDS_PN = "DA34";
"VSS<299>":   PN = "DA32"  !CDS_PN = "DA32";
"VSS<300>":   PN = "DA30"  !CDS_PN = "DA30";
"VSS<301>":   PN = "DA28"  !CDS_PN = "DA28";
"VSS<302>":   PN = "DA26"  !CDS_PN = "DA26";
"VSS<303>":   PN = "DA18"  !CDS_PN = "DA18";
"VSS<304>":   PN = "H53"  !CDS_PN = "H53";
"VSS<305>":   PN = "DA6"  !CDS_PN = "DA6";
"VSS<306>":   PN = "CY85"  !CDS_PN = "CY85";
"VSS<307>":   PN = "CY83"  !CDS_PN = "CY83";
"VSS<308>":   PN = "CY77"  !CDS_PN = "CY77";
"VSS<309>":   PN = "CY75"  !CDS_PN = "CY75";
"VSS<310>":   PN = "CY69"  !CDS_PN = "CY69";
"VSS<311>":   PN = "CY65"  !CDS_PN = "CY65";
"VSS<312>":   PN = "CY61"  !CDS_PN = "CY61";
"VSS<313>":   PN = "CY59"  !CDS_PN = "CY59";
"VSS<314>":   PN = "CY51"  !CDS_PN = "CY51";
"VSS<315>":   PN = "CY45"  !CDS_PN = "CY45";
"VSS<316>":   PN = "CY41"  !CDS_PN = "CY41";
"VSS<317>":   PN = "CY21"  !CDS_PN = "CY21";
"VSS<318>":   PN = "CY15"  !CDS_PN = "CY15";
"VSS<319>":   PN = "CY13"  !CDS_PN = "CY13";
"VSS<320>":   PN = "CY9"  !CDS_PN = "CY9";
"VSS<321>":   PN = "CY1"  !CDS_PN = "CY1";
"VSS<322>":   PN = "CW82"  !CDS_PN = "CW82";
"VSS<323>":   PN = "CW78"  !CDS_PN = "CW78";
"VSS<324>":   PN = "CW74"  !CDS_PN = "CW74";
"VSS<325>":   PN = "CW68"  !CDS_PN = "CW68";
"VSS<326>":   PN = "CW66"  !CDS_PN = "CW66";
"VSS<327>":   PN = "CW64"  !CDS_PN = "CW64";
"VSS<328>":   PN = "CW54"  !CDS_PN = "CW54";
"VSS<329>":   PN = "CW52"  !CDS_PN = "CW52";
"VSS<330>":   PN = "CW42"  !CDS_PN = "CW42";
"VSS<331>":   PN = "CW40"  !CDS_PN = "CW40";
"VSS<332>":   PN = "CW38"  !CDS_PN = "CW38";
"VSS<333>":   PN = "CW32"  !CDS_PN = "CW32";
"VSS<334>":   PN = "CW26"  !CDS_PN = "CW26";
"VSS<335>":   PN = "CW12"  !CDS_PN = "CW12";
"VSS<336>":   PN = "CV83"  !CDS_PN = "CV83";
"VSS<337>":   PN = "CV81"  !CDS_PN = "CV81";
"VSS<338>":   PN = "CV79"  !CDS_PN = "CV79";
"VSS<339>":   PN = "CV73"  !CDS_PN = "CV73";
"VSS<340>":   PN = "CV67"  !CDS_PN = "CV67";
"VSS<341>":   PN = "CV63"  !CDS_PN = "CV63";
"VSS<342>":   PN = "CV55"  !CDS_PN = "CV55";
"VSS<343>":   PN = "CV53"  !CDS_PN = "CV53";
"VSS<344>":   PN = "CV41"  !CDS_PN = "CV41";
"VSS<345>":   PN = "CV39"  !CDS_PN = "CV39";
"VSS<346>":   PN = "CV37"  !CDS_PN = "CV37";
"VSS<347>":   PN = "CV33"  !CDS_PN = "CV33";
"VSS<348>":   PN = "CV31"  !CDS_PN = "CV31";
"VSS<349>":   PN = "CV27"  !CDS_PN = "CV27";
"VSS<350>":   PN = "CV25"  !CDS_PN = "CV25";
"VSS<351>":   PN = "CV17"  !CDS_PN = "CV17";
"VSS<352>":   PN = "H55"  !CDS_PN = "H55";
"VSS<353>":   PN = "CV1"  !CDS_PN = "CV1";
"VSS<354>":   PN = "CU86"  !CDS_PN = "CU86";
"VSS<355>":   PN = "CU82"  !CDS_PN = "CU82";
"VSS<356>":   PN = "CU80"  !CDS_PN = "CU80";
"VSS<357>":   PN = "CU78"  !CDS_PN = "CU78";
"VSS<358>":   PN = "CU76"  !CDS_PN = "CU76";
"VSS<359>":   PN = "CU68"  !CDS_PN = "CU68";
"VSS<360>":   PN = "CU62"  !CDS_PN = "CU62";
"VSS<361>":   PN = "CU56"  !CDS_PN = "CU56";
"VSS<362>":   PN = "CU36"  !CDS_PN = "CU36";
"VSS<363>":   PN = "CU34"  !CDS_PN = "CU34";
"VSS<364>":   PN = "CU30"  !CDS_PN = "CU30";
"VSS<365>":   PN = "CU28"  !CDS_PN = "CU28";
"VSS<366>":   PN = "CU22"  !CDS_PN = "CU22";
"VSS<367>":   PN = "CU4"  !CDS_PN = "CU4";
"VSS<368>":   PN = "CT85"  !CDS_PN = "CT85";
"VSS<369>":   PN = "CT83"  !CDS_PN = "CT83";
"VSS<370>":   PN = "CT79"  !CDS_PN = "CT79";
"VSS<371>":   PN = "CT73"  !CDS_PN = "CT73";
"VSS<372>":   PN = "CT57"  !CDS_PN = "CT57";
"VSS<373>":   PN = "CT35"  !CDS_PN = "CT35";
"VSS<374>":   PN = "CT33"  !CDS_PN = "CT33";
"VSS<375>":   PN = "CT29"  !CDS_PN = "CT29";
"VSS<376>":   PN = "CT27"  !CDS_PN = "CT27";
"VSS<377>":   PN = "CT19"  !CDS_PN = "CT19";
"VSS<378>":   PN = "CT13"  !CDS_PN = "CT13";
"VSS<379>":   PN = "H57"  !CDS_PN = "H57";
"VSS<380>":   PN = "CR86"  !CDS_PN = "CR86";
"VSS<381>":   PN = "CR78"  !CDS_PN = "CR78";
"VSS<382>":   PN = "CR68"  !CDS_PN = "CR68";
"VSS<383>":   PN = "CR66"  !CDS_PN = "CR66";
"VSS<384>":   PN = "CR64"  !CDS_PN = "CR64";
"VSS<385>":   PN = "CR62"  !CDS_PN = "CR62";
"VSS<386>":   PN = "CR58"  !CDS_PN = "CR58";
"VSS<387>":   PN = "CR32"  !CDS_PN = "CR32";
"VSS<388>":   PN = "CR24"  !CDS_PN = "CR24";
"VSS<389>":   PN = "CR22"  !CDS_PN = "CR22";
"VSS<390>":   PN = "CR10"  !CDS_PN = "CR10";
"VSS<391>":   PN = "CR6"  !CDS_PN = "CR6";
"VSS<392>":   PN = "CP83"  !CDS_PN = "CP83";
"VSS<393>":   PN = "CP81"  !CDS_PN = "CP81";
"VSS<394>":   PN = "CP75"  !CDS_PN = "CP75";
"VSS<395>":   PN = "CP73"  !CDS_PN = "CP73";
"VSS<396>":   PN = "CP69"  !CDS_PN = "CP69";
"VSS<397>":   PN = "CP59"  !CDS_PN = "CP59";
"VSS<398>":   PN = "CP25"  !CDS_PN = "CP25";
"VSS<399>":   PN = "H59"  !CDS_PN = "H59";
"VSS<400>":   PN = "CP1"  !CDS_PN = "CP1";
"VSS<401>":   PN = "CN78"  !CDS_PN = "CN78";
"VSS<402>":   PN = "CN68"  !CDS_PN = "CN68";
"VSS<403>":   PN = "CN62"  !CDS_PN = "CN62";
"VSS<404>":   PN = "CN60"  !CDS_PN = "CN60";
"VSS<405>":   PN = "CN32"  !CDS_PN = "CN32";
"VSS<406>":   PN = "CN26"  !CDS_PN = "CN26";
"VSS<407>":   PN = "H61"  !CDS_PN = "H61";
"VSS<408>":   PN = "CN12"  !CDS_PN = "CN12";
"VSS<409>":   PN = "CN2"  !CDS_PN = "CN2";
"VSS<410>":   PN = "CM85"  !CDS_PN = "CM85";
"VSS<411>":   PN = "CM83"  !CDS_PN = "CM83";
"VSS<412>":   PN = "CM77"  !CDS_PN = "CM77";
"VSS<413>":   PN = "CM73"  !CDS_PN = "CM73";
"VSS<414>":   PN = "CM67"  !CDS_PN = "CM67";
"VSS<415>":   PN = "CM63"  !CDS_PN = "CM63";
"VSS<416>":   PN = "CM61"  !CDS_PN = "CM61";
"VSS<417>":   PN = "CM31"  !CDS_PN = "CM31";
"VSS<418>":   PN = "CM5"  !CDS_PN = "CM5";
"VSS<419>":   PN = "CM29"  !CDS_PN = "CM29";
"VSS<420>":   PN = "CM19"  !CDS_PN = "CM19";
"VSS<421>":   PN = "CL80"  !CDS_PN = "CL80";
"VSS<422>":   PN = "CL78"  !CDS_PN = "CL78";
"VSS<423>":   PN = "CL76"  !CDS_PN = "CL76";
"VSS<424>":   PN = "CL74"  !CDS_PN = "CL74";
"VSS<425>":   PN = "CL66"  !CDS_PN = "CL66";
"VSS<426>":   PN = "CL64"  !CDS_PN = "CL64";
"VSS<427>":   PN = "CL62"  !CDS_PN = "CL62";
"VSS<428>":   PN = "H63"  !CDS_PN = "H63";
"VSS<429>":   PN = "P45"  !CDS_PN = "P45";
"VSS<430>":   PN = "CL18"  !CDS_PN = "CL18";
"VSS<431>":   PN = "CL14"  !CDS_PN = "CL14";
"VSS<432>":   PN = "CL8"  !CDS_PN = "CL8";
"VSS<433>":   PN = "CK85"  !CDS_PN = "CK85";
"VSS<434>":   PN = "CK83"  !CDS_PN = "CK83";
"VSS<435>":   PN = "CK75"  !CDS_PN = "CK75";
"VSS<436>":   PN = "CK73"  !CDS_PN = "CK73";
"VSS<437>":   PN = "CK71"  !CDS_PN = "CK71";
"VSS<438>":   PN = "CK69"  !CDS_PN = "CK69";
"VSS<439>":   PN = "CK67"  !CDS_PN = "CK67";
"VSS<440>":   PN = "CK65"  !CDS_PN = "CK65";
"VSS<441>":   PN = "CK63"  !CDS_PN = "CK63";
"VSS<442>":   PN = "CK27"  !CDS_PN = "CK27";
"VSS<443>":   PN = "CK21"  !CDS_PN = "CK21";
"VSS<444>":   PN = "CK15"  !CDS_PN = "CK15";
"VSS<445>":   PN = "CK11"  !CDS_PN = "CK11";
"VSS<446>":   PN = "CJ86"  !CDS_PN = "CJ86";
"VSS<447>":   PN = "CJ84"  !CDS_PN = "CJ84";
"VSS<448>":   PN = "CJ82"  !CDS_PN = "CJ82";
"VSS<449>":   PN = "CJ78"  !CDS_PN = "CJ78";
"VSS<450>":   PN = "CJ76"  !CDS_PN = "CJ76";
"VSS<451>":   PN = "CJ74"  !CDS_PN = "CJ74";
"VSS<452>":   PN = "CJ62"  !CDS_PN = "CJ62";
"VSS<453>":   PN = "P47"  !CDS_PN = "P47";
BODY = "SKX_EXT_B","I285": #LOCATION = "U5D1" !CDS_LOCATION = "U5D1" #SEC = "29" !CDS_SEC = "29";
"VSS<134>":   PN = "DN72"  !CDS_PN = "DN72";
"VSS<135>":   PN = "DN68"  !CDS_PN = "DN68";
"VSS<136>":   PN = "DN38"  !CDS_PN = "DN38";
"VSS<137>":   PN = "DN32"  !CDS_PN = "DN32";
"VSS<138>":   PN = "DN26"  !CDS_PN = "DN26";
"VSS<139>":   PN = "DN22"  !CDS_PN = "DN22";
"VSS<140>":   PN = "DN12"  !CDS_PN = "DN12";
"VSS<141>":   PN = "BH17"  !CDS_PN = "BH17";
"VSS<142>":   PN = "DN2"  !CDS_PN = "DN2";
"VSS<143>":   PN = "DM83"  !CDS_PN = "DM83";
"VSS<144>":   PN = "DM77"  !CDS_PN = "DM77";
"VSS<145>":   PN = "DM73"  !CDS_PN = "DM73";
"VSS<146>":   PN = "DM65"  !CDS_PN = "DM65";
"VSS<147>":   PN = "DM39"  !CDS_PN = "DM39";
"VSS<148>":   PN = "DM37"  !CDS_PN = "DM37";
"VSS<149>":   PN = "DM33"  !CDS_PN = "DM33";
"VSS<150>":   PN = "DM31"  !CDS_PN = "DM31";
"VSS<151>":   PN = "DM27"  !CDS_PN = "DM27";
"VSS<152>":   PN = "DM25"  !CDS_PN = "DM25";
"VSS<153>":   PN = "H45"  !CDS_PN = "H45";
"VSS<154>":   PN = "DM15"  !CDS_PN = "DM15";
"VSS<155>":   PN = "DL80"  !CDS_PN = "DL80";
"VSS<156>":   PN = "DL78"  !CDS_PN = "DL78";
"VSS<157>":   PN = "DL76"  !CDS_PN = "DL76";
"VSS<158>":   PN = "DL74"  !CDS_PN = "DL74";
"VSS<159>":   PN = "DL70"  !CDS_PN = "DL70";
"VSS<160>":   PN = "DL68"  !CDS_PN = "DL68";
"VSS<161>":   PN = "DL40"  !CDS_PN = "DL40";
"VSS<162>":   PN = "DL36"  !CDS_PN = "DL36";
"VSS<163>":   PN = "DL34"  !CDS_PN = "DL34";
"VSS<164>":   PN = "DL30"  !CDS_PN = "DL30";
"VSS<165>":   PN = "DL28"  !CDS_PN = "DL28";
"VSS<166>":   PN = "DL24"  !CDS_PN = "DL24";
"VSS<167>":   PN = "DL22"  !CDS_PN = "DL22";
"VSS<168>":   PN = "DL4"  !CDS_PN = "DL4";
"VSS<169>":   PN = "DL18"  !CDS_PN = "DL18";
"VSS<170>":   PN = "DL16"  !CDS_PN = "DL16";
"VSS<171>":   PN = "DK85"  !CDS_PN = "DK85";
"VSS<172>":   PN = "DK83"  !CDS_PN = "DK83";
"VSS<173>":   PN = "DK77"  !CDS_PN = "DK77";
"VSS<174>":   PN = "DK75"  !CDS_PN = "DK75";
"VSS<175>":   PN = "DK73"  !CDS_PN = "DK73";
"VSS<176>":   PN = "DK41"  !CDS_PN = "DK41";
"VSS<177>":   PN = "DK39"  !CDS_PN = "DK39";
"VSS<178>":   PN = "DK35"  !CDS_PN = "DK35";
"VSS<179>":   PN = "DK29"  !CDS_PN = "DK29";
"VSS<180>":   PN = "DK23"  !CDS_PN = "DK23";
"VSS<181>":   PN = "DK7"  !CDS_PN = "DK7";
"VSS<182>":   PN = "DJ84"  !CDS_PN = "DJ84";
"VSS<183>":   PN = "DJ82"  !CDS_PN = "DJ82";
"VSS<184>":   PN = "DJ78"  !CDS_PN = "DJ78";
"VSS<185>":   PN = "DJ74"  !CDS_PN = "DJ74";
"VSS<186>":   PN = "DJ68"  !CDS_PN = "DJ68";
"VSS<187>":   PN = "DJ42"  !CDS_PN = "DJ42";
"VSS<188>":   PN = "DJ38"  !CDS_PN = "DJ38";
"VSS<189>":   PN = "DJ22"  !CDS_PN = "DJ22";
"VSS<190>":   PN = "H47"  !CDS_PN = "H47";
"VSS<191>":   PN = "DJ10"  !CDS_PN = "DJ10";
"VSS<192>":   PN = "DJ2"  !CDS_PN = "DJ2";
"VSS<193>":   PN = "DH83"  !CDS_PN = "DH83";
"VSS<194>":   PN = "DH81"  !CDS_PN = "DH81";
"VSS<195>":   PN = "DH79"  !CDS_PN = "DH79";
"VSS<196>":   PN = "DH73"  !CDS_PN = "DH73";
"VSS<197>":   PN = "DH71"  !CDS_PN = "DH71";
"VSS<198>":   PN = "DH67"  !CDS_PN = "DH67";
"VSS<199>":   PN = "DH41"  !CDS_PN = "DH41";
"VSS<200>":   PN = "DH37"  !CDS_PN = "DH37";
"VSS<201>":   PN = "DH35"  !CDS_PN = "DH35";
"VSS<202>":   PN = "DH33"  !CDS_PN = "DH33";
"VSS<203>":   PN = "DH31"  !CDS_PN = "DH31";
"VSS<204>":   PN = "DH29"  !CDS_PN = "DH29";
"VSS<205>":   PN = "DH27"  !CDS_PN = "DH27";
"VSS<206>":   PN = "DH25"  !CDS_PN = "DH25";
"VSS<207>":   PN = "DH23"  !CDS_PN = "DH23";
"VSS<208>":   PN = "DH15"  !CDS_PN = "DH15";
"VSS<209>":   PN = "DH13"  !CDS_PN = "DH13";
"VSS<210>":   PN = "DG82"  !CDS_PN = "DG82";
"VSS<211>":   PN = "DG80"  !CDS_PN = "DG80";
"VSS<212>":   PN = "DG78"  !CDS_PN = "DG78";
"VSS<213>":   PN = "DG76"  !CDS_PN = "DG76";
"VSS<214>":   PN = "DG68"  !CDS_PN = "DG68";
"VSS<215>":   PN = "DG66"  !CDS_PN = "DG66";
"VSS<216>":   PN = "DG24"  !CDS_PN = "DG24";
"VSS<217>":   PN = "DG16"  !CDS_PN = "DG16";
"VSS<218>":   PN = "DG14"  !CDS_PN = "DG14";
"VSS<219>":   PN = "H49"  !CDS_PN = "H49";
"VSS<220>":   PN = "DG2"  !CDS_PN = "DG2";
"VSS<221>":   PN = "DF85"  !CDS_PN = "DF85";
"VSS<222>":   PN = "DF83"  !CDS_PN = "DF83";
"VSS<223>":   PN = "DF79"  !CDS_PN = "DF79";
"VSS<224>":   PN = "DF73"  !CDS_PN = "DF73";
"VSS<225>":   PN = "DF69"  !CDS_PN = "DF69";
"VSS<226>":   PN = "DF65"  !CDS_PN = "DF65";
"VSS<227>":   PN = "DF41"  !CDS_PN = "DF41";
"VSS<228>":   PN = "DF39"  !CDS_PN = "DF39";
"VSS<229>":   PN = "DF37"  !CDS_PN = "DF37";
"VSS<230>":   PN = "DF35"  !CDS_PN = "DF35";
"VSS<231>":   PN = "DF29"  !CDS_PN = "DF29";
"VSS<232>":   PN = "DF19"  !CDS_PN = "DF19";
"VSS<233>":   PN = "H51"  !CDS_PN = "H51";
"VSS<234>":   PN = "DF7"  !CDS_PN = "DF7";
"VSS<235>":   PN = "DF5"  !CDS_PN = "DF5";
"VSS<236>":   PN = "DE78"  !CDS_PN = "DE78";
"VSS<237>":   PN = "DE72"  !CDS_PN = "DE72";
"VSS<238>":   PN = "DE70"  !CDS_PN = "DE70";
"VSS<239>":   PN = "DE64"  !CDS_PN = "DE64";
"VSS<240>":   PN = "DE36"  !CDS_PN = "DE36";
"VSS<241>":   PN = "DE34"  !CDS_PN = "DE34";
"VSS<242>":   PN = "DE30"  !CDS_PN = "DE30";
"VSS<243>":   PN = "DE28"  !CDS_PN = "DE28";
"VSS<244>":   PN = "DE24"  !CDS_PN = "DE24";
"VSS<245>":   PN = "DE20"  !CDS_PN = "DE20";
"VSS<246>":   PN = "DE18"  !CDS_PN = "DE18";
"VSS<247>":   PN = "DE8"  !CDS_PN = "DE8";
"VSS<248>":   PN = "DE6"  !CDS_PN = "DE6";
"VSS<249>":   PN = "DD83"  !CDS_PN = "DD83";
"VSS<250>":   PN = "DD81"  !CDS_PN = "DD81";
"VSS<251>":   PN = "DD75"  !CDS_PN = "DD75";
"VSS<252>":   PN = "DD73"  !CDS_PN = "DD73";
"VSS<253>":   PN = "DD71"  !CDS_PN = "DD71";
"VSS<254>":   PN = "DD37"  !CDS_PN = "DD37";
"VSS<255>":   PN = "DD33"  !CDS_PN = "DD33";
"VSS<256>":   PN = "DD31"  !CDS_PN = "DD31";
"VSS<257>":   PN = "DD27"  !CDS_PN = "DD27";
"VSS<258>":   PN = "DD23"  !CDS_PN = "DD23";
"VSS<259>":   PN = "DD11"  !CDS_PN = "DD11";
"VSS<260>":   PN = "DC86"  !CDS_PN = "DC86";
"VSS<261>":   PN = "DC84"  !CDS_PN = "DC84";
"VSS<262>":   PN = "DC78"  !CDS_PN = "DC78";
"VSS<263>":   PN = "DC70"  !CDS_PN = "DC70";
"VSS<264>":   PN = "DC68"  !CDS_PN = "DC68";
"VSS<265>":   PN = "DC66"  !CDS_PN = "DC66";
"VSS<266>":   PN = "DC64"  !CDS_PN = "DC64";
"VSS<267>":   PN = "DC42"  !CDS_PN = "DC42";
"VSS<268>":   PN = "DC38"  !CDS_PN = "DC38";
"VSS<269>":   PN = "DC32"  !CDS_PN = "DC32";
"VSS<270>":   PN = "DC26"  !CDS_PN = "DC26";
"VSS<271>":   PN = "DC24"  !CDS_PN = "DC24";
"VSS<272>":   PN = "DC14"  !CDS_PN = "DC14";
"VSS<273>":   PN = "DB85"  !CDS_PN = "DB85";
"VSS<274>":   PN = "DB83"  !CDS_PN = "DB83";
"VSS<275>":   PN = "DB77"  !CDS_PN = "DB77";
"VSS<276>":   PN = "DB73"  !CDS_PN = "DB73";
"VSS<277>":   PN = "DB49"  !CDS_PN = "DB49";
"VSS<278>":   PN = "DB47"  !CDS_PN = "DB47";
"VSS<279>":   PN = "DB41"  !CDS_PN = "DB41";
"VSS<280>":   PN = "DB39"  !CDS_PN = "DB39";
"VSS<281>":   PN = "DB25"  !CDS_PN = "DB25";
"VSS<282>":   PN = "DB23"  !CDS_PN = "DB23";
"VSS<283>":   PN = "DB17"  !CDS_PN = "DB17";
"VSS<284>":   PN = "DB13"  !CDS_PN = "DB13";
"VSS<285>":   PN = "DB3"  !CDS_PN = "DB3";
"VSS<286>":   PN = "DA80"  !CDS_PN = "DA80";
"VSS<287>":   PN = "DA78"  !CDS_PN = "DA78";
"VSS<288>":   PN = "DA76"  !CDS_PN = "DA76";
"VSS<289>":   PN = "DA74"  !CDS_PN = "DA74";
"VSS<290>":   PN = "DA70"  !CDS_PN = "DA70";
"VSS<291>":   PN = "DA64"  !CDS_PN = "DA64";
"VSS<292>":   PN = "DA50"  !CDS_PN = "DA50";
"VSS<293>":   PN = "DA48"  !CDS_PN = "DA48";
BODY = "SKX_EXT_B","I286": #LOCATION = "U5D1" !CDS_LOCATION = "U5D1" #SEC = "30" !CDS_SEC = "30";
"VSS<0>":   PN = "EF79"  !CDS_PN = "EF79";
"VSS<1>":   PN = "EF75"  !CDS_PN = "EF75";
"VSS<2>":   PN = "EF71"  !CDS_PN = "EF71";
"VSS<3>":   PN = "EE78"  !CDS_PN = "EE78";
"VSS<4>":   PN = "EE76"  !CDS_PN = "EE76";
"VSS<5>":   PN = "EE70"  !CDS_PN = "EE70";
"VSS<6>":   PN = "EE36"  !CDS_PN = "EE36";
"VSS<7>":   PN = "EE34"  !CDS_PN = "EE34";
"VSS<8>":   PN = "EE30"  !CDS_PN = "EE30";
"VSS<9>":   PN = "EE28"  !CDS_PN = "EE28";
"VSS<10>":   PN = "EE24"  !CDS_PN = "EE24";
"VSS<11>":   PN = "ED77"  !CDS_PN = "ED77";
"VSS<12>":   PN = "ED35"  !CDS_PN = "ED35";
"VSS<13>":   PN = "ED29"  !CDS_PN = "ED29";
"VSS<14>":   PN = "ED23"  !CDS_PN = "ED23";
"VSS<15>":   PN = "ED15"  !CDS_PN = "ED15";
"VSS<16>":   PN = "ED11"  !CDS_PN = "ED11";
"VSS<17>":   PN = "EC76"  !CDS_PN = "EC76";
"VSS<18>":   PN = "EC74"  !CDS_PN = "EC74";
"VSS<19>":   PN = "EC72"  !CDS_PN = "EC72";
"VSS<20>":   PN = "EC70"  !CDS_PN = "EC70";
"VSS<21>":   PN = "EC10"  !CDS_PN = "EC10";
"VSS<22>":   PN = "EB69"  !CDS_PN = "EB69";
"VSS<23>":   PN = "EB65"  !CDS_PN = "EB65";
"VSS<24>":   PN = "EB41"  !CDS_PN = "EB41";
"VSS<25>":   PN = "EB39"  !CDS_PN = "EB39";
"VSS<26>":   PN = "EB37"  !CDS_PN = "EB37";
"VSS<27>":   PN = "EB35"  !CDS_PN = "EB35";
"VSS<28>":   PN = "EB33"  !CDS_PN = "EB33";
"VSS<29>":   PN = "EB31"  !CDS_PN = "EB31";
"VSS<30>":   PN = "EB29"  !CDS_PN = "EB29";
"VSS<31>":   PN = "EB27"  !CDS_PN = "EB27";
"VSS<32>":   PN = "EB25"  !CDS_PN = "EB25";
"VSS<33>":   PN = "EB23"  !CDS_PN = "EB23";
"VSS<34>":   PN = "BR18"  !CDS_PN = "BR18";
"VSS<35>":   PN = "EB13"  !CDS_PN = "EB13";
"VSS<36>":   PN = "EA82"  !CDS_PN = "EA82";
"VSS<37>":   PN = "EA80"  !CDS_PN = "EA80";
"VSS<38>":   PN = "EA78"  !CDS_PN = "EA78";
"VSS<39>":   PN = "EA76"  !CDS_PN = "EA76";
"VSS<40>":   PN = "EA70"  !CDS_PN = "EA70";
"VSS<41>":   PN = "EA64"  !CDS_PN = "EA64";
"VSS<42>":   PN = "EA42"  !CDS_PN = "EA42";
"VSS<43>":   PN = "EA22"  !CDS_PN = "EA22";
"VSS<44>":   PN = "EA20"  !CDS_PN = "EA20";
"VSS<45>":   PN = "EA16"  !CDS_PN = "EA16";
"VSS<46>":   PN = "J16"  !CDS_PN = "J16";
"VSS<47>":   PN = "EA6"  !CDS_PN = "EA6";
"VSS<48>":   PN = "DY75"  !CDS_PN = "DY75";
"VSS<49>":   PN = "DY71"  !CDS_PN = "DY71";
"VSS<50>":   PN = "DY41"  !CDS_PN = "DY41";
"VSS<51>":   PN = "DY35"  !CDS_PN = "DY35";
"VSS<52>":   PN = "DY29"  !CDS_PN = "DY29";
"VSS<53>":   PN = "DY23"  !CDS_PN = "DY23";
"VSS<54>":   PN = "DY19"  !CDS_PN = "DY19";
"VSS<55>":   PN = "DY5"  !CDS_PN = "DY5";
"VSS<56>":   PN = "DW84"  !CDS_PN = "DW84";
"VSS<57>":   PN = "DW82"  !CDS_PN = "DW82";
"VSS<58>":   PN = "DW8"  !CDS_PN = "DW8";
"VSS<59>":   PN = "DW76"  !CDS_PN = "DW76";
"VSS<60>":   PN = "DW74"  !CDS_PN = "DW74";
"VSS<61>":   PN = "DW72"  !CDS_PN = "DW72";
"VSS<62>":   PN = "DW70"  !CDS_PN = "DW70";
"VSS<63>":   PN = "DW68"  !CDS_PN = "DW68";
"VSS<64>":   PN = "DW66"  !CDS_PN = "DW66";
"VSS<65>":   PN = "DW64"  !CDS_PN = "DW64";
"VSS<66>":   PN = "DW40"  !CDS_PN = "DW40";
"VSS<67>":   PN = "DW36"  !CDS_PN = "DW36";
"VSS<68>":   PN = "DW34"  !CDS_PN = "DW34";
"VSS<69>":   PN = "DW30"  !CDS_PN = "DW30";
"VSS<70>":   PN = "DW28"  !CDS_PN = "DW28";
"VSS<71>":   PN = "DW24"  !CDS_PN = "DW24";
"VSS<72>":   PN = "DW20"  !CDS_PN = "DW20";
"VSS<73>":   PN = "DW12"  !CDS_PN = "DW12";
"VSS<74>":   PN = "DV81"  !CDS_PN = "DV81";
"VSS<75>":   PN = "DV77"  !CDS_PN = "DV77";
"VSS<76>":   PN = "DV73"  !CDS_PN = "DV73";
"VSS<77>":   PN = "DV39"  !CDS_PN = "DV39";
"VSS<78>":   PN = "DV37"  !CDS_PN = "DV37";
"VSS<79>":   PN = "DV33"  !CDS_PN = "DV33";
"VSS<80>":   PN = "DV31"  !CDS_PN = "DV31";
"VSS<81>":   PN = "DV27"  !CDS_PN = "DV27";
"VSS<82>":   PN = "DV25"  !CDS_PN = "DV25";
"VSS<83>":   PN = "DV21"  !CDS_PN = "DV21";
"VSS<84>":   PN = "DU84"  !CDS_PN = "DU84";
"VSS<85>":   PN = "DU82"  !CDS_PN = "DU82";
"VSS<86>":   PN = "DU80"  !CDS_PN = "DU80";
"VSS<87>":   PN = "DU78"  !CDS_PN = "DU78";
"VSS<88>":   PN = "DU72"  !CDS_PN = "DU72";
"VSS<89>":   PN = "DU70"  !CDS_PN = "DU70";
"VSS<90>":   PN = "DU38"  !CDS_PN = "DU38";
"VSS<91>":   PN = "DU32"  !CDS_PN = "DU32";
"VSS<92>":   PN = "DU26"  !CDS_PN = "DU26";
"VSS<93>":   PN = "DU22"  !CDS_PN = "DU22";
"VSS<94>":   PN = "CN14"  !CDS_PN = "CN14";
"VSS<95>":   PN = "DU14"  !CDS_PN = "DU14";
"VSS<96>":   PN = "DU10"  !CDS_PN = "DU10";
"VSS<97>":   PN = "DT85"  !CDS_PN = "DT85";
"VSS<98>":   PN = "DT83"  !CDS_PN = "DT83";
"VSS<99>":   PN = "DT79"  !CDS_PN = "DT79";
"VSS<100>":   PN = "DT69"  !CDS_PN = "DT69";
"VSS<101>":   PN = "DT65"  !CDS_PN = "DT65";
"VSS<102>":   PN = "DH21"  !CDS_PN = "DH21";
"VSS<103>":   PN = "DT17"  !CDS_PN = "DT17";
"VSS<104>":   PN = "DT3"  !CDS_PN = "DT3";
"VSS<105>":   PN = "DR78"  !CDS_PN = "DR78";
"VSS<106>":   PN = "DR76"  !CDS_PN = "DR76";
"VSS<107>":   PN = "DR74"  !CDS_PN = "DR74";
"VSS<108>":   PN = "DR72"  !CDS_PN = "DR72";
"VSS<109>":   PN = "DR70"  !CDS_PN = "DR70";
"VSS<110>":   PN = "DR68"  !CDS_PN = "DR68";
"VSS<111>":   PN = "DR66"  !CDS_PN = "DR66";
"VSS<112>":   PN = "DR42"  !CDS_PN = "DR42";
"VSS<113>":   PN = "DR40"  !CDS_PN = "DR40";
"VSS<114>":   PN = "DR38"  !CDS_PN = "DR38";
"VSS<115>":   PN = "DR36"  !CDS_PN = "DR36";
"VSS<116>":   PN = "DR34"  !CDS_PN = "DR34";
"VSS<117>":   PN = "DR32"  !CDS_PN = "DR32";
"VSS<118>":   PN = "DR30"  !CDS_PN = "DR30";
"VSS<119>":   PN = "DR28"  !CDS_PN = "DR28";
"VSS<120>":   PN = "DR26"  !CDS_PN = "DR26";
"VSS<121>":   PN = "DR24"  !CDS_PN = "DR24";
"VSS<122>":   PN = "DR22"  !CDS_PN = "DR22";
"VSS<123>":   PN = "DR20"  !CDS_PN = "DR20";
"VSS<124>":   PN = "CL22"  !CDS_PN = "CL22";
"VSS<125>":   PN = "CA20"  !CDS_PN = "CA20";
"VSS<126>":   PN = "DR6"  !CDS_PN = "DR6";
"VSS<127>":   PN = "BR26"  !CDS_PN = "BR26";
"VSS<128>":   PN = "DP83"  !CDS_PN = "DP83";
"VSS<129>":   PN = "DP81"  !CDS_PN = "DP81";
"VSS<130>":   PN = "DP71"  !CDS_PN = "DP71";
"VSS<131>":   PN = "DP69"  !CDS_PN = "DP69";
"VSS<132>":   PN = "DP67"  !CDS_PN = "DP67";
"VSS<133>":   PN = "DN78"  !CDS_PN = "DN78";
DRAWING = "@baseboard_fab2_lib.baseboard_fab2(sch_1):page42";
BODY = "CAP","I2": #LOCATION = "C5P18" !CDS_LOCATION = "C5P18" &SEC = "1" #&CDS_SEC = "1";
"A":   PN = "1"  !CDS_PN = "1";
"B":   PN = "2"  !CDS_PN = "2";
BODY = "CAP","I3": #LOCATION = "C5P28" !CDS_LOCATION = "C5P28" &SEC = "1" #&CDS_SEC = "1";
"A":   PN = "1"  !CDS_PN = "1";
"B":   PN = "2"  !CDS_PN = "2";
BODY = "CAP","I4": #LOCATION = "C5P11" !CDS_LOCATION = "C5P11" &SEC = "1" #&CDS_SEC = "1";
"A":   PN = "1"  !CDS_PN = "1";
"B":   PN = "2"  !CDS_PN = "2";
BODY = "CAP","I6": #LOCATION = "C5P10" !CDS_LOCATION = "C5P10" &SEC = "1" #&CDS_SEC = "1";
"A":   PN = "1"  !CDS_PN = "1";
"B":   PN = "2"  !CDS_PN = "2";
BODY = "CAP","I8": #LOCATION = "C4P3" !CDS_LOCATION = "C4P3" &SEC = "1" #&CDS_SEC = "1";
"A":   PN = "1"  !CDS_PN = "1";
"B":   PN = "2"  !CDS_PN = "2";
BODY = "CAP","I9": #LOCATION = "C4P7" !CDS_LOCATION = "C4P7" &SEC = "1" #&CDS_SEC = "1";
"A":   PN = "1"  !CDS_PN = "1";
"B":   PN = "2"  !CDS_PN = "2";
BODY = "CAP","I10": #LOCATION = "C4P1" !CDS_LOCATION = "C4P1" &SEC = "1" #&CDS_SEC = "1";
"A":   PN = "1"  !CDS_PN = "1";
"B":   PN = "2"  !CDS_PN = "2";
BODY = "CAP","I12": #LOCATION = "C4P9" !CDS_LOCATION = "C4P9" &SEC = "1" #&CDS_SEC = "1";
"A":   PN = "1"  !CDS_PN = "1";
"B":   PN = "2"  !CDS_PN = "2";
BODY = "CAP","I13": #LOCATION = "C5P19" !CDS_LOCATION = "C5P19" &SEC = "1" #&CDS_SEC = "1";
"A":   PN = "1"  !CDS_PN = "1";
"B":   PN = "2"  !CDS_PN = "2";
BODY = "CAP","I14": #LOCATION = "C4P4" !CDS_LOCATION = "C4P4" &SEC = "1" #&CDS_SEC = "1";
"A":   PN = "1"  !CDS_PN = "1";
"B":   PN = "2"  !CDS_PN = "2";
BODY = "CAP","I17": #LOCATION = "C4P10" !CDS_LOCATION = "C4P10" &SEC = "1" #&CDS_SEC = "1";
"A":   PN = "1"  !CDS_PN = "1";
"B":   PN = "2"  !CDS_PN = "2";
BODY = "CAP","I18": #LOCATION = "C5P9" !CDS_LOCATION = "C5P9" &SEC = "1" #&CDS_SEC = "1";
"A":   PN = "1"  !CDS_PN = "1";
"B":   PN = "2"  !CDS_PN = "2";
BODY = "CAP","I19": #LOCATION = "C5P8" !CDS_LOCATION = "C5P8" &SEC = "1" #&CDS_SEC = "1";
"A":   PN = "1"  !CDS_PN = "1";
"B":   PN = "2"  !CDS_PN = "2";
BODY = "CAP","I25": #LOCATION = "C5P7" !CDS_LOCATION = "C5P7" &SEC = "1" #&CDS_SEC = "1";
"A":   PN = "1"  !CDS_PN = "1";
"B":   PN = "2"  !CDS_PN = "2";
BODY = "CAP","I27": #LOCATION = "C5P4" !CDS_LOCATION = "C5P4" &SEC = "1" #&CDS_SEC = "1";
"A":   PN = "1"  !CDS_PN = "1";
"B":   PN = "2"  !CDS_PN = "2";
BODY = "CAP","I28": #LOCATION = "C5P23" !CDS_LOCATION = "C5P23" &SEC = "1" #&CDS_SEC = "1";
"A":   PN = "1"  !CDS_PN = "1";
"B":   PN = "2"  !CDS_PN = "2";
BODY = "CAP","I33": #LOCATION = "C5P24" !CDS_LOCATION = "C5P24" &SEC = "1" #&CDS_SEC = "1";
"A":   PN = "1"  !CDS_PN = "1";
"B":   PN = "2"  !CDS_PN = "2";
BODY = "CAP","I37": #LOCATION = "C5P25" !CDS_LOCATION = "C5P25" &SEC = "1" #&CDS_SEC = "1";
"A":   PN = "1"  !CDS_PN = "1";
"B":   PN = "2"  !CDS_PN = "2";
BODY = "CAP","I38": #LOCATION = "C5P6" !CDS_LOCATION = "C5P6" &SEC = "1" #&CDS_SEC = "1";
"A":   PN = "1"  !CDS_PN = "1";
"B":   PN = "2"  !CDS_PN = "2";
BODY = "CAP","I40": #LOCATION = "C5P41" !CDS_LOCATION = "C5P41" &SEC = "1" #&CDS_SEC = "1";
"A":   PN = "1"  !CDS_PN = "1";
"B":   PN = "2"  !CDS_PN = "2";
BODY = "CAP","I41": #LOCATION = "C5P14" !CDS_LOCATION = "C5P14" &SEC = "1" #&CDS_SEC = "1";
"A":   PN = "1"  !CDS_PN = "1";
"B":   PN = "2"  !CDS_PN = "2";
BODY = "CAP","I42": #LOCATION = "C5P5" !CDS_LOCATION = "C5P5" &SEC = "1" #&CDS_SEC = "1";
"A":   PN = "1"  !CDS_PN = "1";
"B":   PN = "2"  !CDS_PN = "2";
BODY = "CAP","I44": #LOCATION = "C5P27" !CDS_LOCATION = "C5P27" &SEC = "1" #&CDS_SEC = "1";
"A":   PN = "1"  !CDS_PN = "1";
"B":   PN = "2"  !CDS_PN = "2";
BODY = "CAP","I50": #LOCATION = "C5P33" !CDS_LOCATION = "C5P33" &SEC = "1" #&CDS_SEC = "1";
"A":   PN = "1"  !CDS_PN = "1";
"B":   PN = "2"  !CDS_PN = "2";
BODY = "CAP","I51": #LOCATION = "C5P35" !CDS_LOCATION = "C5P35" &SEC = "1" #&CDS_SEC = "1";
"A":   PN = "1"  !CDS_PN = "1";
"B":   PN = "2"  !CDS_PN = "2";
BODY = "CAP","I53": #LOCATION = "C5P32" !CDS_LOCATION = "C5P32" &SEC = "1" #&CDS_SEC = "1";
"A":   PN = "1"  !CDS_PN = "1";
"B":   PN = "2"  !CDS_PN = "2";
BODY = "CAP","I54": #LOCATION = "C5P34" !CDS_LOCATION = "C5P34" &SEC = "1" #&CDS_SEC = "1";
"A":   PN = "1"  !CDS_PN = "1";
"B":   PN = "2"  !CDS_PN = "2";
BODY = "CAP","I55": #LOCATION = "C5P22" !CDS_LOCATION = "C5P22" &SEC = "1" #&CDS_SEC = "1";
"A":   PN = "1"  !CDS_PN = "1";
"B":   PN = "2"  !CDS_PN = "2";
BODY = "CAP","I56": #LOCATION = "C5P26" !CDS_LOCATION = "C5P26" &SEC = "1" #&CDS_SEC = "1";
"A":   PN = "1"  !CDS_PN = "1";
"B":   PN = "2"  !CDS_PN = "2";
BODY = "CAP","I57": #LOCATION = "C5P40" !CDS_LOCATION = "C5P40" &SEC = "1" #&CDS_SEC = "1";
"A":   PN = "1"  !CDS_PN = "1";
"B":   PN = "2"  !CDS_PN = "2";
BODY = "CAP","I59": #LOCATION = "C5P42" !CDS_LOCATION = "C5P42" &SEC = "1" #&CDS_SEC = "1";
"A":   PN = "1"  !CDS_PN = "1";
"B":   PN = "2"  !CDS_PN = "2";
BODY = "CAP","I60": #LOCATION = "C5P43" !CDS_LOCATION = "C5P43" &SEC = "1" #&CDS_SEC = "1";
"A":   PN = "1"  !CDS_PN = "1";
"B":   PN = "2"  !CDS_PN = "2";
BODY = "CAP","I61": #LOCATION = "C5P44" !CDS_LOCATION = "C5P44" &SEC = "1" #&CDS_SEC = "1";
"A":   PN = "1"  !CDS_PN = "1";
"B":   PN = "2"  !CDS_PN = "2";
BODY = "CAP","I63": #LOCATION = "C5P37" !CDS_LOCATION = "C5P37" &SEC = "1" #&CDS_SEC = "1";
"A":   PN = "1"  !CDS_PN = "1";
"B":   PN = "2"  !CDS_PN = "2";
BODY = "CAP","I65": #LOCATION = "C5P36" !CDS_LOCATION = "C5P36" &SEC = "1" #&CDS_SEC = "1";
"A":   PN = "1"  !CDS_PN = "1";
"B":   PN = "2"  !CDS_PN = "2";
BODY = "CAP_A","I68": #LOCATION = "C6D8" !CDS_LOCATION = "C6D8" &SEC = "1" #&CDS_SEC = "1";
"A":   PN = "1"  !CDS_PN = "1";
"B":   PN = "2"  !CDS_PN = "2";
BODY = "CAP_A","I69": #LOCATION = "C5D38" !CDS_LOCATION = "C5D38" &SEC = "1" #&CDS_SEC = "1";
"A":   PN = "1"  !CDS_PN = "1";
"B":   PN = "2"  !CDS_PN = "2";
BODY = "CAP_A","I70": #LOCATION = "C5D37" !CDS_LOCATION = "C5D37" &SEC = "1" #&CDS_SEC = "1";
"A":   PN = "1"  !CDS_PN = "1";
"B":   PN = "2"  !CDS_PN = "2";
BODY = "CAP_A","I72": #LOCATION = "C6D7" !CDS_LOCATION = "C6D7" &SEC = "1" #&CDS_SEC = "1";
"A":   PN = "1"  !CDS_PN = "1";
"B":   PN = "2"  !CDS_PN = "2";
BODY = "CAP_A","I74": #LOCATION = "C6D4" !CDS_LOCATION = "C6D4" &SEC = "1" #&CDS_SEC = "1";
"A":   PN = "1"  !CDS_PN = "1";
"B":   PN = "2"  !CDS_PN = "2";
BODY = "CAP_A","I75": #LOCATION = "C6D5" !CDS_LOCATION = "C6D5" &SEC = "1" #&CDS_SEC = "1";
"A":   PN = "1"  !CDS_PN = "1";
"B":   PN = "2"  !CDS_PN = "2";
BODY = "CAP_A","I77": #LOCATION = "C6D2" !CDS_LOCATION = "C6D2" &SEC = "1" #&CDS_SEC = "1";
"A":   PN = "1"  !CDS_PN = "1";
"B":   PN = "2"  !CDS_PN = "2";
BODY = "CAP_A","I80": #LOCATION = "C6D3" !CDS_LOCATION = "C6D3" &SEC = "1" #&CDS_SEC = "1";
"A":   PN = "1"  !CDS_PN = "1";
"B":   PN = "2"  !CDS_PN = "2";
BODY = "CAP_A","I81": #LOCATION = "C6D6" !CDS_LOCATION = "C6D6" &SEC = "1" #&CDS_SEC = "1";
"A":   PN = "1"  !CDS_PN = "1";
"B":   PN = "2"  !CDS_PN = "2";
BODY = "CAP_A","I83": #LOCATION = "C5D51" !CDS_LOCATION = "C5D51" &SEC = "1" #&CDS_SEC = "1";
"A":   PN = "1"  !CDS_PN = "1";
"B":   PN = "2"  !CDS_PN = "2";
BODY = "CAP_A","I88": #LOCATION = "C5D21" !CDS_LOCATION = "C5D21" &SEC = "1" #&CDS_SEC = "1";
"A":   PN = "1"  !CDS_PN = "1";
"B":   PN = "2"  !CDS_PN = "2";
BODY = "CAP_A","I89": #LOCATION = "C5D50" !CDS_LOCATION = "C5D50" &SEC = "1" #&CDS_SEC = "1";
"A":   PN = "1"  !CDS_PN = "1";
"B":   PN = "2"  !CDS_PN = "2";
BODY = "CAP_A","I90": #LOCATION = "C5D48" !CDS_LOCATION = "C5D48" &SEC = "1" #&CDS_SEC = "1";
"A":   PN = "1"  !CDS_PN = "1";
"B":   PN = "2"  !CDS_PN = "2";
BODY = "CAP","I91": #LOCATION = "C5D13" !CDS_LOCATION = "C5D13" &SEC = "1" #&CDS_SEC = "1";
"A":   PN = "1"  !CDS_PN = "1";
"B":   PN = "2"  !CDS_PN = "2";
BODY = "CAP","I93": #LOCATION = "C5D11" !CDS_LOCATION = "C5D11" &SEC = "1" #&CDS_SEC = "1";
"A":   PN = "1"  !CDS_PN = "1";
"B":   PN = "2"  !CDS_PN = "2";
BODY = "CAP","I94": #LOCATION = "C5D12" !CDS_LOCATION = "C5D12" &SEC = "1" #&CDS_SEC = "1";
"A":   PN = "1"  !CDS_PN = "1";
"B":   PN = "2"  !CDS_PN = "2";
BODY = "CAP_A","I98": #LOCATION = "C5D23" !CDS_LOCATION = "C5D23" &SEC = "1" #&CDS_SEC = "1";
"A":   PN = "1"  !CDS_PN = "1";
"B":   PN = "2"  !CDS_PN = "2";
BODY = "CAP_A","I100": #LOCATION = "C5D28" !CDS_LOCATION = "C5D28" &SEC = "1" #&CDS_SEC = "1";
"A":   PN = "1"  !CDS_PN = "1";
"B":   PN = "2"  !CDS_PN = "2";
BODY = "CAP_A","I102": #LOCATION = "C5D29" !CDS_LOCATION = "C5D29" &SEC = "1" #&CDS_SEC = "1";
"A":   PN = "1"  !CDS_PN = "1";
"B":   PN = "2"  !CDS_PN = "2";
BODY = "CAP_A","I103": #LOCATION = "C5D32" !CDS_LOCATION = "C5D32" &SEC = "1" #&CDS_SEC = "1";
"A":   PN = "1"  !CDS_PN = "1";
"B":   PN = "2"  !CDS_PN = "2";
BODY = "CAP_A","I104": #LOCATION = "C5D47" !CDS_LOCATION = "C5D47" &SEC = "1" #&CDS_SEC = "1";
"A":   PN = "1"  !CDS_PN = "1";
"B":   PN = "2"  !CDS_PN = "2";
BODY = "CAP_A","I106": #LOCATION = "C5D31" !CDS_LOCATION = "C5D31" &SEC = "1" #&CDS_SEC = "1";
"A":   PN = "1"  !CDS_PN = "1";
"B":   PN = "2"  !CDS_PN = "2";
BODY = "CAP_A","I107": #LOCATION = "C5D46" !CDS_LOCATION = "C5D46" &SEC = "1" #&CDS_SEC = "1";
"A":   PN = "1"  !CDS_PN = "1";
"B":   PN = "2"  !CDS_PN = "2";
BODY = "CAP","I108": #LOCATION = "C5D10" !CDS_LOCATION = "C5D10" &SEC = "1" #&CDS_SEC = "1";
"A":   PN = "1"  !CDS_PN = "1";
"B":   PN = "2"  !CDS_PN = "2";
BODY = "CAP_A","I109": #LOCATION = "C5D27" !CDS_LOCATION = "C5D27" &SEC = "1" #&CDS_SEC = "1";
"A":   PN = "1"  !CDS_PN = "1";
"B":   PN = "2"  !CDS_PN = "2";
BODY = "CAP_A","I111": #LOCATION = "C5D30" !CDS_LOCATION = "C5D30" &SEC = "1" #&CDS_SEC = "1";
"A":   PN = "1"  !CDS_PN = "1";
"B":   PN = "2"  !CDS_PN = "2";
BODY = "CAP_A","I112": #LOCATION = "C5D60" !CDS_LOCATION = "C5D60" &SEC = "1" #&CDS_SEC = "1";
"A":   PN = "1"  !CDS_PN = "1";
"B":   PN = "2"  !CDS_PN = "2";
BODY = "CAP_A","I113": #LOCATION = "C5D61" !CDS_LOCATION = "C5D61" &SEC = "1" #&CDS_SEC = "1";
"A":   PN = "1"  !CDS_PN = "1";
"B":   PN = "2"  !CDS_PN = "2";
BODY = "CAP_A","I114": #LOCATION = "C5D41" !CDS_LOCATION = "C5D41" &SEC = "1" #&CDS_SEC = "1";
"A":   PN = "1"  !CDS_PN = "1";
"B":   PN = "2"  !CDS_PN = "2";
BODY = "CAP_A","I115": #LOCATION = "C5D40" !CDS_LOCATION = "C5D40" &SEC = "1" #&CDS_SEC = "1";
"A":   PN = "1"  !CDS_PN = "1";
"B":   PN = "2"  !CDS_PN = "2";
BODY = "CAP_A","I117": #LOCATION = "C5D14" !CDS_LOCATION = "C5D14" &SEC = "1" #&CDS_SEC = "1";
"A":   PN = "1"  !CDS_PN = "1";
"B":   PN = "2"  !CDS_PN = "2";
BODY = "CAP_A","I118": #LOCATION = "C5D17" !CDS_LOCATION = "C5D17" &SEC = "1" #&CDS_SEC = "1";
"A":   PN = "1"  !CDS_PN = "1";
"B":   PN = "2"  !CDS_PN = "2";
BODY = "CAP_A","I120": #LOCATION = "C5D58" !CDS_LOCATION = "C5D58" &SEC = "1" #&CDS_SEC = "1";
"A":   PN = "1"  !CDS_PN = "1";
"B":   PN = "2"  !CDS_PN = "2";
BODY = "CAP_A","I123": #LOCATION = "C5D16" !CDS_LOCATION = "C5D16" &SEC = "1" #&CDS_SEC = "1";
"A":   PN = "1"  !CDS_PN = "1";
"B":   PN = "2"  !CDS_PN = "2";
BODY = "CAP_A","I125": #LOCATION = "C5D5" !CDS_LOCATION = "C5D5" &SEC = "1" #&CDS_SEC = "1";
"A":   PN = "1"  !CDS_PN = "1";
"B":   PN = "2"  !CDS_PN = "2";
BODY = "CAP_A","I126": #LOCATION = "C5D1" !CDS_LOCATION = "C5D1" &SEC = "1" #&CDS_SEC = "1";
"A":   PN = "1"  !CDS_PN = "1";
"B":   PN = "2"  !CDS_PN = "2";
BODY = "CAP_A","I127": #LOCATION = "C5D4" !CDS_LOCATION = "C5D4" &SEC = "1" #&CDS_SEC = "1";
"A":   PN = "1"  !CDS_PN = "1";
"B":   PN = "2"  !CDS_PN = "2";
BODY = "CAP_A","I128": #LOCATION = "C5D19" !CDS_LOCATION = "C5D19" &SEC = "1" #&CDS_SEC = "1";
"A":   PN = "1"  !CDS_PN = "1";
"B":   PN = "2"  !CDS_PN = "2";
BODY = "CAP_A","I129": #LOCATION = "C5D59" !CDS_LOCATION = "C5D59" &SEC = "1" #&CDS_SEC = "1";
"A":   PN = "1"  !CDS_PN = "1";
"B":   PN = "2"  !CDS_PN = "2";
BODY = "CAP_A","I130": #LOCATION = "C5D3" !CDS_LOCATION = "C5D3" &SEC = "1" #&CDS_SEC = "1";
"A":   PN = "1"  !CDS_PN = "1";
"B":   PN = "2"  !CDS_PN = "2";
BODY = "CAP_A","I131": #LOCATION = "C5D43" !CDS_LOCATION = "C5D43" &SEC = "1" #&CDS_SEC = "1";
"A":   PN = "1"  !CDS_PN = "1";
"B":   PN = "2"  !CDS_PN = "2";
BODY = "CAP_A","I132": #LOCATION = "C5D15" !CDS_LOCATION = "C5D15" &SEC = "1" #&CDS_SEC = "1";
"A":   PN = "1"  !CDS_PN = "1";
"B":   PN = "2"  !CDS_PN = "2";
BODY = "CAP_A","I134": #LOCATION = "C5D18" !CDS_LOCATION = "C5D18" &SEC = "1" #&CDS_SEC = "1";
"A":   PN = "1"  !CDS_PN = "1";
"B":   PN = "2"  !CDS_PN = "2";
BODY = "CAP_A","I135": #LOCATION = "C5D42" !CDS_LOCATION = "C5D42" &SEC = "1" #&CDS_SEC = "1";
"A":   PN = "1"  !CDS_PN = "1";
"B":   PN = "2"  !CDS_PN = "2";
BODY = "CAP_A","I136": #LOCATION = "C5D2" !CDS_LOCATION = "C5D2" &SEC = "1" #&CDS_SEC = "1";
"A":   PN = "1"  !CDS_PN = "1";
"B":   PN = "2"  !CDS_PN = "2";
BODY = "CAP_A","I138": #LOCATION = "C5D24" !CDS_LOCATION = "C5D24" &SEC = "1" #&CDS_SEC = "1";
"A":   PN = "1"  !CDS_PN = "1";
"B":   PN = "2"  !CDS_PN = "2";
BODY = "CAP_A","I140": #LOCATION = "C5D39" !CDS_LOCATION = "C5D39" &SEC = "1" #&CDS_SEC = "1";
"A":   PN = "1"  !CDS_PN = "1";
"B":   PN = "2"  !CDS_PN = "2";
BODY = "CAP_A","I142": #LOCATION = "C5D44" !CDS_LOCATION = "C5D44" &SEC = "1" #&CDS_SEC = "1";
"A":   PN = "1"  !CDS_PN = "1";
"B":   PN = "2"  !CDS_PN = "2";
BODY = "CAP_A","I145": #LOCATION = "C6D9" !CDS_LOCATION = "C6D9" &SEC = "1" #&CDS_SEC = "1";
"A":   PN = "1"  !CDS_PN = "1";
"B":   PN = "2"  !CDS_PN = "2";
BODY = "CAP_A","I147": #LOCATION = "C6D10" !CDS_LOCATION = "C6D10" &SEC = "1" #&CDS_SEC = "1";
"A":   PN = "1"  !CDS_PN = "1";
"B":   PN = "2"  !CDS_PN = "2";
BODY = "CAP","I148": #LOCATION = "C5P30" !CDS_LOCATION = "C5P30" &SEC = "1" #&CDS_SEC = "1";
"A":   PN = "1"  !CDS_PN = "1";
"B":   PN = "2"  !CDS_PN = "2";
BODY = "CAP","I149": #LOCATION = "C5P29" !CDS_LOCATION = "C5P29" &SEC = "1" #&CDS_SEC = "1";
"A":   PN = "1"  !CDS_PN = "1";
"B":   PN = "2"  !CDS_PN = "2";
BODY = "CAP_A","I151": #LOCATION = "C5D36" !CDS_LOCATION = "C5D36" &SEC = "1" #&CDS_SEC = "1";
"A":   PN = "1"  !CDS_PN = "1";
"B":   PN = "2"  !CDS_PN = "2";
BODY = "CAP_A","I152": #LOCATION = "C5D49" !CDS_LOCATION = "C5D49" &SEC = "1" #&CDS_SEC = "1";
"A":   PN = "1"  !CDS_PN = "1";
"B":   PN = "2"  !CDS_PN = "2";
BODY = "CAP_A","I153": #LOCATION = "C5D22" !CDS_LOCATION = "C5D22" &SEC = "1" #&CDS_SEC = "1";
"A":   PN = "1"  !CDS_PN = "1";
"B":   PN = "2"  !CDS_PN = "2";
BODY = "CAP_A","I154": #LOCATION = "C5D26" !CDS_LOCATION = "C5D26" &SEC = "1" #&CDS_SEC = "1";
"A":   PN = "1"  !CDS_PN = "1";
"B":   PN = "2"  !CDS_PN = "2";
BODY = "CAP_A","I155": #LOCATION = "C5D25" !CDS_LOCATION = "C5D25" &SEC = "1" #&CDS_SEC = "1";
"A":   PN = "1"  !CDS_PN = "1";
"B":   PN = "2"  !CDS_PN = "2";
BODY = "CAP_A","I156": #LOCATION = "C5D45" !CDS_LOCATION = "C5D45" &SEC = "1" #&CDS_SEC = "1";
"A":   PN = "1"  !CDS_PN = "1";
"B":   PN = "2"  !CDS_PN = "2";
BODY = "CAP","I162": #LOCATION = "C5P31" !CDS_LOCATION = "C5P31" &SEC = "1" #&CDS_SEC = "1";
"A":   PN = "1"  !CDS_PN = "1";
"B":   PN = "2"  !CDS_PN = "2";
BODY = "CAP","I163": #LOCATION = "C4P2" !CDS_LOCATION = "C4P2" &SEC = "1" #&CDS_SEC = "1";
"A":   PN = "1"  !CDS_PN = "1";
"B":   PN = "2"  !CDS_PN = "2";
BODY = "CAP_A","I164": #LOCATION = "C4P6" !CDS_LOCATION = "C4P6" &SEC = "1" #&CDS_SEC = "1";
"A":   PN = "1"  !CDS_PN = "1";
"B":   PN = "2"  !CDS_PN = "2";
BODY = "CAP","I172": #LOCATION = "C4P5" !CDS_LOCATION = "C4P5" &SEC = "1" #&CDS_SEC = "1";
"A":   PN = "1"  !CDS_PN = "1";
"B":   PN = "2"  !CDS_PN = "2";
BODY = "CAP_A","I173": #LOCATION = "C5D20" !CDS_LOCATION = "C5D20" &SEC = "1" #&CDS_SEC = "1";
"A":   PN = "1"  !CDS_PN = "1";
"B":   PN = "2"  !CDS_PN = "2";
BODY = "CAP_A","I174": #LOCATION = "C5D33" !CDS_LOCATION = "C5D33" &SEC = "1" #&CDS_SEC = "1";
"A":   PN = "1"  !CDS_PN = "1";
"B":   PN = "2"  !CDS_PN = "2";
BODY = "CAP_A","I175": #LOCATION = "C5D34" !CDS_LOCATION = "C5D34" &SEC = "1" #&CDS_SEC = "1";
"A":   PN = "1"  !CDS_PN = "1";
"B":   PN = "2"  !CDS_PN = "2";
BODY = "CAP_A","I176": #LOCATION = "C5D35" !CDS_LOCATION = "C5D35" &SEC = "1" #&CDS_SEC = "1";
"A":   PN = "1"  !CDS_PN = "1";
"B":   PN = "2"  !CDS_PN = "2";
BODY = "CAP_A","I178": #LOCATION = "C4P8" !CDS_LOCATION = "C4P8" &SEC = "1" #&CDS_SEC = "1";
"A":   PN = "1"  !CDS_PN = "1";
"B":   PN = "2"  !CDS_PN = "2";
BODY = "CAP_A","I179": #LOCATION = "C5D53" !CDS_LOCATION = "C5D53" &SEC = "1" #&CDS_SEC = "1";
"A":   PN = "1"  !CDS_PN = "1";
"B":   PN = "2"  !CDS_PN = "2";
BODY = "CAP_A","I180": #LOCATION = "C5D52" !CDS_LOCATION = "C5D52" &SEC = "1" #&CDS_SEC = "1";
"A":   PN = "1"  !CDS_PN = "1";
"B":   PN = "2"  !CDS_PN = "2";
BODY = "CAP","I183": #LOCATION = "C5P12" !CDS_LOCATION = "C5P12" &SEC = "1" #&CDS_SEC = "1";
"A":   PN = "1"  !CDS_PN = "1";
"B":   PN = "2"  !CDS_PN = "2";
BODY = "CAP","I184": #LOCATION = "C5P21" !CDS_LOCATION = "C5P21" &SEC = "1" #&CDS_SEC = "1";
"A":   PN = "1"  !CDS_PN = "1";
"B":   PN = "2"  !CDS_PN = "2";
BODY = "CAP","I185": #LOCATION = "C5P20" !CDS_LOCATION = "C5P20" &SEC = "1" #&CDS_SEC = "1";
"A":   PN = "1"  !CDS_PN = "1";
"B":   PN = "2"  !CDS_PN = "2";
BODY = "CAP","I186": #LOCATION = "C5P13" !CDS_LOCATION = "C5P13" &SEC = "1" #&CDS_SEC = "1";
"A":   PN = "1"  !CDS_PN = "1";
"B":   PN = "2"  !CDS_PN = "2";
BODY = "CAP","I187": #LOCATION = "C5P15" !CDS_LOCATION = "C5P15" &SEC = "1" #&CDS_SEC = "1";
"A":   PN = "1"  !CDS_PN = "1";
"B":   PN = "2"  !CDS_PN = "2";
BODY = "CAP","I188": #LOCATION = "C5P16" !CDS_LOCATION = "C5P16" &SEC = "1" #&CDS_SEC = "1";
"A":   PN = "1"  !CDS_PN = "1";
"B":   PN = "2"  !CDS_PN = "2";
BODY = "CAP","I189": #LOCATION = "C5P3" !CDS_LOCATION = "C5P3" &SEC = "1" #&CDS_SEC = "1";
"A":   PN = "1"  !CDS_PN = "1";
"B":   PN = "2"  !CDS_PN = "2";
BODY = "CAP","I190": #LOCATION = "C5P17" !CDS_LOCATION = "C5P17" &SEC = "1" #&CDS_SEC = "1";
"A":   PN = "1"  !CDS_PN = "1";
"B":   PN = "2"  !CDS_PN = "2";
DRAWING = "@baseboard_fab2_lib.baseboard_fab2(sch_1):page43";
BODY = "SCONN288_H44441004","I1": #LOCATION = "J4G1" !CDS_LOCATION = "J4G1" #SEC = "1" !CDS_SEC = "1";
"A0":   PN = "79"  !CDS_PN = "79";
"A1":   PN = "72"  !CDS_PN = "72";
"A2":   PN = "216"  !CDS_PN = "216";
"A3":   PN = "71"  !CDS_PN = "71";
"A4":   PN = "214"  !CDS_PN = "214";
"A5":   PN = "213"  !CDS_PN = "213";
"A6":   PN = "69"  !CDS_PN = "69";
"A7":   PN = "211"  !CDS_PN = "211";
"A8":   PN = "68"  !CDS_PN = "68";
"A9":   PN = "66"  !CDS_PN = "66";
"A10":   PN = "225"  !CDS_PN = "225";
"A11":   PN = "210"  !CDS_PN = "210";
"A12":   PN = "65"  !CDS_PN = "65";
"A13":   PN = "232"  !CDS_PN = "232";
"A14_WE_N":   PN = "228"  !CDS_PN = "228";
"A15_CAS_N":   PN = "86"  !CDS_PN = "86";
"A16_RAS_N":   PN = "82"  !CDS_PN = "82";
"A17":   PN = "234"  !CDS_PN = "234";
"ACT_N":   PN = "62"  !CDS_PN = "62";
"ALERT_N":   PN = "208"  !CDS_PN = "208";
"BA<0>":   PN = "81"  !CDS_PN = "81";
"BA<1>":   PN = "224"  !CDS_PN = "224";
"BG<0>":   PN = "63"  !CDS_PN = "63";
"BG<1>":   PN = "207"  !CDS_PN = "207";
"C<2>":   PN = "235"  !CDS_PN = "235";
"CB<0>":   PN = "49"  !CDS_PN = "49";
"CB<1>":   PN = "194"  !CDS_PN = "194";
"CB<2>":   PN = "56"  !CDS_PN = "56";
"CB<3>":   PN = "201"  !CDS_PN = "201";
"CB<4>":   PN = "47"  !CDS_PN = "47";
"CB<5>":   PN = "192"  !CDS_PN = "192";
"CB<6>":   PN = "54"  !CDS_PN = "54";
"CB<7>":   PN = "199"  !CDS_PN = "199";
"CK0N":   PN = "75"  !CDS_PN = "75";
"CK0P":   PN = "74"  !CDS_PN = "74";
"CK1N":   PN = "219"  !CDS_PN = "219";
"CK1P":   PN = "218"  !CDS_PN = "218";
"CKE<0>":   PN = "60"  !CDS_PN = "60";
"CKE<1>":   PN = "203"  !CDS_PN = "203";
"DQ<0>":   PN = "5"  !CDS_PN = "5";
"DQ<1>":   PN = "150"  !CDS_PN = "150";
"DQ<2>":   PN = "12"  !CDS_PN = "12";
"DQ<3>":   PN = "157"  !CDS_PN = "157";
"DQ<4>":   PN = "3"  !CDS_PN = "3";
"DQ<5>":   PN = "148"  !CDS_PN = "148";
"DQ<6>":   PN = "10"  !CDS_PN = "10";
"DQ<7>":   PN = "155"  !CDS_PN = "155";
"DQ<8>":   PN = "16"  !CDS_PN = "16";
"DQ<9>":   PN = "161"  !CDS_PN = "161";
"DQ<10>":   PN = "23"  !CDS_PN = "23";
"DQ<11>":   PN = "168"  !CDS_PN = "168";
"DQ<12>":   PN = "14"  !CDS_PN = "14";
"DQ<13>":   PN = "159"  !CDS_PN = "159";
"DQ<14>":   PN = "21"  !CDS_PN = "21";
"DQ<15>":   PN = "166"  !CDS_PN = "166";
"DQ<16>":   PN = "27"  !CDS_PN = "27";
"DQ<17>":   PN = "172"  !CDS_PN = "172";
"DQ<18>":   PN = "34"  !CDS_PN = "34";
"DQ<19>":   PN = "179"  !CDS_PN = "179";
"DQ<20>":   PN = "25"  !CDS_PN = "25";
"DQ<21>":   PN = "170"  !CDS_PN = "170";
"DQ<22>":   PN = "32"  !CDS_PN = "32";
"DQ<23>":   PN = "177"  !CDS_PN = "177";
"DQ<24>":   PN = "38"  !CDS_PN = "38";
"DQ<25>":   PN = "183"  !CDS_PN = "183";
"DQ<26>":   PN = "45"  !CDS_PN = "45";
"DQ<27>":   PN = "190"  !CDS_PN = "190";
"DQ<28>":   PN = "36"  !CDS_PN = "36";
"DQ<29>":   PN = "181"  !CDS_PN = "181";
"DQ<30>":   PN = "43"  !CDS_PN = "43";
"DQ<31>":   PN = "188"  !CDS_PN = "188";
"DQ<32>":   PN = "97"  !CDS_PN = "97";
"DQ<33>":   PN = "242"  !CDS_PN = "242";
"DQ<34>":   PN = "104"  !CDS_PN = "104";
"DQ<35>":   PN = "249"  !CDS_PN = "249";
"DQ<36>":   PN = "95"  !CDS_PN = "95";
"DQ<37>":   PN = "240"  !CDS_PN = "240";
"DQ<38>":   PN = "102"  !CDS_PN = "102";
"DQ<39>":   PN = "247"  !CDS_PN = "247";
"DQ<40>":   PN = "108"  !CDS_PN = "108";
"DQ<41>":   PN = "253"  !CDS_PN = "253";
"DQ<42>":   PN = "115"  !CDS_PN = "115";
"DQ<43>":   PN = "260"  !CDS_PN = "260";
"DQ<44>":   PN = "106"  !CDS_PN = "106";
"DQ<45>":   PN = "251"  !CDS_PN = "251";
"DQ<46>":   PN = "113"  !CDS_PN = "113";
"DQ<47>":   PN = "258"  !CDS_PN = "258";
"DQ<48>":   PN = "119"  !CDS_PN = "119";
"DQ<49>":   PN = "264"  !CDS_PN = "264";
"DQ<50>":   PN = "126"  !CDS_PN = "126";
"DQ<51>":   PN = "271"  !CDS_PN = "271";
"DQ<52>":   PN = "117"  !CDS_PN = "117";
"DQ<53>":   PN = "262"  !CDS_PN = "262";
"DQ<54>":   PN = "124"  !CDS_PN = "124";
"DQ<55>":   PN = "269"  !CDS_PN = "269";
"DQ<56>":   PN = "130"  !CDS_PN = "130";
"DQ<57>":   PN = "275"  !CDS_PN = "275";
"DQ<58>":   PN = "137"  !CDS_PN = "137";
"DQ<59>":   PN = "282"  !CDS_PN = "282";
"DQ<60>":   PN = "128"  !CDS_PN = "128";
"DQ<61>":   PN = "273"  !CDS_PN = "273";
"DQ<62>":   PN = "135"  !CDS_PN = "135";
"DQ<63>":   PN = "280"  !CDS_PN = "280";
"EVENT_N":   PN = "78"  !CDS_PN = "78";
"ODT<0>":   PN = "87"  !CDS_PN = "87";
"ODT<1>":   PN = "91"  !CDS_PN = "91";
"PAR":   PN = "222"  !CDS_PN = "222";
"RESET_N":   PN = "58"  !CDS_PN = "58";
"RFU<0>":   PN = "205"  !CDS_PN = "205";
"RFU<1>":   PN = "227"  !CDS_PN = "227";
"RFU<2>":   PN = "144"  !CDS_PN = "144";
"S0_N":   PN = "84"  !CDS_PN = "84";
"S1_N":   PN = "89"  !CDS_PN = "89";
"S2_N_C<0>":   PN = "93"  !CDS_PN = "93";
"S3_N_C<1>":   PN = "237"  !CDS_PN = "237";
"SA<0>":   PN = "139"  !CDS_PN = "139";
"SA<1>":   PN = "140"  !CDS_PN = "140";
"SA<2>":   PN = "238"  !CDS_PN = "238";
"SAVE_N_NC":   PN = "230"  !CDS_PN = "230";
"SCL":   PN = "141"  !CDS_PN = "141";
"SDA":   PN = "285"  !CDS_PN = "285";
"VDDSPD":   PN = "284"  !CDS_PN = "284";
"VREFCA":   PN = "146"  !CDS_PN = "146";
BODY = "SCONN288_H44441004","I2": #LOCATION = "J4G1" !CDS_LOCATION = "J4G1" #SEC = "2" !CDS_SEC = "2";
"DQS0N":   PN = "152"  !CDS_PN = "152";
"DQS0P":   PN = "153"  !CDS_PN = "153";
"DQS1N":   PN = "163"  !CDS_PN = "163";
"DQS1P":   PN = "164"  !CDS_PN = "164";
"DQS2N":   PN = "174"  !CDS_PN = "174";
"DQS2P":   PN = "175"  !CDS_PN = "175";
"DQS3N":   PN = "185"  !CDS_PN = "185";
"DQS3P":   PN = "186"  !CDS_PN = "186";
"DQS4N":   PN = "244"  !CDS_PN = "244";
"DQS4P":   PN = "245"  !CDS_PN = "245";
"DQS5N":   PN = "255"  !CDS_PN = "255";
"DQS5P":   PN = "256"  !CDS_PN = "256";
"DQS6N":   PN = "266"  !CDS_PN = "266";
"DQS6P":   PN = "267"  !CDS_PN = "267";
"DQS7N":   PN = "277"  !CDS_PN = "277";
"DQS7P":   PN = "278"  !CDS_PN = "278";
"DQS8N":   PN = "196"  !CDS_PN = "196";
"DQS8P":   PN = "197"  !CDS_PN = "197";
"DQS9N":   PN = "8"  !CDS_PN = "8";
"DQS9P":   PN = "7"  !CDS_PN = "7";
"DQS10N":   PN = "19"  !CDS_PN = "19";
"DQS10P":   PN = "18"  !CDS_PN = "18";
"DQS11N":   PN = "30"  !CDS_PN = "30";
"DQS11P":   PN = "29"  !CDS_PN = "29";
"DQS12N":   PN = "41"  !CDS_PN = "41";
"DQS12P":   PN = "40"  !CDS_PN = "40";
"DQS13N":   PN = "100"  !CDS_PN = "100";
"DQS13P":   PN = "99"  !CDS_PN = "99";
"DQS14N":   PN = "111"  !CDS_PN = "111";
"DQS14P":   PN = "110"  !CDS_PN = "110";
"DQS15N":   PN = "122"  !CDS_PN = "122";
"DQS15P":   PN = "121"  !CDS_PN = "121";
"DQS16N":   PN = "133"  !CDS_PN = "133";
"DQS16P":   PN = "132"  !CDS_PN = "132";
"DQS17N":   PN = "52"  !CDS_PN = "52";
"DQS17P":   PN = "51"  !CDS_PN = "51";
BODY = "SCONN288_H44441004","I259": #LOCATION = "J4G1" !CDS_LOCATION = "J4G1" #SEC = "3" !CDS_SEC = "3";
"VSS<0>":   PN = "283"  !CDS_PN = "283";
"VSS<1>":   PN = "281"  !CDS_PN = "281";
"VSS<2>":   PN = "279"  !CDS_PN = "279";
"VSS<3>":   PN = "276"  !CDS_PN = "276";
"VSS<4>":   PN = "274"  !CDS_PN = "274";
"VSS<5>":   PN = "272"  !CDS_PN = "272";
"VSS<6>":   PN = "270"  !CDS_PN = "270";
"VSS<7>":   PN = "268"  !CDS_PN = "268";
"VSS<8>":   PN = "265"  !CDS_PN = "265";
"VSS<9>":   PN = "263"  !CDS_PN = "263";
"VSS<10>":   PN = "261"  !CDS_PN = "261";
"VSS<11>":   PN = "259"  !CDS_PN = "259";
"VSS<12>":   PN = "257"  !CDS_PN = "257";
"VSS<13>":   PN = "254"  !CDS_PN = "254";
"VSS<14>":   PN = "252"  !CDS_PN = "252";
"VSS<15>":   PN = "250"  !CDS_PN = "250";
"VSS<16>":   PN = "248"  !CDS_PN = "248";
"VSS<17>":   PN = "246"  !CDS_PN = "246";
"VSS<18>":   PN = "243"  !CDS_PN = "243";
"VSS<19>":   PN = "241"  !CDS_PN = "241";
"VSS<20>":   PN = "239"  !CDS_PN = "239";
"VSS<21>":   PN = "202"  !CDS_PN = "202";
"VSS<22>":   PN = "200"  !CDS_PN = "200";
"VSS<23>":   PN = "198"  !CDS_PN = "198";
"VSS<24>":   PN = "195"  !CDS_PN = "195";
"VSS<25>":   PN = "193"  !CDS_PN = "193";
"VSS<26>":   PN = "191"  !CDS_PN = "191";
"VSS<27>":   PN = "189"  !CDS_PN = "189";
"VSS<28>":   PN = "187"  !CDS_PN = "187";
"VSS<29>":   PN = "184"  !CDS_PN = "184";
"VSS<30>":   PN = "182"  !CDS_PN = "182";
"VSS<31>":   PN = "180"  !CDS_PN = "180";
"VSS<32>":   PN = "178"  !CDS_PN = "178";
"VSS<33>":   PN = "176"  !CDS_PN = "176";
"VSS<34>":   PN = "173"  !CDS_PN = "173";
"VSS<35>":   PN = "171"  !CDS_PN = "171";
"VSS<36>":   PN = "169"  !CDS_PN = "169";
"VSS<37>":   PN = "167"  !CDS_PN = "167";
"VSS<38>":   PN = "165"  !CDS_PN = "165";
"VSS<39>":   PN = "162"  !CDS_PN = "162";
"VSS<40>":   PN = "160"  !CDS_PN = "160";
"VSS<41>":   PN = "158"  !CDS_PN = "158";
"VSS<42>":   PN = "156"  !CDS_PN = "156";
"VSS<43>":   PN = "154"  !CDS_PN = "154";
"VSS<44>":   PN = "151"  !CDS_PN = "151";
"VSS<45>":   PN = "149"  !CDS_PN = "149";
"VSS<46>":   PN = "147"  !CDS_PN = "147";
"VSS<47>":   PN = "138"  !CDS_PN = "138";
"VSS<48>":   PN = "136"  !CDS_PN = "136";
"VSS<49>":   PN = "134"  !CDS_PN = "134";
"VSS<50>":   PN = "131"  !CDS_PN = "131";
"VSS<51>":   PN = "129"  !CDS_PN = "129";
"VSS<52>":   PN = "127"  !CDS_PN = "127";
"VSS<53>":   PN = "125"  !CDS_PN = "125";
"VSS<54>":   PN = "123"  !CDS_PN = "123";
"VSS<55>":   PN = "120"  !CDS_PN = "120";
"VSS<56>":   PN = "118"  !CDS_PN = "118";
"VSS<57>":   PN = "116"  !CDS_PN = "116";
"VSS<58>":   PN = "114"  !CDS_PN = "114";
"VSS<59>":   PN = "112"  !CDS_PN = "112";
"VSS<60>":   PN = "109"  !CDS_PN = "109";
"VSS<61>":   PN = "107"  !CDS_PN = "107";
"VSS<62>":   PN = "105"  !CDS_PN = "105";
"VSS<63>":   PN = "103"  !CDS_PN = "103";
"VSS<64>":   PN = "101"  !CDS_PN = "101";
"VSS<65>":   PN = "98"  !CDS_PN = "98";
"VSS<66>":   PN = "96"  !CDS_PN = "96";
"VSS<67>":   PN = "94"  !CDS_PN = "94";
"VSS<68>":   PN = "57"  !CDS_PN = "57";
"VSS<69>":   PN = "55"  !CDS_PN = "55";
"VSS<70>":   PN = "53"  !CDS_PN = "53";
"VSS<71>":   PN = "50"  !CDS_PN = "50";
"VSS<72>":   PN = "48"  !CDS_PN = "48";
"VSS<73>":   PN = "46"  !CDS_PN = "46";
"VSS<74>":   PN = "44"  !CDS_PN = "44";
"VSS<75>":   PN = "42"  !CDS_PN = "42";
"VSS<76>":   PN = "39"  !CDS_PN = "39";
"VSS<77>":   PN = "37"  !CDS_PN = "37";
"VSS<78>":   PN = "35"  !CDS_PN = "35";
"VSS<79>":   PN = "33"  !CDS_PN = "33";
"VSS<80>":   PN = "31"  !CDS_PN = "31";
"VSS<81>":   PN = "28"  !CDS_PN = "28";
"VSS<82>":   PN = "26"  !CDS_PN = "26";
"VSS<83>":   PN = "24"  !CDS_PN = "24";
"VSS<84>":   PN = "22"  !CDS_PN = "22";
"VSS<85>":   PN = "20"  !CDS_PN = "20";
"VSS<86>":   PN = "17"  !CDS_PN = "17";
"VSS<87>":   PN = "15"  !CDS_PN = "15";
"VSS<88>":   PN = "13"  !CDS_PN = "13";
"VSS<89>":   PN = "11"  !CDS_PN = "11";
"VSS<90>":   PN = "9"  !CDS_PN = "9";
"VSS<91>":   PN = "6"  !CDS_PN = "6";
"VSS<92>":   PN = "4"  !CDS_PN = "4";
"VSS<93>":   PN = "2"  !CDS_PN = "2";
BODY = "SCONN288_H44441004","I260": #LOCATION = "J4G1" !CDS_LOCATION = "J4G1" #SEC = "4" !CDS_SEC = "4";
"12V<0>":   PN = "145"  !CDS_PN = "145";
"12V<1>":   PN = "1"  !CDS_PN = "1";
"VDD<0>":   PN = "236"  !CDS_PN = "236";
"VDD<1>":   PN = "233"  !CDS_PN = "233";
"VDD<2>":   PN = "231"  !CDS_PN = "231";
"VDD<3>":   PN = "229"  !CDS_PN = "229";
"VDD<4>":   PN = "226"  !CDS_PN = "226";
"VDD<5>":   PN = "223"  !CDS_PN = "223";
"VDD<6>":   PN = "220"  !CDS_PN = "220";
"VDD<7>":   PN = "217"  !CDS_PN = "217";
"VDD<8>":   PN = "215"  !CDS_PN = "215";
"VDD<9>":   PN = "212"  !CDS_PN = "212";
"VDD<10>":   PN = "209"  !CDS_PN = "209";
"VDD<11>":   PN = "206"  !CDS_PN = "206";
"VDD<12>":   PN = "204"  !CDS_PN = "204";
"VDD<13>":   PN = "92"  !CDS_PN = "92";
"VDD<14>":   PN = "90"  !CDS_PN = "90";
"VDD<15>":   PN = "88"  !CDS_PN = "88";
"VDD<16>":   PN = "85"  !CDS_PN = "85";
"VDD<17>":   PN = "83"  !CDS_PN = "83";
"VDD<18>":   PN = "80"  !CDS_PN = "80";
"VDD<19>":   PN = "76"  !CDS_PN = "76";
"VDD<20>":   PN = "73"  !CDS_PN = "73";
"VDD<21>":   PN = "70"  !CDS_PN = "70";
"VDD<22>":   PN = "67"  !CDS_PN = "67";
"VDD<23>":   PN = "64"  !CDS_PN = "64";
"VDD<24>":   PN = "61"  !CDS_PN = "61";
"VDD<25>":   PN = "59"  !CDS_PN = "59";
"VPP<0>":   PN = "287"  !CDS_PN = "287";
"VPP<1>":   PN = "286"  !CDS_PN = "286";
"VPP<2>":   PN = "288"  !CDS_PN = "288";
"VPP<3>":   PN = "143"  !CDS_PN = "143";
"VPP<4>":   PN = "142"  !CDS_PN = "142";
"VTT<0>":   PN = "221"  !CDS_PN = "221";
"VTT<1>":   PN = "77"  !CDS_PN = "77";
BODY = "CAP_A","I272": #LOCATION = "C4F10" !CDS_LOCATION = "C4F10" &SEC = "1" #&CDS_SEC = "1";
"A":   PN = "1"  !CDS_PN = "1";
"B":   PN = "2"  !CDS_PN = "2";
DRAWING = "@baseboard_fab2_lib.baseboard_fab2(sch_1):page44";
BODY = "CAP_A","I2": #LOCATION = "C6T1" !CDS_LOCATION = "C6T1" #SEC = "1" !CDS_SEC = "1";
"A":   PN = "1"  !CDS_PN = "1";
"B":   PN = "2"  !CDS_PN = "2";
BODY = "SCONN288_H44441003","I13": #LOCATION = "J6T1" !CDS_LOCATION = "J6T1" #SEC = "1" !CDS_SEC = "1";
"A0":   PN = "79"  !CDS_PN = "79";
"A1":   PN = "72"  !CDS_PN = "72";
"A2":   PN = "216"  !CDS_PN = "216";
"A3":   PN = "71"  !CDS_PN = "71";
"A4":   PN = "214"  !CDS_PN = "214";
"A5":   PN = "213"  !CDS_PN = "213";
"A6":   PN = "69"  !CDS_PN = "69";
"A7":   PN = "211"  !CDS_PN = "211";
"A8":   PN = "68"  !CDS_PN = "68";
"A9":   PN = "66"  !CDS_PN = "66";
"A10":   PN = "225"  !CDS_PN = "225";
"A11":   PN = "210"  !CDS_PN = "210";
"A12":   PN = "65"  !CDS_PN = "65";
"A13":   PN = "232"  !CDS_PN = "232";
"A14_WE_N":   PN = "228"  !CDS_PN = "228";
"A15_CAS_N":   PN = "86"  !CDS_PN = "86";
"A16_RAS_N":   PN = "82"  !CDS_PN = "82";
"A17":   PN = "234"  !CDS_PN = "234";
"ACT_N":   PN = "62"  !CDS_PN = "62";
"ALERT_N":   PN = "208"  !CDS_PN = "208";
"BA<0>":   PN = "81"  !CDS_PN = "81";
"BA<1>":   PN = "224"  !CDS_PN = "224";
"BG<0>":   PN = "63"  !CDS_PN = "63";
"BG<1>":   PN = "207"  !CDS_PN = "207";
"C<2>":   PN = "235"  !CDS_PN = "235";
"CB<0>":   PN = "49"  !CDS_PN = "49";
"CB<1>":   PN = "194"  !CDS_PN = "194";
"CB<2>":   PN = "56"  !CDS_PN = "56";
"CB<3>":   PN = "201"  !CDS_PN = "201";
"CB<4>":   PN = "47"  !CDS_PN = "47";
"CB<5>":   PN = "192"  !CDS_PN = "192";
"CB<6>":   PN = "54"  !CDS_PN = "54";
"CB<7>":   PN = "199"  !CDS_PN = "199";
"CK0N":   PN = "75"  !CDS_PN = "75";
"CK0P":   PN = "74"  !CDS_PN = "74";
"CK1N":   PN = "219"  !CDS_PN = "219";
"CK1P":   PN = "218"  !CDS_PN = "218";
"CKE<0>":   PN = "60"  !CDS_PN = "60";
"CKE<1>":   PN = "203"  !CDS_PN = "203";
"DQ<0>":   PN = "5"  !CDS_PN = "5";
"DQ<1>":   PN = "150"  !CDS_PN = "150";
"DQ<2>":   PN = "12"  !CDS_PN = "12";
"DQ<3>":   PN = "157"  !CDS_PN = "157";
"DQ<4>":   PN = "3"  !CDS_PN = "3";
"DQ<5>":   PN = "148"  !CDS_PN = "148";
"DQ<6>":   PN = "10"  !CDS_PN = "10";
"DQ<7>":   PN = "155"  !CDS_PN = "155";
"DQ<8>":   PN = "16"  !CDS_PN = "16";
"DQ<9>":   PN = "161"  !CDS_PN = "161";
"DQ<10>":   PN = "23"  !CDS_PN = "23";
"DQ<11>":   PN = "168"  !CDS_PN = "168";
"DQ<12>":   PN = "14"  !CDS_PN = "14";
"DQ<13>":   PN = "159"  !CDS_PN = "159";
"DQ<14>":   PN = "21"  !CDS_PN = "21";
"DQ<15>":   PN = "166"  !CDS_PN = "166";
"DQ<16>":   PN = "27"  !CDS_PN = "27";
"DQ<17>":   PN = "172"  !CDS_PN = "172";
"DQ<18>":   PN = "34"  !CDS_PN = "34";
"DQ<19>":   PN = "179"  !CDS_PN = "179";
"DQ<20>":   PN = "25"  !CDS_PN = "25";
"DQ<21>":   PN = "170"  !CDS_PN = "170";
"DQ<22>":   PN = "32"  !CDS_PN = "32";
"DQ<23>":   PN = "177"  !CDS_PN = "177";
"DQ<24>":   PN = "38"  !CDS_PN = "38";
"DQ<25>":   PN = "183"  !CDS_PN = "183";
"DQ<26>":   PN = "45"  !CDS_PN = "45";
"DQ<27>":   PN = "190"  !CDS_PN = "190";
"DQ<28>":   PN = "36"  !CDS_PN = "36";
"DQ<29>":   PN = "181"  !CDS_PN = "181";
"DQ<30>":   PN = "43"  !CDS_PN = "43";
"DQ<31>":   PN = "188"  !CDS_PN = "188";
"DQ<32>":   PN = "97"  !CDS_PN = "97";
"DQ<33>":   PN = "242"  !CDS_PN = "242";
"DQ<34>":   PN = "104"  !CDS_PN = "104";
"DQ<35>":   PN = "249"  !CDS_PN = "249";
"DQ<36>":   PN = "95"  !CDS_PN = "95";
"DQ<37>":   PN = "240"  !CDS_PN = "240";
"DQ<38>":   PN = "102"  !CDS_PN = "102";
"DQ<39>":   PN = "247"  !CDS_PN = "247";
"DQ<40>":   PN = "108"  !CDS_PN = "108";
"DQ<41>":   PN = "253"  !CDS_PN = "253";
"DQ<42>":   PN = "115"  !CDS_PN = "115";
"DQ<43>":   PN = "260"  !CDS_PN = "260";
"DQ<44>":   PN = "106"  !CDS_PN = "106";
"DQ<45>":   PN = "251"  !CDS_PN = "251";
"DQ<46>":   PN = "113"  !CDS_PN = "113";
"DQ<47>":   PN = "258"  !CDS_PN = "258";
"DQ<48>":   PN = "119"  !CDS_PN = "119";
"DQ<49>":   PN = "264"  !CDS_PN = "264";
"DQ<50>":   PN = "126"  !CDS_PN = "126";
"DQ<51>":   PN = "271"  !CDS_PN = "271";
"DQ<52>":   PN = "117"  !CDS_PN = "117";
"DQ<53>":   PN = "262"  !CDS_PN = "262";
"DQ<54>":   PN = "124"  !CDS_PN = "124";
"DQ<55>":   PN = "269"  !CDS_PN = "269";
"DQ<56>":   PN = "130"  !CDS_PN = "130";
"DQ<57>":   PN = "275"  !CDS_PN = "275";
"DQ<58>":   PN = "137"  !CDS_PN = "137";
"DQ<59>":   PN = "282"  !CDS_PN = "282";
"DQ<60>":   PN = "128"  !CDS_PN = "128";
"DQ<61>":   PN = "273"  !CDS_PN = "273";
"DQ<62>":   PN = "135"  !CDS_PN = "135";
"DQ<63>":   PN = "280"  !CDS_PN = "280";
"EVENT_N":   PN = "78"  !CDS_PN = "78";
"ODT<0>":   PN = "87"  !CDS_PN = "87";
"ODT<1>":   PN = "91"  !CDS_PN = "91";
"PAR":   PN = "222"  !CDS_PN = "222";
"RESET_N":   PN = "58"  !CDS_PN = "58";
"RFU<0>":   PN = "205"  !CDS_PN = "205";
"RFU<1>":   PN = "227"  !CDS_PN = "227";
"RFU<2>":   PN = "144"  !CDS_PN = "144";
"S0_N":   PN = "84"  !CDS_PN = "84";
"S1_N":   PN = "89"  !CDS_PN = "89";
"S2_N_C<0>":   PN = "93"  !CDS_PN = "93";
"S3_N_C<1>":   PN = "237"  !CDS_PN = "237";
"SA<0>":   PN = "139"  !CDS_PN = "139";
"SA<1>":   PN = "140"  !CDS_PN = "140";
"SA<2>":   PN = "238"  !CDS_PN = "238";
"SAVE_N_NC":   PN = "230"  !CDS_PN = "230";
"SCL":   PN = "141"  !CDS_PN = "141";
"SDA":   PN = "285"  !CDS_PN = "285";
"VDDSPD":   PN = "284"  !CDS_PN = "284";
"VREFCA":   PN = "146"  !CDS_PN = "146";
BODY = "SCONN288_H44441003","I75": #LOCATION = "J6T1" !CDS_LOCATION = "J6T1" #SEC = "4" !CDS_SEC = "4";
"12V<0>":   PN = "145"  !CDS_PN = "145";
"12V<1>":   PN = "1"  !CDS_PN = "1";
"VDD<0>":   PN = "236"  !CDS_PN = "236";
"VDD<1>":   PN = "233"  !CDS_PN = "233";
"VDD<2>":   PN = "231"  !CDS_PN = "231";
"VDD<3>":   PN = "229"  !CDS_PN = "229";
"VDD<4>":   PN = "226"  !CDS_PN = "226";
"VDD<5>":   PN = "223"  !CDS_PN = "223";
"VDD<6>":   PN = "220"  !CDS_PN = "220";
"VDD<7>":   PN = "217"  !CDS_PN = "217";
"VDD<8>":   PN = "215"  !CDS_PN = "215";
"VDD<9>":   PN = "212"  !CDS_PN = "212";
"VDD<10>":   PN = "209"  !CDS_PN = "209";
"VDD<11>":   PN = "206"  !CDS_PN = "206";
"VDD<12>":   PN = "204"  !CDS_PN = "204";
"VDD<13>":   PN = "92"  !CDS_PN = "92";
"VDD<14>":   PN = "90"  !CDS_PN = "90";
"VDD<15>":   PN = "88"  !CDS_PN = "88";
"VDD<16>":   PN = "85"  !CDS_PN = "85";
"VDD<17>":   PN = "83"  !CDS_PN = "83";
"VDD<18>":   PN = "80"  !CDS_PN = "80";
"VDD<19>":   PN = "76"  !CDS_PN = "76";
"VDD<20>":   PN = "73"  !CDS_PN = "73";
"VDD<21>":   PN = "70"  !CDS_PN = "70";
"VDD<22>":   PN = "67"  !CDS_PN = "67";
"VDD<23>":   PN = "64"  !CDS_PN = "64";
"VDD<24>":   PN = "61"  !CDS_PN = "61";
"VDD<25>":   PN = "59"  !CDS_PN = "59";
"VPP<0>":   PN = "287"  !CDS_PN = "287";
"VPP<1>":   PN = "286"  !CDS_PN = "286";
"VPP<2>":   PN = "288"  !CDS_PN = "288";
"VPP<3>":   PN = "143"  !CDS_PN = "143";
"VPP<4>":   PN = "142"  !CDS_PN = "142";
"VTT<0>":   PN = "221"  !CDS_PN = "221";
"VTT<1>":   PN = "77"  !CDS_PN = "77";
BODY = "SCONN288_H44441003","I120": #LOCATION = "J6T1" !CDS_LOCATION = "J6T1" #SEC = "2" !CDS_SEC = "2";
"DQS0N":   PN = "152"  !CDS_PN = "152";
"DQS0P":   PN = "153"  !CDS_PN = "153";
"DQS1N":   PN = "163"  !CDS_PN = "163";
"DQS1P":   PN = "164"  !CDS_PN = "164";
"DQS2N":   PN = "174"  !CDS_PN = "174";
"DQS2P":   PN = "175"  !CDS_PN = "175";
"DQS3N":   PN = "185"  !CDS_PN = "185";
"DQS3P":   PN = "186"  !CDS_PN = "186";
"DQS4N":   PN = "244"  !CDS_PN = "244";
"DQS4P":   PN = "245"  !CDS_PN = "245";
"DQS5N":   PN = "255"  !CDS_PN = "255";
"DQS5P":   PN = "256"  !CDS_PN = "256";
"DQS6N":   PN = "266"  !CDS_PN = "266";
"DQS6P":   PN = "267"  !CDS_PN = "267";
"DQS7N":   PN = "277"  !CDS_PN = "277";
"DQS7P":   PN = "278"  !CDS_PN = "278";
"DQS8N":   PN = "196"  !CDS_PN = "196";
"DQS8P":   PN = "197"  !CDS_PN = "197";
"DQS9N":   PN = "8"  !CDS_PN = "8";
"DQS9P":   PN = "7"  !CDS_PN = "7";
"DQS10N":   PN = "19"  !CDS_PN = "19";
"DQS10P":   PN = "18"  !CDS_PN = "18";
"DQS11N":   PN = "30"  !CDS_PN = "30";
"DQS11P":   PN = "29"  !CDS_PN = "29";
"DQS12N":   PN = "41"  !CDS_PN = "41";
"DQS12P":   PN = "40"  !CDS_PN = "40";
"DQS13N":   PN = "100"  !CDS_PN = "100";
"DQS13P":   PN = "99"  !CDS_PN = "99";
"DQS14N":   PN = "111"  !CDS_PN = "111";
"DQS14P":   PN = "110"  !CDS_PN = "110";
"DQS15N":   PN = "122"  !CDS_PN = "122";
"DQS15P":   PN = "121"  !CDS_PN = "121";
"DQS16N":   PN = "133"  !CDS_PN = "133";
"DQS16P":   PN = "132"  !CDS_PN = "132";
"DQS17N":   PN = "52"  !CDS_PN = "52";
"DQS17P":   PN = "51"  !CDS_PN = "51";
BODY = "SCONN288_H44441003","I139": #LOCATION = "J6T1" !CDS_LOCATION = "J6T1" #SEC = "3" !CDS_SEC = "3";
"VSS<0>":   PN = "283"  !CDS_PN = "283";
"VSS<1>":   PN = "281"  !CDS_PN = "281";
"VSS<2>":   PN = "279"  !CDS_PN = "279";
"VSS<3>":   PN = "276"  !CDS_PN = "276";
"VSS<4>":   PN = "274"  !CDS_PN = "274";
"VSS<5>":   PN = "272"  !CDS_PN = "272";
"VSS<6>":   PN = "270"  !CDS_PN = "270";
"VSS<7>":   PN = "268"  !CDS_PN = "268";
"VSS<8>":   PN = "265"  !CDS_PN = "265";
"VSS<9>":   PN = "263"  !CDS_PN = "263";
"VSS<10>":   PN = "261"  !CDS_PN = "261";
"VSS<11>":   PN = "259"  !CDS_PN = "259";
"VSS<12>":   PN = "257"  !CDS_PN = "257";
"VSS<13>":   PN = "254"  !CDS_PN = "254";
"VSS<14>":   PN = "252"  !CDS_PN = "252";
"VSS<15>":   PN = "250"  !CDS_PN = "250";
"VSS<16>":   PN = "248"  !CDS_PN = "248";
"VSS<17>":   PN = "246"  !CDS_PN = "246";
"VSS<18>":   PN = "243"  !CDS_PN = "243";
"VSS<19>":   PN = "241"  !CDS_PN = "241";
"VSS<20>":   PN = "239"  !CDS_PN = "239";
"VSS<21>":   PN = "202"  !CDS_PN = "202";
"VSS<22>":   PN = "200"  !CDS_PN = "200";
"VSS<23>":   PN = "198"  !CDS_PN = "198";
"VSS<24>":   PN = "195"  !CDS_PN = "195";
"VSS<25>":   PN = "193"  !CDS_PN = "193";
"VSS<26>":   PN = "191"  !CDS_PN = "191";
"VSS<27>":   PN = "189"  !CDS_PN = "189";
"VSS<28>":   PN = "187"  !CDS_PN = "187";
"VSS<29>":   PN = "184"  !CDS_PN = "184";
"VSS<30>":   PN = "182"  !CDS_PN = "182";
"VSS<31>":   PN = "180"  !CDS_PN = "180";
"VSS<32>":   PN = "178"  !CDS_PN = "178";
"VSS<33>":   PN = "176"  !CDS_PN = "176";
"VSS<34>":   PN = "173"  !CDS_PN = "173";
"VSS<35>":   PN = "171"  !CDS_PN = "171";
"VSS<36>":   PN = "169"  !CDS_PN = "169";
"VSS<37>":   PN = "167"  !CDS_PN = "167";
"VSS<38>":   PN = "165"  !CDS_PN = "165";
"VSS<39>":   PN = "162"  !CDS_PN = "162";
"VSS<40>":   PN = "160"  !CDS_PN = "160";
"VSS<41>":   PN = "158"  !CDS_PN = "158";
"VSS<42>":   PN = "156"  !CDS_PN = "156";
"VSS<43>":   PN = "154"  !CDS_PN = "154";
"VSS<44>":   PN = "151"  !CDS_PN = "151";
"VSS<45>":   PN = "149"  !CDS_PN = "149";
"VSS<46>":   PN = "147"  !CDS_PN = "147";
"VSS<47>":   PN = "138"  !CDS_PN = "138";
"VSS<48>":   PN = "136"  !CDS_PN = "136";
"VSS<49>":   PN = "134"  !CDS_PN = "134";
"VSS<50>":   PN = "131"  !CDS_PN = "131";
"VSS<51>":   PN = "129"  !CDS_PN = "129";
"VSS<52>":   PN = "127"  !CDS_PN = "127";
"VSS<53>":   PN = "125"  !CDS_PN = "125";
"VSS<54>":   PN = "123"  !CDS_PN = "123";
"VSS<55>":   PN = "120"  !CDS_PN = "120";
"VSS<56>":   PN = "118"  !CDS_PN = "118";
"VSS<57>":   PN = "116"  !CDS_PN = "116";
"VSS<58>":   PN = "114"  !CDS_PN = "114";
"VSS<59>":   PN = "112"  !CDS_PN = "112";
"VSS<60>":   PN = "109"  !CDS_PN = "109";
"VSS<61>":   PN = "107"  !CDS_PN = "107";
"VSS<62>":   PN = "105"  !CDS_PN = "105";
"VSS<63>":   PN = "103"  !CDS_PN = "103";
"VSS<64>":   PN = "101"  !CDS_PN = "101";
"VSS<65>":   PN = "98"  !CDS_PN = "98";
"VSS<66>":   PN = "96"  !CDS_PN = "96";
"VSS<67>":   PN = "94"  !CDS_PN = "94";
"VSS<68>":   PN = "57"  !CDS_PN = "57";
"VSS<69>":   PN = "55"  !CDS_PN = "55";
"VSS<70>":   PN = "53"  !CDS_PN = "53";
"VSS<71>":   PN = "50"  !CDS_PN = "50";
"VSS<72>":   PN = "48"  !CDS_PN = "48";
"VSS<73>":   PN = "46"  !CDS_PN = "46";
"VSS<74>":   PN = "44"  !CDS_PN = "44";
"VSS<75>":   PN = "42"  !CDS_PN = "42";
"VSS<76>":   PN = "39"  !CDS_PN = "39";
"VSS<77>":   PN = "37"  !CDS_PN = "37";
"VSS<78>":   PN = "35"  !CDS_PN = "35";
"VSS<79>":   PN = "33"  !CDS_PN = "33";
"VSS<80>":   PN = "31"  !CDS_PN = "31";
"VSS<81>":   PN = "28"  !CDS_PN = "28";
"VSS<82>":   PN = "26"  !CDS_PN = "26";
"VSS<83>":   PN = "24"  !CDS_PN = "24";
"VSS<84>":   PN = "22"  !CDS_PN = "22";
"VSS<85>":   PN = "20"  !CDS_PN = "20";
"VSS<86>":   PN = "17"  !CDS_PN = "17";
"VSS<87>":   PN = "15"  !CDS_PN = "15";
"VSS<88>":   PN = "13"  !CDS_PN = "13";
"VSS<89>":   PN = "11"  !CDS_PN = "11";
"VSS<90>":   PN = "9"  !CDS_PN = "9";
"VSS<91>":   PN = "6"  !CDS_PN = "6";
"VSS<92>":   PN = "4"  !CDS_PN = "4";
"VSS<93>":   PN = "2"  !CDS_PN = "2";
DRAWING = "@baseboard_fab2_lib.baseboard_fab2(sch_1):page45";
BODY = "SCONN288_H44441004","I43": #LOCATION = "J4G2" !CDS_LOCATION = "J4G2" #SEC = "3" !CDS_SEC = "3";
"VSS<0>":   PN = "283"  !CDS_PN = "283";
"VSS<1>":   PN = "281"  !CDS_PN = "281";
"VSS<2>":   PN = "279"  !CDS_PN = "279";
"VSS<3>":   PN = "276"  !CDS_PN = "276";
"VSS<4>":   PN = "274"  !CDS_PN = "274";
"VSS<5>":   PN = "272"  !CDS_PN = "272";
"VSS<6>":   PN = "270"  !CDS_PN = "270";
"VSS<7>":   PN = "268"  !CDS_PN = "268";
"VSS<8>":   PN = "265"  !CDS_PN = "265";
"VSS<9>":   PN = "263"  !CDS_PN = "263";
"VSS<10>":   PN = "261"  !CDS_PN = "261";
"VSS<11>":   PN = "259"  !CDS_PN = "259";
"VSS<12>":   PN = "257"  !CDS_PN = "257";
"VSS<13>":   PN = "254"  !CDS_PN = "254";
"VSS<14>":   PN = "252"  !CDS_PN = "252";
"VSS<15>":   PN = "250"  !CDS_PN = "250";
"VSS<16>":   PN = "248"  !CDS_PN = "248";
"VSS<17>":   PN = "246"  !CDS_PN = "246";
"VSS<18>":   PN = "243"  !CDS_PN = "243";
"VSS<19>":   PN = "241"  !CDS_PN = "241";
"VSS<20>":   PN = "239"  !CDS_PN = "239";
"VSS<21>":   PN = "202"  !CDS_PN = "202";
"VSS<22>":   PN = "200"  !CDS_PN = "200";
"VSS<23>":   PN = "198"  !CDS_PN = "198";
"VSS<24>":   PN = "195"  !CDS_PN = "195";
"VSS<25>":   PN = "193"  !CDS_PN = "193";
"VSS<26>":   PN = "191"  !CDS_PN = "191";
"VSS<27>":   PN = "189"  !CDS_PN = "189";
"VSS<28>":   PN = "187"  !CDS_PN = "187";
"VSS<29>":   PN = "184"  !CDS_PN = "184";
"VSS<30>":   PN = "182"  !CDS_PN = "182";
"VSS<31>":   PN = "180"  !CDS_PN = "180";
"VSS<32>":   PN = "178"  !CDS_PN = "178";
"VSS<33>":   PN = "176"  !CDS_PN = "176";
"VSS<34>":   PN = "173"  !CDS_PN = "173";
"VSS<35>":   PN = "171"  !CDS_PN = "171";
"VSS<36>":   PN = "169"  !CDS_PN = "169";
"VSS<37>":   PN = "167"  !CDS_PN = "167";
"VSS<38>":   PN = "165"  !CDS_PN = "165";
"VSS<39>":   PN = "162"  !CDS_PN = "162";
"VSS<40>":   PN = "160"  !CDS_PN = "160";
"VSS<41>":   PN = "158"  !CDS_PN = "158";
"VSS<42>":   PN = "156"  !CDS_PN = "156";
"VSS<43>":   PN = "154"  !CDS_PN = "154";
"VSS<44>":   PN = "151"  !CDS_PN = "151";
"VSS<45>":   PN = "149"  !CDS_PN = "149";
"VSS<46>":   PN = "147"  !CDS_PN = "147";
"VSS<47>":   PN = "138"  !CDS_PN = "138";
"VSS<48>":   PN = "136"  !CDS_PN = "136";
"VSS<49>":   PN = "134"  !CDS_PN = "134";
"VSS<50>":   PN = "131"  !CDS_PN = "131";
"VSS<51>":   PN = "129"  !CDS_PN = "129";
"VSS<52>":   PN = "127"  !CDS_PN = "127";
"VSS<53>":   PN = "125"  !CDS_PN = "125";
"VSS<54>":   PN = "123"  !CDS_PN = "123";
"VSS<55>":   PN = "120"  !CDS_PN = "120";
"VSS<56>":   PN = "118"  !CDS_PN = "118";
"VSS<57>":   PN = "116"  !CDS_PN = "116";
"VSS<58>":   PN = "114"  !CDS_PN = "114";
"VSS<59>":   PN = "112"  !CDS_PN = "112";
"VSS<60>":   PN = "109"  !CDS_PN = "109";
"VSS<61>":   PN = "107"  !CDS_PN = "107";
"VSS<62>":   PN = "105"  !CDS_PN = "105";
"VSS<63>":   PN = "103"  !CDS_PN = "103";
"VSS<64>":   PN = "101"  !CDS_PN = "101";
"VSS<65>":   PN = "98"  !CDS_PN = "98";
"VSS<66>":   PN = "96"  !CDS_PN = "96";
"VSS<67>":   PN = "94"  !CDS_PN = "94";
"VSS<68>":   PN = "57"  !CDS_PN = "57";
"VSS<69>":   PN = "55"  !CDS_PN = "55";
"VSS<70>":   PN = "53"  !CDS_PN = "53";
"VSS<71>":   PN = "50"  !CDS_PN = "50";
"VSS<72>":   PN = "48"  !CDS_PN = "48";
"VSS<73>":   PN = "46"  !CDS_PN = "46";
"VSS<74>":   PN = "44"  !CDS_PN = "44";
"VSS<75>":   PN = "42"  !CDS_PN = "42";
"VSS<76>":   PN = "39"  !CDS_PN = "39";
"VSS<77>":   PN = "37"  !CDS_PN = "37";
"VSS<78>":   PN = "35"  !CDS_PN = "35";
"VSS<79>":   PN = "33"  !CDS_PN = "33";
"VSS<80>":   PN = "31"  !CDS_PN = "31";
"VSS<81>":   PN = "28"  !CDS_PN = "28";
"VSS<82>":   PN = "26"  !CDS_PN = "26";
"VSS<83>":   PN = "24"  !CDS_PN = "24";
"VSS<84>":   PN = "22"  !CDS_PN = "22";
"VSS<85>":   PN = "20"  !CDS_PN = "20";
"VSS<86>":   PN = "17"  !CDS_PN = "17";
"VSS<87>":   PN = "15"  !CDS_PN = "15";
"VSS<88>":   PN = "13"  !CDS_PN = "13";
"VSS<89>":   PN = "11"  !CDS_PN = "11";
"VSS<90>":   PN = "9"  !CDS_PN = "9";
"VSS<91>":   PN = "6"  !CDS_PN = "6";
"VSS<92>":   PN = "4"  !CDS_PN = "4";
"VSS<93>":   PN = "2"  !CDS_PN = "2";
BODY = "SCONN288_H44441004","I61": #LOCATION = "J4G2" !CDS_LOCATION = "J4G2" #SEC = "2" !CDS_SEC = "2";
"DQS0N":   PN = "152"  !CDS_PN = "152";
"DQS0P":   PN = "153"  !CDS_PN = "153";
"DQS1N":   PN = "163"  !CDS_PN = "163";
"DQS1P":   PN = "164"  !CDS_PN = "164";
"DQS2N":   PN = "174"  !CDS_PN = "174";
"DQS2P":   PN = "175"  !CDS_PN = "175";
"DQS3N":   PN = "185"  !CDS_PN = "185";
"DQS3P":   PN = "186"  !CDS_PN = "186";
"DQS4N":   PN = "244"  !CDS_PN = "244";
"DQS4P":   PN = "245"  !CDS_PN = "245";
"DQS5N":   PN = "255"  !CDS_PN = "255";
"DQS5P":   PN = "256"  !CDS_PN = "256";
"DQS6N":   PN = "266"  !CDS_PN = "266";
"DQS6P":   PN = "267"  !CDS_PN = "267";
"DQS7N":   PN = "277"  !CDS_PN = "277";
"DQS7P":   PN = "278"  !CDS_PN = "278";
"DQS8N":   PN = "196"  !CDS_PN = "196";
"DQS8P":   PN = "197"  !CDS_PN = "197";
"DQS9N":   PN = "8"  !CDS_PN = "8";
"DQS9P":   PN = "7"  !CDS_PN = "7";
"DQS10N":   PN = "19"  !CDS_PN = "19";
"DQS10P":   PN = "18"  !CDS_PN = "18";
"DQS11N":   PN = "30"  !CDS_PN = "30";
"DQS11P":   PN = "29"  !CDS_PN = "29";
"DQS12N":   PN = "41"  !CDS_PN = "41";
"DQS12P":   PN = "40"  !CDS_PN = "40";
"DQS13N":   PN = "100"  !CDS_PN = "100";
"DQS13P":   PN = "99"  !CDS_PN = "99";
"DQS14N":   PN = "111"  !CDS_PN = "111";
"DQS14P":   PN = "110"  !CDS_PN = "110";
"DQS15N":   PN = "122"  !CDS_PN = "122";
"DQS15P":   PN = "121"  !CDS_PN = "121";
"DQS16N":   PN = "133"  !CDS_PN = "133";
"DQS16P":   PN = "132"  !CDS_PN = "132";
"DQS17N":   PN = "52"  !CDS_PN = "52";
"DQS17P":   PN = "51"  !CDS_PN = "51";
BODY = "SCONN288_H44441004","I111": #LOCATION = "J4G2" !CDS_LOCATION = "J4G2" #SEC = "1" !CDS_SEC = "1";
"A0":   PN = "79"  !CDS_PN = "79";
"A1":   PN = "72"  !CDS_PN = "72";
"A2":   PN = "216"  !CDS_PN = "216";
"A3":   PN = "71"  !CDS_PN = "71";
"A4":   PN = "214"  !CDS_PN = "214";
"A5":   PN = "213"  !CDS_PN = "213";
"A6":   PN = "69"  !CDS_PN = "69";
"A7":   PN = "211"  !CDS_PN = "211";
"A8":   PN = "68"  !CDS_PN = "68";
"A9":   PN = "66"  !CDS_PN = "66";
"A10":   PN = "225"  !CDS_PN = "225";
"A11":   PN = "210"  !CDS_PN = "210";
"A12":   PN = "65"  !CDS_PN = "65";
"A13":   PN = "232"  !CDS_PN = "232";
"A14_WE_N":   PN = "228"  !CDS_PN = "228";
"A15_CAS_N":   PN = "86"  !CDS_PN = "86";
"A16_RAS_N":   PN = "82"  !CDS_PN = "82";
"A17":   PN = "234"  !CDS_PN = "234";
"ACT_N":   PN = "62"  !CDS_PN = "62";
"ALERT_N":   PN = "208"  !CDS_PN = "208";
"BA<0>":   PN = "81"  !CDS_PN = "81";
"BA<1>":   PN = "224"  !CDS_PN = "224";
"BG<0>":   PN = "63"  !CDS_PN = "63";
"BG<1>":   PN = "207"  !CDS_PN = "207";
"C<2>":   PN = "235"  !CDS_PN = "235";
"CB<0>":   PN = "49"  !CDS_PN = "49";
"CB<1>":   PN = "194"  !CDS_PN = "194";
"CB<2>":   PN = "56"  !CDS_PN = "56";
"CB<3>":   PN = "201"  !CDS_PN = "201";
"CB<4>":   PN = "47"  !CDS_PN = "47";
"CB<5>":   PN = "192"  !CDS_PN = "192";
"CB<6>":   PN = "54"  !CDS_PN = "54";
"CB<7>":   PN = "199"  !CDS_PN = "199";
"CK0N":   PN = "75"  !CDS_PN = "75";
"CK0P":   PN = "74"  !CDS_PN = "74";
"CK1N":   PN = "219"  !CDS_PN = "219";
"CK1P":   PN = "218"  !CDS_PN = "218";
"CKE<0>":   PN = "60"  !CDS_PN = "60";
"CKE<1>":   PN = "203"  !CDS_PN = "203";
"DQ<0>":   PN = "5"  !CDS_PN = "5";
"DQ<1>":   PN = "150"  !CDS_PN = "150";
"DQ<2>":   PN = "12"  !CDS_PN = "12";
"DQ<3>":   PN = "157"  !CDS_PN = "157";
"DQ<4>":   PN = "3"  !CDS_PN = "3";
"DQ<5>":   PN = "148"  !CDS_PN = "148";
"DQ<6>":   PN = "10"  !CDS_PN = "10";
"DQ<7>":   PN = "155"  !CDS_PN = "155";
"DQ<8>":   PN = "16"  !CDS_PN = "16";
"DQ<9>":   PN = "161"  !CDS_PN = "161";
"DQ<10>":   PN = "23"  !CDS_PN = "23";
"DQ<11>":   PN = "168"  !CDS_PN = "168";
"DQ<12>":   PN = "14"  !CDS_PN = "14";
"DQ<13>":   PN = "159"  !CDS_PN = "159";
"DQ<14>":   PN = "21"  !CDS_PN = "21";
"DQ<15>":   PN = "166"  !CDS_PN = "166";
"DQ<16>":   PN = "27"  !CDS_PN = "27";
"DQ<17>":   PN = "172"  !CDS_PN = "172";
"DQ<18>":   PN = "34"  !CDS_PN = "34";
"DQ<19>":   PN = "179"  !CDS_PN = "179";
"DQ<20>":   PN = "25"  !CDS_PN = "25";
"DQ<21>":   PN = "170"  !CDS_PN = "170";
"DQ<22>":   PN = "32"  !CDS_PN = "32";
"DQ<23>":   PN = "177"  !CDS_PN = "177";
"DQ<24>":   PN = "38"  !CDS_PN = "38";
"DQ<25>":   PN = "183"  !CDS_PN = "183";
"DQ<26>":   PN = "45"  !CDS_PN = "45";
"DQ<27>":   PN = "190"  !CDS_PN = "190";
"DQ<28>":   PN = "36"  !CDS_PN = "36";
"DQ<29>":   PN = "181"  !CDS_PN = "181";
"DQ<30>":   PN = "43"  !CDS_PN = "43";
"DQ<31>":   PN = "188"  !CDS_PN = "188";
"DQ<32>":   PN = "97"  !CDS_PN = "97";
"DQ<33>":   PN = "242"  !CDS_PN = "242";
"DQ<34>":   PN = "104"  !CDS_PN = "104";
"DQ<35>":   PN = "249"  !CDS_PN = "249";
"DQ<36>":   PN = "95"  !CDS_PN = "95";
"DQ<37>":   PN = "240"  !CDS_PN = "240";
"DQ<38>":   PN = "102"  !CDS_PN = "102";
"DQ<39>":   PN = "247"  !CDS_PN = "247";
"DQ<40>":   PN = "108"  !CDS_PN = "108";
"DQ<41>":   PN = "253"  !CDS_PN = "253";
"DQ<42>":   PN = "115"  !CDS_PN = "115";
"DQ<43>":   PN = "260"  !CDS_PN = "260";
"DQ<44>":   PN = "106"  !CDS_PN = "106";
"DQ<45>":   PN = "251"  !CDS_PN = "251";
"DQ<46>":   PN = "113"  !CDS_PN = "113";
"DQ<47>":   PN = "258"  !CDS_PN = "258";
"DQ<48>":   PN = "119"  !CDS_PN = "119";
"DQ<49>":   PN = "264"  !CDS_PN = "264";
"DQ<50>":   PN = "126"  !CDS_PN = "126";
"DQ<51>":   PN = "271"  !CDS_PN = "271";
"DQ<52>":   PN = "117"  !CDS_PN = "117";
"DQ<53>":   PN = "262"  !CDS_PN = "262";
"DQ<54>":   PN = "124"  !CDS_PN = "124";
"DQ<55>":   PN = "269"  !CDS_PN = "269";
"DQ<56>":   PN = "130"  !CDS_PN = "130";
"DQ<57>":   PN = "275"  !CDS_PN = "275";
"DQ<58>":   PN = "137"  !CDS_PN = "137";
"DQ<59>":   PN = "282"  !CDS_PN = "282";
"DQ<60>":   PN = "128"  !CDS_PN = "128";
"DQ<61>":   PN = "273"  !CDS_PN = "273";
"DQ<62>":   PN = "135"  !CDS_PN = "135";
"DQ<63>":   PN = "280"  !CDS_PN = "280";
"EVENT_N":   PN = "78"  !CDS_PN = "78";
"ODT<0>":   PN = "87"  !CDS_PN = "87";
"ODT<1>":   PN = "91"  !CDS_PN = "91";
"PAR":   PN = "222"  !CDS_PN = "222";
"RESET_N":   PN = "58"  !CDS_PN = "58";
"RFU<0>":   PN = "205"  !CDS_PN = "205";
"RFU<1>":   PN = "227"  !CDS_PN = "227";
"RFU<2>":   PN = "144"  !CDS_PN = "144";
"S0_N":   PN = "84"  !CDS_PN = "84";
"S1_N":   PN = "89"  !CDS_PN = "89";
"S2_N_C<0>":   PN = "93"  !CDS_PN = "93";
"S3_N_C<1>":   PN = "237"  !CDS_PN = "237";
"SA<0>":   PN = "139"  !CDS_PN = "139";
"SA<1>":   PN = "140"  !CDS_PN = "140";
"SA<2>":   PN = "238"  !CDS_PN = "238";
"SAVE_N_NC":   PN = "230"  !CDS_PN = "230";
"SCL":   PN = "141"  !CDS_PN = "141";
"SDA":   PN = "285"  !CDS_PN = "285";
"VDDSPD":   PN = "284"  !CDS_PN = "284";
"VREFCA":   PN = "146"  !CDS_PN = "146";
BODY = "SCONN288_H44441004","I169": #LOCATION = "J4G2" !CDS_LOCATION = "J4G2" #SEC = "4" !CDS_SEC = "4";
"12V<0>":   PN = "145"  !CDS_PN = "145";
"12V<1>":   PN = "1"  !CDS_PN = "1";
"VDD<0>":   PN = "236"  !CDS_PN = "236";
"VDD<1>":   PN = "233"  !CDS_PN = "233";
"VDD<2>":   PN = "231"  !CDS_PN = "231";
"VDD<3>":   PN = "229"  !CDS_PN = "229";
"VDD<4>":   PN = "226"  !CDS_PN = "226";
"VDD<5>":   PN = "223"  !CDS_PN = "223";
"VDD<6>":   PN = "220"  !CDS_PN = "220";
"VDD<7>":   PN = "217"  !CDS_PN = "217";
"VDD<8>":   PN = "215"  !CDS_PN = "215";
"VDD<9>":   PN = "212"  !CDS_PN = "212";
"VDD<10>":   PN = "209"  !CDS_PN = "209";
"VDD<11>":   PN = "206"  !CDS_PN = "206";
"VDD<12>":   PN = "204"  !CDS_PN = "204";
"VDD<13>":   PN = "92"  !CDS_PN = "92";
"VDD<14>":   PN = "90"  !CDS_PN = "90";
"VDD<15>":   PN = "88"  !CDS_PN = "88";
"VDD<16>":   PN = "85"  !CDS_PN = "85";
"VDD<17>":   PN = "83"  !CDS_PN = "83";
"VDD<18>":   PN = "80"  !CDS_PN = "80";
"VDD<19>":   PN = "76"  !CDS_PN = "76";
"VDD<20>":   PN = "73"  !CDS_PN = "73";
"VDD<21>":   PN = "70"  !CDS_PN = "70";
"VDD<22>":   PN = "67"  !CDS_PN = "67";
"VDD<23>":   PN = "64"  !CDS_PN = "64";
"VDD<24>":   PN = "61"  !CDS_PN = "61";
"VDD<25>":   PN = "59"  !CDS_PN = "59";
"VPP<0>":   PN = "287"  !CDS_PN = "287";
"VPP<1>":   PN = "286"  !CDS_PN = "286";
"VPP<2>":   PN = "288"  !CDS_PN = "288";
"VPP<3>":   PN = "143"  !CDS_PN = "143";
"VPP<4>":   PN = "142"  !CDS_PN = "142";
"VTT<0>":   PN = "221"  !CDS_PN = "221";
"VTT<1>":   PN = "77"  !CDS_PN = "77";
BODY = "CAP_A","I179": #LOCATION = "C4G3" !CDS_LOCATION = "C4G3" &SEC = "1" #&CDS_SEC = "1";
"A":   PN = "1"  !CDS_PN = "1";
"B":   PN = "2"  !CDS_PN = "2";
DRAWING = "@baseboard_fab2_lib.baseboard_fab2(sch_1):page46";
BODY = "CAP_A","I5": #LOCATION = "C6U9" !CDS_LOCATION = "C6U9" #SEC = "1" !CDS_SEC = "1";
"A":   PN = "1"  !CDS_PN = "1";
"B":   PN = "2"  !CDS_PN = "2";
BODY = "SCONN288_H44441003","I14": #LOCATION = "J6U1" !CDS_LOCATION = "J6U1" #SEC = "1" !CDS_SEC = "1";
"A0":   PN = "79"  !CDS_PN = "79";
"A1":   PN = "72"  !CDS_PN = "72";
"A2":   PN = "216"  !CDS_PN = "216";
"A3":   PN = "71"  !CDS_PN = "71";
"A4":   PN = "214"  !CDS_PN = "214";
"A5":   PN = "213"  !CDS_PN = "213";
"A6":   PN = "69"  !CDS_PN = "69";
"A7":   PN = "211"  !CDS_PN = "211";
"A8":   PN = "68"  !CDS_PN = "68";
"A9":   PN = "66"  !CDS_PN = "66";
"A10":   PN = "225"  !CDS_PN = "225";
"A11":   PN = "210"  !CDS_PN = "210";
"A12":   PN = "65"  !CDS_PN = "65";
"A13":   PN = "232"  !CDS_PN = "232";
"A14_WE_N":   PN = "228"  !CDS_PN = "228";
"A15_CAS_N":   PN = "86"  !CDS_PN = "86";
"A16_RAS_N":   PN = "82"  !CDS_PN = "82";
"A17":   PN = "234"  !CDS_PN = "234";
"ACT_N":   PN = "62"  !CDS_PN = "62";
"ALERT_N":   PN = "208"  !CDS_PN = "208";
"BA<0>":   PN = "81"  !CDS_PN = "81";
"BA<1>":   PN = "224"  !CDS_PN = "224";
"BG<0>":   PN = "63"  !CDS_PN = "63";
"BG<1>":   PN = "207"  !CDS_PN = "207";
"C<2>":   PN = "235"  !CDS_PN = "235";
"CB<0>":   PN = "49"  !CDS_PN = "49";
"CB<1>":   PN = "194"  !CDS_PN = "194";
"CB<2>":   PN = "56"  !CDS_PN = "56";
"CB<3>":   PN = "201"  !CDS_PN = "201";
"CB<4>":   PN = "47"  !CDS_PN = "47";
"CB<5>":   PN = "192"  !CDS_PN = "192";
"CB<6>":   PN = "54"  !CDS_PN = "54";
"CB<7>":   PN = "199"  !CDS_PN = "199";
"CK0N":   PN = "75"  !CDS_PN = "75";
"CK0P":   PN = "74"  !CDS_PN = "74";
"CK1N":   PN = "219"  !CDS_PN = "219";
"CK1P":   PN = "218"  !CDS_PN = "218";
"CKE<0>":   PN = "60"  !CDS_PN = "60";
"CKE<1>":   PN = "203"  !CDS_PN = "203";
"DQ<0>":   PN = "5"  !CDS_PN = "5";
"DQ<1>":   PN = "150"  !CDS_PN = "150";
"DQ<2>":   PN = "12"  !CDS_PN = "12";
"DQ<3>":   PN = "157"  !CDS_PN = "157";
"DQ<4>":   PN = "3"  !CDS_PN = "3";
"DQ<5>":   PN = "148"  !CDS_PN = "148";
"DQ<6>":   PN = "10"  !CDS_PN = "10";
"DQ<7>":   PN = "155"  !CDS_PN = "155";
"DQ<8>":   PN = "16"  !CDS_PN = "16";
"DQ<9>":   PN = "161"  !CDS_PN = "161";
"DQ<10>":   PN = "23"  !CDS_PN = "23";
"DQ<11>":   PN = "168"  !CDS_PN = "168";
"DQ<12>":   PN = "14"  !CDS_PN = "14";
"DQ<13>":   PN = "159"  !CDS_PN = "159";
"DQ<14>":   PN = "21"  !CDS_PN = "21";
"DQ<15>":   PN = "166"  !CDS_PN = "166";
"DQ<16>":   PN = "27"  !CDS_PN = "27";
"DQ<17>":   PN = "172"  !CDS_PN = "172";
"DQ<18>":   PN = "34"  !CDS_PN = "34";
"DQ<19>":   PN = "179"  !CDS_PN = "179";
"DQ<20>":   PN = "25"  !CDS_PN = "25";
"DQ<21>":   PN = "170"  !CDS_PN = "170";
"DQ<22>":   PN = "32"  !CDS_PN = "32";
"DQ<23>":   PN = "177"  !CDS_PN = "177";
"DQ<24>":   PN = "38"  !CDS_PN = "38";
"DQ<25>":   PN = "183"  !CDS_PN = "183";
"DQ<26>":   PN = "45"  !CDS_PN = "45";
"DQ<27>":   PN = "190"  !CDS_PN = "190";
"DQ<28>":   PN = "36"  !CDS_PN = "36";
"DQ<29>":   PN = "181"  !CDS_PN = "181";
"DQ<30>":   PN = "43"  !CDS_PN = "43";
"DQ<31>":   PN = "188"  !CDS_PN = "188";
"DQ<32>":   PN = "97"  !CDS_PN = "97";
"DQ<33>":   PN = "242"  !CDS_PN = "242";
"DQ<34>":   PN = "104"  !CDS_PN = "104";
"DQ<35>":   PN = "249"  !CDS_PN = "249";
"DQ<36>":   PN = "95"  !CDS_PN = "95";
"DQ<37>":   PN = "240"  !CDS_PN = "240";
"DQ<38>":   PN = "102"  !CDS_PN = "102";
"DQ<39>":   PN = "247"  !CDS_PN = "247";
"DQ<40>":   PN = "108"  !CDS_PN = "108";
"DQ<41>":   PN = "253"  !CDS_PN = "253";
"DQ<42>":   PN = "115"  !CDS_PN = "115";
"DQ<43>":   PN = "260"  !CDS_PN = "260";
"DQ<44>":   PN = "106"  !CDS_PN = "106";
"DQ<45>":   PN = "251"  !CDS_PN = "251";
"DQ<46>":   PN = "113"  !CDS_PN = "113";
"DQ<47>":   PN = "258"  !CDS_PN = "258";
"DQ<48>":   PN = "119"  !CDS_PN = "119";
"DQ<49>":   PN = "264"  !CDS_PN = "264";
"DQ<50>":   PN = "126"  !CDS_PN = "126";
"DQ<51>":   PN = "271"  !CDS_PN = "271";
"DQ<52>":   PN = "117"  !CDS_PN = "117";
"DQ<53>":   PN = "262"  !CDS_PN = "262";
"DQ<54>":   PN = "124"  !CDS_PN = "124";
"DQ<55>":   PN = "269"  !CDS_PN = "269";
"DQ<56>":   PN = "130"  !CDS_PN = "130";
"DQ<57>":   PN = "275"  !CDS_PN = "275";
"DQ<58>":   PN = "137"  !CDS_PN = "137";
"DQ<59>":   PN = "282"  !CDS_PN = "282";
"DQ<60>":   PN = "128"  !CDS_PN = "128";
"DQ<61>":   PN = "273"  !CDS_PN = "273";
"DQ<62>":   PN = "135"  !CDS_PN = "135";
"DQ<63>":   PN = "280"  !CDS_PN = "280";
"EVENT_N":   PN = "78"  !CDS_PN = "78";
"ODT<0>":   PN = "87"  !CDS_PN = "87";
"ODT<1>":   PN = "91"  !CDS_PN = "91";
"PAR":   PN = "222"  !CDS_PN = "222";
"RESET_N":   PN = "58"  !CDS_PN = "58";
"RFU<0>":   PN = "205"  !CDS_PN = "205";
"RFU<1>":   PN = "227"  !CDS_PN = "227";
"RFU<2>":   PN = "144"  !CDS_PN = "144";
"S0_N":   PN = "84"  !CDS_PN = "84";
"S1_N":   PN = "89"  !CDS_PN = "89";
"S2_N_C<0>":   PN = "93"  !CDS_PN = "93";
"S3_N_C<1>":   PN = "237"  !CDS_PN = "237";
"SA<0>":   PN = "139"  !CDS_PN = "139";
"SA<1>":   PN = "140"  !CDS_PN = "140";
"SA<2>":   PN = "238"  !CDS_PN = "238";
"SAVE_N_NC":   PN = "230"  !CDS_PN = "230";
"SCL":   PN = "141"  !CDS_PN = "141";
"SDA":   PN = "285"  !CDS_PN = "285";
"VDDSPD":   PN = "284"  !CDS_PN = "284";
"VREFCA":   PN = "146"  !CDS_PN = "146";
BODY = "SCONN288_H44441003","I67": #LOCATION = "J6U1" !CDS_LOCATION = "J6U1" #SEC = "4" !CDS_SEC = "4";
"12V<0>":   PN = "145"  !CDS_PN = "145";
"12V<1>":   PN = "1"  !CDS_PN = "1";
"VDD<0>":   PN = "236"  !CDS_PN = "236";
"VDD<1>":   PN = "233"  !CDS_PN = "233";
"VDD<2>":   PN = "231"  !CDS_PN = "231";
"VDD<3>":   PN = "229"  !CDS_PN = "229";
"VDD<4>":   PN = "226"  !CDS_PN = "226";
"VDD<5>":   PN = "223"  !CDS_PN = "223";
"VDD<6>":   PN = "220"  !CDS_PN = "220";
"VDD<7>":   PN = "217"  !CDS_PN = "217";
"VDD<8>":   PN = "215"  !CDS_PN = "215";
"VDD<9>":   PN = "212"  !CDS_PN = "212";
"VDD<10>":   PN = "209"  !CDS_PN = "209";
"VDD<11>":   PN = "206"  !CDS_PN = "206";
"VDD<12>":   PN = "204"  !CDS_PN = "204";
"VDD<13>":   PN = "92"  !CDS_PN = "92";
"VDD<14>":   PN = "90"  !CDS_PN = "90";
"VDD<15>":   PN = "88"  !CDS_PN = "88";
"VDD<16>":   PN = "85"  !CDS_PN = "85";
"VDD<17>":   PN = "83"  !CDS_PN = "83";
"VDD<18>":   PN = "80"  !CDS_PN = "80";
"VDD<19>":   PN = "76"  !CDS_PN = "76";
"VDD<20>":   PN = "73"  !CDS_PN = "73";
"VDD<21>":   PN = "70"  !CDS_PN = "70";
"VDD<22>":   PN = "67"  !CDS_PN = "67";
"VDD<23>":   PN = "64"  !CDS_PN = "64";
"VDD<24>":   PN = "61"  !CDS_PN = "61";
"VDD<25>":   PN = "59"  !CDS_PN = "59";
"VPP<0>":   PN = "287"  !CDS_PN = "287";
"VPP<1>":   PN = "286"  !CDS_PN = "286";
"VPP<2>":   PN = "288"  !CDS_PN = "288";
"VPP<3>":   PN = "143"  !CDS_PN = "143";
"VPP<4>":   PN = "142"  !CDS_PN = "142";
"VTT<0>":   PN = "221"  !CDS_PN = "221";
"VTT<1>":   PN = "77"  !CDS_PN = "77";
BODY = "SCONN288_H44441003","I112": #LOCATION = "J6U1" !CDS_LOCATION = "J6U1" #SEC = "2" !CDS_SEC = "2";
"DQS0N":   PN = "152"  !CDS_PN = "152";
"DQS0P":   PN = "153"  !CDS_PN = "153";
"DQS1N":   PN = "163"  !CDS_PN = "163";
"DQS1P":   PN = "164"  !CDS_PN = "164";
"DQS2N":   PN = "174"  !CDS_PN = "174";
"DQS2P":   PN = "175"  !CDS_PN = "175";
"DQS3N":   PN = "185"  !CDS_PN = "185";
"DQS3P":   PN = "186"  !CDS_PN = "186";
"DQS4N":   PN = "244"  !CDS_PN = "244";
"DQS4P":   PN = "245"  !CDS_PN = "245";
"DQS5N":   PN = "255"  !CDS_PN = "255";
"DQS5P":   PN = "256"  !CDS_PN = "256";
"DQS6N":   PN = "266"  !CDS_PN = "266";
"DQS6P":   PN = "267"  !CDS_PN = "267";
"DQS7N":   PN = "277"  !CDS_PN = "277";
"DQS7P":   PN = "278"  !CDS_PN = "278";
"DQS8N":   PN = "196"  !CDS_PN = "196";
"DQS8P":   PN = "197"  !CDS_PN = "197";
"DQS9N":   PN = "8"  !CDS_PN = "8";
"DQS9P":   PN = "7"  !CDS_PN = "7";
"DQS10N":   PN = "19"  !CDS_PN = "19";
"DQS10P":   PN = "18"  !CDS_PN = "18";
"DQS11N":   PN = "30"  !CDS_PN = "30";
"DQS11P":   PN = "29"  !CDS_PN = "29";
"DQS12N":   PN = "41"  !CDS_PN = "41";
"DQS12P":   PN = "40"  !CDS_PN = "40";
"DQS13N":   PN = "100"  !CDS_PN = "100";
"DQS13P":   PN = "99"  !CDS_PN = "99";
"DQS14N":   PN = "111"  !CDS_PN = "111";
"DQS14P":   PN = "110"  !CDS_PN = "110";
"DQS15N":   PN = "122"  !CDS_PN = "122";
"DQS15P":   PN = "121"  !CDS_PN = "121";
"DQS16N":   PN = "133"  !CDS_PN = "133";
"DQS16P":   PN = "132"  !CDS_PN = "132";
"DQS17N":   PN = "52"  !CDS_PN = "52";
"DQS17P":   PN = "51"  !CDS_PN = "51";
BODY = "SCONN288_H44441003","I138": #LOCATION = "J6U1" !CDS_LOCATION = "J6U1" #SEC = "3" !CDS_SEC = "3";
"VSS<0>":   PN = "283"  !CDS_PN = "283";
"VSS<1>":   PN = "281"  !CDS_PN = "281";
"VSS<2>":   PN = "279"  !CDS_PN = "279";
"VSS<3>":   PN = "276"  !CDS_PN = "276";
"VSS<4>":   PN = "274"  !CDS_PN = "274";
"VSS<5>":   PN = "272"  !CDS_PN = "272";
"VSS<6>":   PN = "270"  !CDS_PN = "270";
"VSS<7>":   PN = "268"  !CDS_PN = "268";
"VSS<8>":   PN = "265"  !CDS_PN = "265";
"VSS<9>":   PN = "263"  !CDS_PN = "263";
"VSS<10>":   PN = "261"  !CDS_PN = "261";
"VSS<11>":   PN = "259"  !CDS_PN = "259";
"VSS<12>":   PN = "257"  !CDS_PN = "257";
"VSS<13>":   PN = "254"  !CDS_PN = "254";
"VSS<14>":   PN = "252"  !CDS_PN = "252";
"VSS<15>":   PN = "250"  !CDS_PN = "250";
"VSS<16>":   PN = "248"  !CDS_PN = "248";
"VSS<17>":   PN = "246"  !CDS_PN = "246";
"VSS<18>":   PN = "243"  !CDS_PN = "243";
"VSS<19>":   PN = "241"  !CDS_PN = "241";
"VSS<20>":   PN = "239"  !CDS_PN = "239";
"VSS<21>":   PN = "202"  !CDS_PN = "202";
"VSS<22>":   PN = "200"  !CDS_PN = "200";
"VSS<23>":   PN = "198"  !CDS_PN = "198";
"VSS<24>":   PN = "195"  !CDS_PN = "195";
"VSS<25>":   PN = "193"  !CDS_PN = "193";
"VSS<26>":   PN = "191"  !CDS_PN = "191";
"VSS<27>":   PN = "189"  !CDS_PN = "189";
"VSS<28>":   PN = "187"  !CDS_PN = "187";
"VSS<29>":   PN = "184"  !CDS_PN = "184";
"VSS<30>":   PN = "182"  !CDS_PN = "182";
"VSS<31>":   PN = "180"  !CDS_PN = "180";
"VSS<32>":   PN = "178"  !CDS_PN = "178";
"VSS<33>":   PN = "176"  !CDS_PN = "176";
"VSS<34>":   PN = "173"  !CDS_PN = "173";
"VSS<35>":   PN = "171"  !CDS_PN = "171";
"VSS<36>":   PN = "169"  !CDS_PN = "169";
"VSS<37>":   PN = "167"  !CDS_PN = "167";
"VSS<38>":   PN = "165"  !CDS_PN = "165";
"VSS<39>":   PN = "162"  !CDS_PN = "162";
"VSS<40>":   PN = "160"  !CDS_PN = "160";
"VSS<41>":   PN = "158"  !CDS_PN = "158";
"VSS<42>":   PN = "156"  !CDS_PN = "156";
"VSS<43>":   PN = "154"  !CDS_PN = "154";
"VSS<44>":   PN = "151"  !CDS_PN = "151";
"VSS<45>":   PN = "149"  !CDS_PN = "149";
"VSS<46>":   PN = "147"  !CDS_PN = "147";
"VSS<47>":   PN = "138"  !CDS_PN = "138";
"VSS<48>":   PN = "136"  !CDS_PN = "136";
"VSS<49>":   PN = "134"  !CDS_PN = "134";
"VSS<50>":   PN = "131"  !CDS_PN = "131";
"VSS<51>":   PN = "129"  !CDS_PN = "129";
"VSS<52>":   PN = "127"  !CDS_PN = "127";
"VSS<53>":   PN = "125"  !CDS_PN = "125";
"VSS<54>":   PN = "123"  !CDS_PN = "123";
"VSS<55>":   PN = "120"  !CDS_PN = "120";
"VSS<56>":   PN = "118"  !CDS_PN = "118";
"VSS<57>":   PN = "116"  !CDS_PN = "116";
"VSS<58>":   PN = "114"  !CDS_PN = "114";
"VSS<59>":   PN = "112"  !CDS_PN = "112";
"VSS<60>":   PN = "109"  !CDS_PN = "109";
"VSS<61>":   PN = "107"  !CDS_PN = "107";
"VSS<62>":   PN = "105"  !CDS_PN = "105";
"VSS<63>":   PN = "103"  !CDS_PN = "103";
"VSS<64>":   PN = "101"  !CDS_PN = "101";
"VSS<65>":   PN = "98"  !CDS_PN = "98";
"VSS<66>":   PN = "96"  !CDS_PN = "96";
"VSS<67>":   PN = "94"  !CDS_PN = "94";
"VSS<68>":   PN = "57"  !CDS_PN = "57";
"VSS<69>":   PN = "55"  !CDS_PN = "55";
"VSS<70>":   PN = "53"  !CDS_PN = "53";
"VSS<71>":   PN = "50"  !CDS_PN = "50";
"VSS<72>":   PN = "48"  !CDS_PN = "48";
"VSS<73>":   PN = "46"  !CDS_PN = "46";
"VSS<74>":   PN = "44"  !CDS_PN = "44";
"VSS<75>":   PN = "42"  !CDS_PN = "42";
"VSS<76>":   PN = "39"  !CDS_PN = "39";
"VSS<77>":   PN = "37"  !CDS_PN = "37";
"VSS<78>":   PN = "35"  !CDS_PN = "35";
"VSS<79>":   PN = "33"  !CDS_PN = "33";
"VSS<80>":   PN = "31"  !CDS_PN = "31";
"VSS<81>":   PN = "28"  !CDS_PN = "28";
"VSS<82>":   PN = "26"  !CDS_PN = "26";
"VSS<83>":   PN = "24"  !CDS_PN = "24";
"VSS<84>":   PN = "22"  !CDS_PN = "22";
"VSS<85>":   PN = "20"  !CDS_PN = "20";
"VSS<86>":   PN = "17"  !CDS_PN = "17";
"VSS<87>":   PN = "15"  !CDS_PN = "15";
"VSS<88>":   PN = "13"  !CDS_PN = "13";
"VSS<89>":   PN = "11"  !CDS_PN = "11";
"VSS<90>":   PN = "9"  !CDS_PN = "9";
"VSS<91>":   PN = "6"  !CDS_PN = "6";
"VSS<92>":   PN = "4"  !CDS_PN = "4";
"VSS<93>":   PN = "2"  !CDS_PN = "2";
DRAWING = "@baseboard_fab2_lib.baseboard_fab2(sch_1):page47";
BODY = "SCONN288_H44441004","I43": #LOCATION = "J4G3" !CDS_LOCATION = "J4G3" #SEC = "3" !CDS_SEC = "3";
"VSS<0>":   PN = "283"  !CDS_PN = "283";
"VSS<1>":   PN = "281"  !CDS_PN = "281";
"VSS<2>":   PN = "279"  !CDS_PN = "279";
"VSS<3>":   PN = "276"  !CDS_PN = "276";
"VSS<4>":   PN = "274"  !CDS_PN = "274";
"VSS<5>":   PN = "272"  !CDS_PN = "272";
"VSS<6>":   PN = "270"  !CDS_PN = "270";
"VSS<7>":   PN = "268"  !CDS_PN = "268";
"VSS<8>":   PN = "265"  !CDS_PN = "265";
"VSS<9>":   PN = "263"  !CDS_PN = "263";
"VSS<10>":   PN = "261"  !CDS_PN = "261";
"VSS<11>":   PN = "259"  !CDS_PN = "259";
"VSS<12>":   PN = "257"  !CDS_PN = "257";
"VSS<13>":   PN = "254"  !CDS_PN = "254";
"VSS<14>":   PN = "252"  !CDS_PN = "252";
"VSS<15>":   PN = "250"  !CDS_PN = "250";
"VSS<16>":   PN = "248"  !CDS_PN = "248";
"VSS<17>":   PN = "246"  !CDS_PN = "246";
"VSS<18>":   PN = "243"  !CDS_PN = "243";
"VSS<19>":   PN = "241"  !CDS_PN = "241";
"VSS<20>":   PN = "239"  !CDS_PN = "239";
"VSS<21>":   PN = "202"  !CDS_PN = "202";
"VSS<22>":   PN = "200"  !CDS_PN = "200";
"VSS<23>":   PN = "198"  !CDS_PN = "198";
"VSS<24>":   PN = "195"  !CDS_PN = "195";
"VSS<25>":   PN = "193"  !CDS_PN = "193";
"VSS<26>":   PN = "191"  !CDS_PN = "191";
"VSS<27>":   PN = "189"  !CDS_PN = "189";
"VSS<28>":   PN = "187"  !CDS_PN = "187";
"VSS<29>":   PN = "184"  !CDS_PN = "184";
"VSS<30>":   PN = "182"  !CDS_PN = "182";
"VSS<31>":   PN = "180"  !CDS_PN = "180";
"VSS<32>":   PN = "178"  !CDS_PN = "178";
"VSS<33>":   PN = "176"  !CDS_PN = "176";
"VSS<34>":   PN = "173"  !CDS_PN = "173";
"VSS<35>":   PN = "171"  !CDS_PN = "171";
"VSS<36>":   PN = "169"  !CDS_PN = "169";
"VSS<37>":   PN = "167"  !CDS_PN = "167";
"VSS<38>":   PN = "165"  !CDS_PN = "165";
"VSS<39>":   PN = "162"  !CDS_PN = "162";
"VSS<40>":   PN = "160"  !CDS_PN = "160";
"VSS<41>":   PN = "158"  !CDS_PN = "158";
"VSS<42>":   PN = "156"  !CDS_PN = "156";
"VSS<43>":   PN = "154"  !CDS_PN = "154";
"VSS<44>":   PN = "151"  !CDS_PN = "151";
"VSS<45>":   PN = "149"  !CDS_PN = "149";
"VSS<46>":   PN = "147"  !CDS_PN = "147";
"VSS<47>":   PN = "138"  !CDS_PN = "138";
"VSS<48>":   PN = "136"  !CDS_PN = "136";
"VSS<49>":   PN = "134"  !CDS_PN = "134";
"VSS<50>":   PN = "131"  !CDS_PN = "131";
"VSS<51>":   PN = "129"  !CDS_PN = "129";
"VSS<52>":   PN = "127"  !CDS_PN = "127";
"VSS<53>":   PN = "125"  !CDS_PN = "125";
"VSS<54>":   PN = "123"  !CDS_PN = "123";
"VSS<55>":   PN = "120"  !CDS_PN = "120";
"VSS<56>":   PN = "118"  !CDS_PN = "118";
"VSS<57>":   PN = "116"  !CDS_PN = "116";
"VSS<58>":   PN = "114"  !CDS_PN = "114";
"VSS<59>":   PN = "112"  !CDS_PN = "112";
"VSS<60>":   PN = "109"  !CDS_PN = "109";
"VSS<61>":   PN = "107"  !CDS_PN = "107";
"VSS<62>":   PN = "105"  !CDS_PN = "105";
"VSS<63>":   PN = "103"  !CDS_PN = "103";
"VSS<64>":   PN = "101"  !CDS_PN = "101";
"VSS<65>":   PN = "98"  !CDS_PN = "98";
"VSS<66>":   PN = "96"  !CDS_PN = "96";
"VSS<67>":   PN = "94"  !CDS_PN = "94";
"VSS<68>":   PN = "57"  !CDS_PN = "57";
"VSS<69>":   PN = "55"  !CDS_PN = "55";
"VSS<70>":   PN = "53"  !CDS_PN = "53";
"VSS<71>":   PN = "50"  !CDS_PN = "50";
"VSS<72>":   PN = "48"  !CDS_PN = "48";
"VSS<73>":   PN = "46"  !CDS_PN = "46";
"VSS<74>":   PN = "44"  !CDS_PN = "44";
"VSS<75>":   PN = "42"  !CDS_PN = "42";
"VSS<76>":   PN = "39"  !CDS_PN = "39";
"VSS<77>":   PN = "37"  !CDS_PN = "37";
"VSS<78>":   PN = "35"  !CDS_PN = "35";
"VSS<79>":   PN = "33"  !CDS_PN = "33";
"VSS<80>":   PN = "31"  !CDS_PN = "31";
"VSS<81>":   PN = "28"  !CDS_PN = "28";
"VSS<82>":   PN = "26"  !CDS_PN = "26";
"VSS<83>":   PN = "24"  !CDS_PN = "24";
"VSS<84>":   PN = "22"  !CDS_PN = "22";
"VSS<85>":   PN = "20"  !CDS_PN = "20";
"VSS<86>":   PN = "17"  !CDS_PN = "17";
"VSS<87>":   PN = "15"  !CDS_PN = "15";
"VSS<88>":   PN = "13"  !CDS_PN = "13";
"VSS<89>":   PN = "11"  !CDS_PN = "11";
"VSS<90>":   PN = "9"  !CDS_PN = "9";
"VSS<91>":   PN = "6"  !CDS_PN = "6";
"VSS<92>":   PN = "4"  !CDS_PN = "4";
"VSS<93>":   PN = "2"  !CDS_PN = "2";
BODY = "SCONN288_H44441004","I61": #LOCATION = "J4G3" !CDS_LOCATION = "J4G3" #SEC = "2" !CDS_SEC = "2";
"DQS0N":   PN = "152"  !CDS_PN = "152";
"DQS0P":   PN = "153"  !CDS_PN = "153";
"DQS1N":   PN = "163"  !CDS_PN = "163";
"DQS1P":   PN = "164"  !CDS_PN = "164";
"DQS2N":   PN = "174"  !CDS_PN = "174";
"DQS2P":   PN = "175"  !CDS_PN = "175";
"DQS3N":   PN = "185"  !CDS_PN = "185";
"DQS3P":   PN = "186"  !CDS_PN = "186";
"DQS4N":   PN = "244"  !CDS_PN = "244";
"DQS4P":   PN = "245"  !CDS_PN = "245";
"DQS5N":   PN = "255"  !CDS_PN = "255";
"DQS5P":   PN = "256"  !CDS_PN = "256";
"DQS6N":   PN = "266"  !CDS_PN = "266";
"DQS6P":   PN = "267"  !CDS_PN = "267";
"DQS7N":   PN = "277"  !CDS_PN = "277";
"DQS7P":   PN = "278"  !CDS_PN = "278";
"DQS8N":   PN = "196"  !CDS_PN = "196";
"DQS8P":   PN = "197"  !CDS_PN = "197";
"DQS9N":   PN = "8"  !CDS_PN = "8";
"DQS9P":   PN = "7"  !CDS_PN = "7";
"DQS10N":   PN = "19"  !CDS_PN = "19";
"DQS10P":   PN = "18"  !CDS_PN = "18";
"DQS11N":   PN = "30"  !CDS_PN = "30";
"DQS11P":   PN = "29"  !CDS_PN = "29";
"DQS12N":   PN = "41"  !CDS_PN = "41";
"DQS12P":   PN = "40"  !CDS_PN = "40";
"DQS13N":   PN = "100"  !CDS_PN = "100";
"DQS13P":   PN = "99"  !CDS_PN = "99";
"DQS14N":   PN = "111"  !CDS_PN = "111";
"DQS14P":   PN = "110"  !CDS_PN = "110";
"DQS15N":   PN = "122"  !CDS_PN = "122";
"DQS15P":   PN = "121"  !CDS_PN = "121";
"DQS16N":   PN = "133"  !CDS_PN = "133";
"DQS16P":   PN = "132"  !CDS_PN = "132";
"DQS17N":   PN = "52"  !CDS_PN = "52";
"DQS17P":   PN = "51"  !CDS_PN = "51";
BODY = "SCONN288_H44441004","I111": #LOCATION = "J4G3" !CDS_LOCATION = "J4G3" #SEC = "1" !CDS_SEC = "1";
"A0":   PN = "79"  !CDS_PN = "79";
"A1":   PN = "72"  !CDS_PN = "72";
"A2":   PN = "216"  !CDS_PN = "216";
"A3":   PN = "71"  !CDS_PN = "71";
"A4":   PN = "214"  !CDS_PN = "214";
"A5":   PN = "213"  !CDS_PN = "213";
"A6":   PN = "69"  !CDS_PN = "69";
"A7":   PN = "211"  !CDS_PN = "211";
"A8":   PN = "68"  !CDS_PN = "68";
"A9":   PN = "66"  !CDS_PN = "66";
"A10":   PN = "225"  !CDS_PN = "225";
"A11":   PN = "210"  !CDS_PN = "210";
"A12":   PN = "65"  !CDS_PN = "65";
"A13":   PN = "232"  !CDS_PN = "232";
"A14_WE_N":   PN = "228"  !CDS_PN = "228";
"A15_CAS_N":   PN = "86"  !CDS_PN = "86";
"A16_RAS_N":   PN = "82"  !CDS_PN = "82";
"A17":   PN = "234"  !CDS_PN = "234";
"ACT_N":   PN = "62"  !CDS_PN = "62";
"ALERT_N":   PN = "208"  !CDS_PN = "208";
"BA<0>":   PN = "81"  !CDS_PN = "81";
"BA<1>":   PN = "224"  !CDS_PN = "224";
"BG<0>":   PN = "63"  !CDS_PN = "63";
"BG<1>":   PN = "207"  !CDS_PN = "207";
"C<2>":   PN = "235"  !CDS_PN = "235";
"CB<0>":   PN = "49"  !CDS_PN = "49";
"CB<1>":   PN = "194"  !CDS_PN = "194";
"CB<2>":   PN = "56"  !CDS_PN = "56";
"CB<3>":   PN = "201"  !CDS_PN = "201";
"CB<4>":   PN = "47"  !CDS_PN = "47";
"CB<5>":   PN = "192"  !CDS_PN = "192";
"CB<6>":   PN = "54"  !CDS_PN = "54";
"CB<7>":   PN = "199"  !CDS_PN = "199";
"CK0N":   PN = "75"  !CDS_PN = "75";
"CK0P":   PN = "74"  !CDS_PN = "74";
"CK1N":   PN = "219"  !CDS_PN = "219";
"CK1P":   PN = "218"  !CDS_PN = "218";
"CKE<0>":   PN = "60"  !CDS_PN = "60";
"CKE<1>":   PN = "203"  !CDS_PN = "203";
"DQ<0>":   PN = "5"  !CDS_PN = "5";
"DQ<1>":   PN = "150"  !CDS_PN = "150";
"DQ<2>":   PN = "12"  !CDS_PN = "12";
"DQ<3>":   PN = "157"  !CDS_PN = "157";
"DQ<4>":   PN = "3"  !CDS_PN = "3";
"DQ<5>":   PN = "148"  !CDS_PN = "148";
"DQ<6>":   PN = "10"  !CDS_PN = "10";
"DQ<7>":   PN = "155"  !CDS_PN = "155";
"DQ<8>":   PN = "16"  !CDS_PN = "16";
"DQ<9>":   PN = "161"  !CDS_PN = "161";
"DQ<10>":   PN = "23"  !CDS_PN = "23";
"DQ<11>":   PN = "168"  !CDS_PN = "168";
"DQ<12>":   PN = "14"  !CDS_PN = "14";
"DQ<13>":   PN = "159"  !CDS_PN = "159";
"DQ<14>":   PN = "21"  !CDS_PN = "21";
"DQ<15>":   PN = "166"  !CDS_PN = "166";
"DQ<16>":   PN = "27"  !CDS_PN = "27";
"DQ<17>":   PN = "172"  !CDS_PN = "172";
"DQ<18>":   PN = "34"  !CDS_PN = "34";
"DQ<19>":   PN = "179"  !CDS_PN = "179";
"DQ<20>":   PN = "25"  !CDS_PN = "25";
"DQ<21>":   PN = "170"  !CDS_PN = "170";
"DQ<22>":   PN = "32"  !CDS_PN = "32";
"DQ<23>":   PN = "177"  !CDS_PN = "177";
"DQ<24>":   PN = "38"  !CDS_PN = "38";
"DQ<25>":   PN = "183"  !CDS_PN = "183";
"DQ<26>":   PN = "45"  !CDS_PN = "45";
"DQ<27>":   PN = "190"  !CDS_PN = "190";
"DQ<28>":   PN = "36"  !CDS_PN = "36";
"DQ<29>":   PN = "181"  !CDS_PN = "181";
"DQ<30>":   PN = "43"  !CDS_PN = "43";
"DQ<31>":   PN = "188"  !CDS_PN = "188";
"DQ<32>":   PN = "97"  !CDS_PN = "97";
"DQ<33>":   PN = "242"  !CDS_PN = "242";
"DQ<34>":   PN = "104"  !CDS_PN = "104";
"DQ<35>":   PN = "249"  !CDS_PN = "249";
"DQ<36>":   PN = "95"  !CDS_PN = "95";
"DQ<37>":   PN = "240"  !CDS_PN = "240";
"DQ<38>":   PN = "102"  !CDS_PN = "102";
"DQ<39>":   PN = "247"  !CDS_PN = "247";
"DQ<40>":   PN = "108"  !CDS_PN = "108";
"DQ<41>":   PN = "253"  !CDS_PN = "253";
"DQ<42>":   PN = "115"  !CDS_PN = "115";
"DQ<43>":   PN = "260"  !CDS_PN = "260";
"DQ<44>":   PN = "106"  !CDS_PN = "106";
"DQ<45>":   PN = "251"  !CDS_PN = "251";
"DQ<46>":   PN = "113"  !CDS_PN = "113";
"DQ<47>":   PN = "258"  !CDS_PN = "258";
"DQ<48>":   PN = "119"  !CDS_PN = "119";
"DQ<49>":   PN = "264"  !CDS_PN = "264";
"DQ<50>":   PN = "126"  !CDS_PN = "126";
"DQ<51>":   PN = "271"  !CDS_PN = "271";
"DQ<52>":   PN = "117"  !CDS_PN = "117";
"DQ<53>":   PN = "262"  !CDS_PN = "262";
"DQ<54>":   PN = "124"  !CDS_PN = "124";
"DQ<55>":   PN = "269"  !CDS_PN = "269";
"DQ<56>":   PN = "130"  !CDS_PN = "130";
"DQ<57>":   PN = "275"  !CDS_PN = "275";
"DQ<58>":   PN = "137"  !CDS_PN = "137";
"DQ<59>":   PN = "282"  !CDS_PN = "282";
"DQ<60>":   PN = "128"  !CDS_PN = "128";
"DQ<61>":   PN = "273"  !CDS_PN = "273";
"DQ<62>":   PN = "135"  !CDS_PN = "135";
"DQ<63>":   PN = "280"  !CDS_PN = "280";
"EVENT_N":   PN = "78"  !CDS_PN = "78";
"ODT<0>":   PN = "87"  !CDS_PN = "87";
"ODT<1>":   PN = "91"  !CDS_PN = "91";
"PAR":   PN = "222"  !CDS_PN = "222";
"RESET_N":   PN = "58"  !CDS_PN = "58";
"RFU<0>":   PN = "205"  !CDS_PN = "205";
"RFU<1>":   PN = "227"  !CDS_PN = "227";
"RFU<2>":   PN = "144"  !CDS_PN = "144";
"S0_N":   PN = "84"  !CDS_PN = "84";
"S1_N":   PN = "89"  !CDS_PN = "89";
"S2_N_C<0>":   PN = "93"  !CDS_PN = "93";
"S3_N_C<1>":   PN = "237"  !CDS_PN = "237";
"SA<0>":   PN = "139"  !CDS_PN = "139";
"SA<1>":   PN = "140"  !CDS_PN = "140";
"SA<2>":   PN = "238"  !CDS_PN = "238";
"SAVE_N_NC":   PN = "230"  !CDS_PN = "230";
"SCL":   PN = "141"  !CDS_PN = "141";
"SDA":   PN = "285"  !CDS_PN = "285";
"VDDSPD":   PN = "284"  !CDS_PN = "284";
"VREFCA":   PN = "146"  !CDS_PN = "146";
BODY = "SCONN288_H44441004","I179": #LOCATION = "J4G3" !CDS_LOCATION = "J4G3" #SEC = "4" !CDS_SEC = "4";
"12V<0>":   PN = "145"  !CDS_PN = "145";
"12V<1>":   PN = "1"  !CDS_PN = "1";
"VDD<0>":   PN = "236"  !CDS_PN = "236";
"VDD<1>":   PN = "233"  !CDS_PN = "233";
"VDD<2>":   PN = "231"  !CDS_PN = "231";
"VDD<3>":   PN = "229"  !CDS_PN = "229";
"VDD<4>":   PN = "226"  !CDS_PN = "226";
"VDD<5>":   PN = "223"  !CDS_PN = "223";
"VDD<6>":   PN = "220"  !CDS_PN = "220";
"VDD<7>":   PN = "217"  !CDS_PN = "217";
"VDD<8>":   PN = "215"  !CDS_PN = "215";
"VDD<9>":   PN = "212"  !CDS_PN = "212";
"VDD<10>":   PN = "209"  !CDS_PN = "209";
"VDD<11>":   PN = "206"  !CDS_PN = "206";
"VDD<12>":   PN = "204"  !CDS_PN = "204";
"VDD<13>":   PN = "92"  !CDS_PN = "92";
"VDD<14>":   PN = "90"  !CDS_PN = "90";
"VDD<15>":   PN = "88"  !CDS_PN = "88";
"VDD<16>":   PN = "85"  !CDS_PN = "85";
"VDD<17>":   PN = "83"  !CDS_PN = "83";
"VDD<18>":   PN = "80"  !CDS_PN = "80";
"VDD<19>":   PN = "76"  !CDS_PN = "76";
"VDD<20>":   PN = "73"  !CDS_PN = "73";
"VDD<21>":   PN = "70"  !CDS_PN = "70";
"VDD<22>":   PN = "67"  !CDS_PN = "67";
"VDD<23>":   PN = "64"  !CDS_PN = "64";
"VDD<24>":   PN = "61"  !CDS_PN = "61";
"VDD<25>":   PN = "59"  !CDS_PN = "59";
"VPP<0>":   PN = "287"  !CDS_PN = "287";
"VPP<1>":   PN = "286"  !CDS_PN = "286";
"VPP<2>":   PN = "288"  !CDS_PN = "288";
"VPP<3>":   PN = "143"  !CDS_PN = "143";
"VPP<4>":   PN = "142"  !CDS_PN = "142";
"VTT<0>":   PN = "221"  !CDS_PN = "221";
"VTT<1>":   PN = "77"  !CDS_PN = "77";
BODY = "CAP_A","I188": #LOCATION = "C4G19" !CDS_LOCATION = "C4G19" #SEC = "1" !CDS_SEC = "1";
"A":   PN = "1"  !CDS_PN = "1";
"B":   PN = "2"  !CDS_PN = "2";
DRAWING = "@baseboard_fab2_lib.baseboard_fab2(sch_1):page48";
BODY = "SCONN288_H44441003","I43": #LOCATION = "J6U2" !CDS_LOCATION = "J6U2" #SEC = "3" !CDS_SEC = "3";
"VSS<0>":   PN = "283"  !CDS_PN = "283";
"VSS<1>":   PN = "281"  !CDS_PN = "281";
"VSS<2>":   PN = "279"  !CDS_PN = "279";
"VSS<3>":   PN = "276"  !CDS_PN = "276";
"VSS<4>":   PN = "274"  !CDS_PN = "274";
"VSS<5>":   PN = "272"  !CDS_PN = "272";
"VSS<6>":   PN = "270"  !CDS_PN = "270";
"VSS<7>":   PN = "268"  !CDS_PN = "268";
"VSS<8>":   PN = "265"  !CDS_PN = "265";
"VSS<9>":   PN = "263"  !CDS_PN = "263";
"VSS<10>":   PN = "261"  !CDS_PN = "261";
"VSS<11>":   PN = "259"  !CDS_PN = "259";
"VSS<12>":   PN = "257"  !CDS_PN = "257";
"VSS<13>":   PN = "254"  !CDS_PN = "254";
"VSS<14>":   PN = "252"  !CDS_PN = "252";
"VSS<15>":   PN = "250"  !CDS_PN = "250";
"VSS<16>":   PN = "248"  !CDS_PN = "248";
"VSS<17>":   PN = "246"  !CDS_PN = "246";
"VSS<18>":   PN = "243"  !CDS_PN = "243";
"VSS<19>":   PN = "241"  !CDS_PN = "241";
"VSS<20>":   PN = "239"  !CDS_PN = "239";
"VSS<21>":   PN = "202"  !CDS_PN = "202";
"VSS<22>":   PN = "200"  !CDS_PN = "200";
"VSS<23>":   PN = "198"  !CDS_PN = "198";
"VSS<24>":   PN = "195"  !CDS_PN = "195";
"VSS<25>":   PN = "193"  !CDS_PN = "193";
"VSS<26>":   PN = "191"  !CDS_PN = "191";
"VSS<27>":   PN = "189"  !CDS_PN = "189";
"VSS<28>":   PN = "187"  !CDS_PN = "187";
"VSS<29>":   PN = "184"  !CDS_PN = "184";
"VSS<30>":   PN = "182"  !CDS_PN = "182";
"VSS<31>":   PN = "180"  !CDS_PN = "180";
"VSS<32>":   PN = "178"  !CDS_PN = "178";
"VSS<33>":   PN = "176"  !CDS_PN = "176";
"VSS<34>":   PN = "173"  !CDS_PN = "173";
"VSS<35>":   PN = "171"  !CDS_PN = "171";
"VSS<36>":   PN = "169"  !CDS_PN = "169";
"VSS<37>":   PN = "167"  !CDS_PN = "167";
"VSS<38>":   PN = "165"  !CDS_PN = "165";
"VSS<39>":   PN = "162"  !CDS_PN = "162";
"VSS<40>":   PN = "160"  !CDS_PN = "160";
"VSS<41>":   PN = "158"  !CDS_PN = "158";
"VSS<42>":   PN = "156"  !CDS_PN = "156";
"VSS<43>":   PN = "154"  !CDS_PN = "154";
"VSS<44>":   PN = "151"  !CDS_PN = "151";
"VSS<45>":   PN = "149"  !CDS_PN = "149";
"VSS<46>":   PN = "147"  !CDS_PN = "147";
"VSS<47>":   PN = "138"  !CDS_PN = "138";
"VSS<48>":   PN = "136"  !CDS_PN = "136";
"VSS<49>":   PN = "134"  !CDS_PN = "134";
"VSS<50>":   PN = "131"  !CDS_PN = "131";
"VSS<51>":   PN = "129"  !CDS_PN = "129";
"VSS<52>":   PN = "127"  !CDS_PN = "127";
"VSS<53>":   PN = "125"  !CDS_PN = "125";
"VSS<54>":   PN = "123"  !CDS_PN = "123";
"VSS<55>":   PN = "120"  !CDS_PN = "120";
"VSS<56>":   PN = "118"  !CDS_PN = "118";
"VSS<57>":   PN = "116"  !CDS_PN = "116";
"VSS<58>":   PN = "114"  !CDS_PN = "114";
"VSS<59>":   PN = "112"  !CDS_PN = "112";
"VSS<60>":   PN = "109"  !CDS_PN = "109";
"VSS<61>":   PN = "107"  !CDS_PN = "107";
"VSS<62>":   PN = "105"  !CDS_PN = "105";
"VSS<63>":   PN = "103"  !CDS_PN = "103";
"VSS<64>":   PN = "101"  !CDS_PN = "101";
"VSS<65>":   PN = "98"  !CDS_PN = "98";
"VSS<66>":   PN = "96"  !CDS_PN = "96";
"VSS<67>":   PN = "94"  !CDS_PN = "94";
"VSS<68>":   PN = "57"  !CDS_PN = "57";
"VSS<69>":   PN = "55"  !CDS_PN = "55";
"VSS<70>":   PN = "53"  !CDS_PN = "53";
"VSS<71>":   PN = "50"  !CDS_PN = "50";
"VSS<72>":   PN = "48"  !CDS_PN = "48";
"VSS<73>":   PN = "46"  !CDS_PN = "46";
"VSS<74>":   PN = "44"  !CDS_PN = "44";
"VSS<75>":   PN = "42"  !CDS_PN = "42";
"VSS<76>":   PN = "39"  !CDS_PN = "39";
"VSS<77>":   PN = "37"  !CDS_PN = "37";
"VSS<78>":   PN = "35"  !CDS_PN = "35";
"VSS<79>":   PN = "33"  !CDS_PN = "33";
"VSS<80>":   PN = "31"  !CDS_PN = "31";
"VSS<81>":   PN = "28"  !CDS_PN = "28";
"VSS<82>":   PN = "26"  !CDS_PN = "26";
"VSS<83>":   PN = "24"  !CDS_PN = "24";
"VSS<84>":   PN = "22"  !CDS_PN = "22";
"VSS<85>":   PN = "20"  !CDS_PN = "20";
"VSS<86>":   PN = "17"  !CDS_PN = "17";
"VSS<87>":   PN = "15"  !CDS_PN = "15";
"VSS<88>":   PN = "13"  !CDS_PN = "13";
"VSS<89>":   PN = "11"  !CDS_PN = "11";
"VSS<90>":   PN = "9"  !CDS_PN = "9";
"VSS<91>":   PN = "6"  !CDS_PN = "6";
"VSS<92>":   PN = "4"  !CDS_PN = "4";
"VSS<93>":   PN = "2"  !CDS_PN = "2";
BODY = "SCONN288_H44441003","I61": #LOCATION = "J6U2" !CDS_LOCATION = "J6U2" #SEC = "2" !CDS_SEC = "2";
"DQS0N":   PN = "152"  !CDS_PN = "152";
"DQS0P":   PN = "153"  !CDS_PN = "153";
"DQS1N":   PN = "163"  !CDS_PN = "163";
"DQS1P":   PN = "164"  !CDS_PN = "164";
"DQS2N":   PN = "174"  !CDS_PN = "174";
"DQS2P":   PN = "175"  !CDS_PN = "175";
"DQS3N":   PN = "185"  !CDS_PN = "185";
"DQS3P":   PN = "186"  !CDS_PN = "186";
"DQS4N":   PN = "244"  !CDS_PN = "244";
"DQS4P":   PN = "245"  !CDS_PN = "245";
"DQS5N":   PN = "255"  !CDS_PN = "255";
"DQS5P":   PN = "256"  !CDS_PN = "256";
"DQS6N":   PN = "266"  !CDS_PN = "266";
"DQS6P":   PN = "267"  !CDS_PN = "267";
"DQS7N":   PN = "277"  !CDS_PN = "277";
"DQS7P":   PN = "278"  !CDS_PN = "278";
"DQS8N":   PN = "196"  !CDS_PN = "196";
"DQS8P":   PN = "197"  !CDS_PN = "197";
"DQS9N":   PN = "8"  !CDS_PN = "8";
"DQS9P":   PN = "7"  !CDS_PN = "7";
"DQS10N":   PN = "19"  !CDS_PN = "19";
"DQS10P":   PN = "18"  !CDS_PN = "18";
"DQS11N":   PN = "30"  !CDS_PN = "30";
"DQS11P":   PN = "29"  !CDS_PN = "29";
"DQS12N":   PN = "41"  !CDS_PN = "41";
"DQS12P":   PN = "40"  !CDS_PN = "40";
"DQS13N":   PN = "100"  !CDS_PN = "100";
"DQS13P":   PN = "99"  !CDS_PN = "99";
"DQS14N":   PN = "111"  !CDS_PN = "111";
"DQS14P":   PN = "110"  !CDS_PN = "110";
"DQS15N":   PN = "122"  !CDS_PN = "122";
"DQS15P":   PN = "121"  !CDS_PN = "121";
"DQS16N":   PN = "133"  !CDS_PN = "133";
"DQS16P":   PN = "132"  !CDS_PN = "132";
"DQS17N":   PN = "52"  !CDS_PN = "52";
"DQS17P":   PN = "51"  !CDS_PN = "51";
BODY = "SCONN288_H44441003","I111": #LOCATION = "J6U2" !CDS_LOCATION = "J6U2" #SEC = "1" !CDS_SEC = "1";
"A0":   PN = "79"  !CDS_PN = "79";
"A1":   PN = "72"  !CDS_PN = "72";
"A2":   PN = "216"  !CDS_PN = "216";
"A3":   PN = "71"  !CDS_PN = "71";
"A4":   PN = "214"  !CDS_PN = "214";
"A5":   PN = "213"  !CDS_PN = "213";
"A6":   PN = "69"  !CDS_PN = "69";
"A7":   PN = "211"  !CDS_PN = "211";
"A8":   PN = "68"  !CDS_PN = "68";
"A9":   PN = "66"  !CDS_PN = "66";
"A10":   PN = "225"  !CDS_PN = "225";
"A11":   PN = "210"  !CDS_PN = "210";
"A12":   PN = "65"  !CDS_PN = "65";
"A13":   PN = "232"  !CDS_PN = "232";
"A14_WE_N":   PN = "228"  !CDS_PN = "228";
"A15_CAS_N":   PN = "86"  !CDS_PN = "86";
"A16_RAS_N":   PN = "82"  !CDS_PN = "82";
"A17":   PN = "234"  !CDS_PN = "234";
"ACT_N":   PN = "62"  !CDS_PN = "62";
"ALERT_N":   PN = "208"  !CDS_PN = "208";
"BA<0>":   PN = "81"  !CDS_PN = "81";
"BA<1>":   PN = "224"  !CDS_PN = "224";
"BG<0>":   PN = "63"  !CDS_PN = "63";
"BG<1>":   PN = "207"  !CDS_PN = "207";
"C<2>":   PN = "235"  !CDS_PN = "235";
"CB<0>":   PN = "49"  !CDS_PN = "49";
"CB<1>":   PN = "194"  !CDS_PN = "194";
"CB<2>":   PN = "56"  !CDS_PN = "56";
"CB<3>":   PN = "201"  !CDS_PN = "201";
"CB<4>":   PN = "47"  !CDS_PN = "47";
"CB<5>":   PN = "192"  !CDS_PN = "192";
"CB<6>":   PN = "54"  !CDS_PN = "54";
"CB<7>":   PN = "199"  !CDS_PN = "199";
"CK0N":   PN = "75"  !CDS_PN = "75";
"CK0P":   PN = "74"  !CDS_PN = "74";
"CK1N":   PN = "219"  !CDS_PN = "219";
"CK1P":   PN = "218"  !CDS_PN = "218";
"CKE<0>":   PN = "60"  !CDS_PN = "60";
"CKE<1>":   PN = "203"  !CDS_PN = "203";
"DQ<0>":   PN = "5"  !CDS_PN = "5";
"DQ<1>":   PN = "150"  !CDS_PN = "150";
"DQ<2>":   PN = "12"  !CDS_PN = "12";
"DQ<3>":   PN = "157"  !CDS_PN = "157";
"DQ<4>":   PN = "3"  !CDS_PN = "3";
"DQ<5>":   PN = "148"  !CDS_PN = "148";
"DQ<6>":   PN = "10"  !CDS_PN = "10";
"DQ<7>":   PN = "155"  !CDS_PN = "155";
"DQ<8>":   PN = "16"  !CDS_PN = "16";
"DQ<9>":   PN = "161"  !CDS_PN = "161";
"DQ<10>":   PN = "23"  !CDS_PN = "23";
"DQ<11>":   PN = "168"  !CDS_PN = "168";
"DQ<12>":   PN = "14"  !CDS_PN = "14";
"DQ<13>":   PN = "159"  !CDS_PN = "159";
"DQ<14>":   PN = "21"  !CDS_PN = "21";
"DQ<15>":   PN = "166"  !CDS_PN = "166";
"DQ<16>":   PN = "27"  !CDS_PN = "27";
"DQ<17>":   PN = "172"  !CDS_PN = "172";
"DQ<18>":   PN = "34"  !CDS_PN = "34";
"DQ<19>":   PN = "179"  !CDS_PN = "179";
"DQ<20>":   PN = "25"  !CDS_PN = "25";
"DQ<21>":   PN = "170"  !CDS_PN = "170";
"DQ<22>":   PN = "32"  !CDS_PN = "32";
"DQ<23>":   PN = "177"  !CDS_PN = "177";
"DQ<24>":   PN = "38"  !CDS_PN = "38";
"DQ<25>":   PN = "183"  !CDS_PN = "183";
"DQ<26>":   PN = "45"  !CDS_PN = "45";
"DQ<27>":   PN = "190"  !CDS_PN = "190";
"DQ<28>":   PN = "36"  !CDS_PN = "36";
"DQ<29>":   PN = "181"  !CDS_PN = "181";
"DQ<30>":   PN = "43"  !CDS_PN = "43";
"DQ<31>":   PN = "188"  !CDS_PN = "188";
"DQ<32>":   PN = "97"  !CDS_PN = "97";
"DQ<33>":   PN = "242"  !CDS_PN = "242";
"DQ<34>":   PN = "104"  !CDS_PN = "104";
"DQ<35>":   PN = "249"  !CDS_PN = "249";
"DQ<36>":   PN = "95"  !CDS_PN = "95";
"DQ<37>":   PN = "240"  !CDS_PN = "240";
"DQ<38>":   PN = "102"  !CDS_PN = "102";
"DQ<39>":   PN = "247"  !CDS_PN = "247";
"DQ<40>":   PN = "108"  !CDS_PN = "108";
"DQ<41>":   PN = "253"  !CDS_PN = "253";
"DQ<42>":   PN = "115"  !CDS_PN = "115";
"DQ<43>":   PN = "260"  !CDS_PN = "260";
"DQ<44>":   PN = "106"  !CDS_PN = "106";
"DQ<45>":   PN = "251"  !CDS_PN = "251";
"DQ<46>":   PN = "113"  !CDS_PN = "113";
"DQ<47>":   PN = "258"  !CDS_PN = "258";
"DQ<48>":   PN = "119"  !CDS_PN = "119";
"DQ<49>":   PN = "264"  !CDS_PN = "264";
"DQ<50>":   PN = "126"  !CDS_PN = "126";
"DQ<51>":   PN = "271"  !CDS_PN = "271";
"DQ<52>":   PN = "117"  !CDS_PN = "117";
"DQ<53>":   PN = "262"  !CDS_PN = "262";
"DQ<54>":   PN = "124"  !CDS_PN = "124";
"DQ<55>":   PN = "269"  !CDS_PN = "269";
"DQ<56>":   PN = "130"  !CDS_PN = "130";
"DQ<57>":   PN = "275"  !CDS_PN = "275";
"DQ<58>":   PN = "137"  !CDS_PN = "137";
"DQ<59>":   PN = "282"  !CDS_PN = "282";
"DQ<60>":   PN = "128"  !CDS_PN = "128";
"DQ<61>":   PN = "273"  !CDS_PN = "273";
"DQ<62>":   PN = "135"  !CDS_PN = "135";
"DQ<63>":   PN = "280"  !CDS_PN = "280";
"EVENT_N":   PN = "78"  !CDS_PN = "78";
"ODT<0>":   PN = "87"  !CDS_PN = "87";
"ODT<1>":   PN = "91"  !CDS_PN = "91";
"PAR":   PN = "222"  !CDS_PN = "222";
"RESET_N":   PN = "58"  !CDS_PN = "58";
"RFU<0>":   PN = "205"  !CDS_PN = "205";
"RFU<1>":   PN = "227"  !CDS_PN = "227";
"RFU<2>":   PN = "144"  !CDS_PN = "144";
"S0_N":   PN = "84"  !CDS_PN = "84";
"S1_N":   PN = "89"  !CDS_PN = "89";
"S2_N_C<0>":   PN = "93"  !CDS_PN = "93";
"S3_N_C<1>":   PN = "237"  !CDS_PN = "237";
"SA<0>":   PN = "139"  !CDS_PN = "139";
"SA<1>":   PN = "140"  !CDS_PN = "140";
"SA<2>":   PN = "238"  !CDS_PN = "238";
"SAVE_N_NC":   PN = "230"  !CDS_PN = "230";
"SCL":   PN = "141"  !CDS_PN = "141";
"SDA":   PN = "285"  !CDS_PN = "285";
"VDDSPD":   PN = "284"  !CDS_PN = "284";
"VREFCA":   PN = "146"  !CDS_PN = "146";
BODY = "SCONN288_H44441003","I171": #LOCATION = "J6U2" !CDS_LOCATION = "J6U2" #SEC = "4" !CDS_SEC = "4";
"12V<0>":   PN = "145"  !CDS_PN = "145";
"12V<1>":   PN = "1"  !CDS_PN = "1";
"VDD<0>":   PN = "236"  !CDS_PN = "236";
"VDD<1>":   PN = "233"  !CDS_PN = "233";
"VDD<2>":   PN = "231"  !CDS_PN = "231";
"VDD<3>":   PN = "229"  !CDS_PN = "229";
"VDD<4>":   PN = "226"  !CDS_PN = "226";
"VDD<5>":   PN = "223"  !CDS_PN = "223";
"VDD<6>":   PN = "220"  !CDS_PN = "220";
"VDD<7>":   PN = "217"  !CDS_PN = "217";
"VDD<8>":   PN = "215"  !CDS_PN = "215";
"VDD<9>":   PN = "212"  !CDS_PN = "212";
"VDD<10>":   PN = "209"  !CDS_PN = "209";
"VDD<11>":   PN = "206"  !CDS_PN = "206";
"VDD<12>":   PN = "204"  !CDS_PN = "204";
"VDD<13>":   PN = "92"  !CDS_PN = "92";
"VDD<14>":   PN = "90"  !CDS_PN = "90";
"VDD<15>":   PN = "88"  !CDS_PN = "88";
"VDD<16>":   PN = "85"  !CDS_PN = "85";
"VDD<17>":   PN = "83"  !CDS_PN = "83";
"VDD<18>":   PN = "80"  !CDS_PN = "80";
"VDD<19>":   PN = "76"  !CDS_PN = "76";
"VDD<20>":   PN = "73"  !CDS_PN = "73";
"VDD<21>":   PN = "70"  !CDS_PN = "70";
"VDD<22>":   PN = "67"  !CDS_PN = "67";
"VDD<23>":   PN = "64"  !CDS_PN = "64";
"VDD<24>":   PN = "61"  !CDS_PN = "61";
"VDD<25>":   PN = "59"  !CDS_PN = "59";
"VPP<0>":   PN = "287"  !CDS_PN = "287";
"VPP<1>":   PN = "286"  !CDS_PN = "286";
"VPP<2>":   PN = "288"  !CDS_PN = "288";
"VPP<3>":   PN = "143"  !CDS_PN = "143";
"VPP<4>":   PN = "142"  !CDS_PN = "142";
"VTT<0>":   PN = "221"  !CDS_PN = "221";
"VTT<1>":   PN = "77"  !CDS_PN = "77";
BODY = "CAP_A","I176": #LOCATION = "C6U17" !CDS_LOCATION = "C6U17" #SEC = "1" !CDS_SEC = "1";
"A":   PN = "1"  !CDS_PN = "1";
"B":   PN = "2"  !CDS_PN = "2";
DRAWING = "@baseboard_fab2_lib.baseboard_fab2(sch_1):page49";
BODY = "SCONN288_H44441004","I43": #LOCATION = "J4B1" !CDS_LOCATION = "J4B1" #SEC = "3" !CDS_SEC = "3";
"VSS<0>":   PN = "283"  !CDS_PN = "283";
"VSS<1>":   PN = "281"  !CDS_PN = "281";
"VSS<2>":   PN = "279"  !CDS_PN = "279";
"VSS<3>":   PN = "276"  !CDS_PN = "276";
"VSS<4>":   PN = "274"  !CDS_PN = "274";
"VSS<5>":   PN = "272"  !CDS_PN = "272";
"VSS<6>":   PN = "270"  !CDS_PN = "270";
"VSS<7>":   PN = "268"  !CDS_PN = "268";
"VSS<8>":   PN = "265"  !CDS_PN = "265";
"VSS<9>":   PN = "263"  !CDS_PN = "263";
"VSS<10>":   PN = "261"  !CDS_PN = "261";
"VSS<11>":   PN = "259"  !CDS_PN = "259";
"VSS<12>":   PN = "257"  !CDS_PN = "257";
"VSS<13>":   PN = "254"  !CDS_PN = "254";
"VSS<14>":   PN = "252"  !CDS_PN = "252";
"VSS<15>":   PN = "250"  !CDS_PN = "250";
"VSS<16>":   PN = "248"  !CDS_PN = "248";
"VSS<17>":   PN = "246"  !CDS_PN = "246";
"VSS<18>":   PN = "243"  !CDS_PN = "243";
"VSS<19>":   PN = "241"  !CDS_PN = "241";
"VSS<20>":   PN = "239"  !CDS_PN = "239";
"VSS<21>":   PN = "202"  !CDS_PN = "202";
"VSS<22>":   PN = "200"  !CDS_PN = "200";
"VSS<23>":   PN = "198"  !CDS_PN = "198";
"VSS<24>":   PN = "195"  !CDS_PN = "195";
"VSS<25>":   PN = "193"  !CDS_PN = "193";
"VSS<26>":   PN = "191"  !CDS_PN = "191";
"VSS<27>":   PN = "189"  !CDS_PN = "189";
"VSS<28>":   PN = "187"  !CDS_PN = "187";
"VSS<29>":   PN = "184"  !CDS_PN = "184";
"VSS<30>":   PN = "182"  !CDS_PN = "182";
"VSS<31>":   PN = "180"  !CDS_PN = "180";
"VSS<32>":   PN = "178"  !CDS_PN = "178";
"VSS<33>":   PN = "176"  !CDS_PN = "176";
"VSS<34>":   PN = "173"  !CDS_PN = "173";
"VSS<35>":   PN = "171"  !CDS_PN = "171";
"VSS<36>":   PN = "169"  !CDS_PN = "169";
"VSS<37>":   PN = "167"  !CDS_PN = "167";
"VSS<38>":   PN = "165"  !CDS_PN = "165";
"VSS<39>":   PN = "162"  !CDS_PN = "162";
"VSS<40>":   PN = "160"  !CDS_PN = "160";
"VSS<41>":   PN = "158"  !CDS_PN = "158";
"VSS<42>":   PN = "156"  !CDS_PN = "156";
"VSS<43>":   PN = "154"  !CDS_PN = "154";
"VSS<44>":   PN = "151"  !CDS_PN = "151";
"VSS<45>":   PN = "149"  !CDS_PN = "149";
"VSS<46>":   PN = "147"  !CDS_PN = "147";
"VSS<47>":   PN = "138"  !CDS_PN = "138";
"VSS<48>":   PN = "136"  !CDS_PN = "136";
"VSS<49>":   PN = "134"  !CDS_PN = "134";
"VSS<50>":   PN = "131"  !CDS_PN = "131";
"VSS<51>":   PN = "129"  !CDS_PN = "129";
"VSS<52>":   PN = "127"  !CDS_PN = "127";
"VSS<53>":   PN = "125"  !CDS_PN = "125";
"VSS<54>":   PN = "123"  !CDS_PN = "123";
"VSS<55>":   PN = "120"  !CDS_PN = "120";
"VSS<56>":   PN = "118"  !CDS_PN = "118";
"VSS<57>":   PN = "116"  !CDS_PN = "116";
"VSS<58>":   PN = "114"  !CDS_PN = "114";
"VSS<59>":   PN = "112"  !CDS_PN = "112";
"VSS<60>":   PN = "109"  !CDS_PN = "109";
"VSS<61>":   PN = "107"  !CDS_PN = "107";
"VSS<62>":   PN = "105"  !CDS_PN = "105";
"VSS<63>":   PN = "103"  !CDS_PN = "103";
"VSS<64>":   PN = "101"  !CDS_PN = "101";
"VSS<65>":   PN = "98"  !CDS_PN = "98";
"VSS<66>":   PN = "96"  !CDS_PN = "96";
"VSS<67>":   PN = "94"  !CDS_PN = "94";
"VSS<68>":   PN = "57"  !CDS_PN = "57";
"VSS<69>":   PN = "55"  !CDS_PN = "55";
"VSS<70>":   PN = "53"  !CDS_PN = "53";
"VSS<71>":   PN = "50"  !CDS_PN = "50";
"VSS<72>":   PN = "48"  !CDS_PN = "48";
"VSS<73>":   PN = "46"  !CDS_PN = "46";
"VSS<74>":   PN = "44"  !CDS_PN = "44";
"VSS<75>":   PN = "42"  !CDS_PN = "42";
"VSS<76>":   PN = "39"  !CDS_PN = "39";
"VSS<77>":   PN = "37"  !CDS_PN = "37";
"VSS<78>":   PN = "35"  !CDS_PN = "35";
"VSS<79>":   PN = "33"  !CDS_PN = "33";
"VSS<80>":   PN = "31"  !CDS_PN = "31";
"VSS<81>":   PN = "28"  !CDS_PN = "28";
"VSS<82>":   PN = "26"  !CDS_PN = "26";
"VSS<83>":   PN = "24"  !CDS_PN = "24";
"VSS<84>":   PN = "22"  !CDS_PN = "22";
"VSS<85>":   PN = "20"  !CDS_PN = "20";
"VSS<86>":   PN = "17"  !CDS_PN = "17";
"VSS<87>":   PN = "15"  !CDS_PN = "15";
"VSS<88>":   PN = "13"  !CDS_PN = "13";
"VSS<89>":   PN = "11"  !CDS_PN = "11";
"VSS<90>":   PN = "9"  !CDS_PN = "9";
"VSS<91>":   PN = "6"  !CDS_PN = "6";
"VSS<92>":   PN = "4"  !CDS_PN = "4";
"VSS<93>":   PN = "2"  !CDS_PN = "2";
BODY = "SCONN288_H44441004","I66": #LOCATION = "J4B1" !CDS_LOCATION = "J4B1" #SEC = "2" !CDS_SEC = "2";
"DQS0N":   PN = "152"  !CDS_PN = "152";
"DQS0P":   PN = "153"  !CDS_PN = "153";
"DQS1N":   PN = "163"  !CDS_PN = "163";
"DQS1P":   PN = "164"  !CDS_PN = "164";
"DQS2N":   PN = "174"  !CDS_PN = "174";
"DQS2P":   PN = "175"  !CDS_PN = "175";
"DQS3N":   PN = "185"  !CDS_PN = "185";
"DQS3P":   PN = "186"  !CDS_PN = "186";
"DQS4N":   PN = "244"  !CDS_PN = "244";
"DQS4P":   PN = "245"  !CDS_PN = "245";
"DQS5N":   PN = "255"  !CDS_PN = "255";
"DQS5P":   PN = "256"  !CDS_PN = "256";
"DQS6N":   PN = "266"  !CDS_PN = "266";
"DQS6P":   PN = "267"  !CDS_PN = "267";
"DQS7N":   PN = "277"  !CDS_PN = "277";
"DQS7P":   PN = "278"  !CDS_PN = "278";
"DQS8N":   PN = "196"  !CDS_PN = "196";
"DQS8P":   PN = "197"  !CDS_PN = "197";
"DQS9N":   PN = "8"  !CDS_PN = "8";
"DQS9P":   PN = "7"  !CDS_PN = "7";
"DQS10N":   PN = "19"  !CDS_PN = "19";
"DQS10P":   PN = "18"  !CDS_PN = "18";
"DQS11N":   PN = "30"  !CDS_PN = "30";
"DQS11P":   PN = "29"  !CDS_PN = "29";
"DQS12N":   PN = "41"  !CDS_PN = "41";
"DQS12P":   PN = "40"  !CDS_PN = "40";
"DQS13N":   PN = "100"  !CDS_PN = "100";
"DQS13P":   PN = "99"  !CDS_PN = "99";
"DQS14N":   PN = "111"  !CDS_PN = "111";
"DQS14P":   PN = "110"  !CDS_PN = "110";
"DQS15N":   PN = "122"  !CDS_PN = "122";
"DQS15P":   PN = "121"  !CDS_PN = "121";
"DQS16N":   PN = "133"  !CDS_PN = "133";
"DQS16P":   PN = "132"  !CDS_PN = "132";
"DQS17N":   PN = "52"  !CDS_PN = "52";
"DQS17P":   PN = "51"  !CDS_PN = "51";
BODY = "SCONN288_H44441004","I111": #LOCATION = "J4B1" !CDS_LOCATION = "J4B1" #SEC = "1" !CDS_SEC = "1";
"A0":   PN = "79"  !CDS_PN = "79";
"A1":   PN = "72"  !CDS_PN = "72";
"A2":   PN = "216"  !CDS_PN = "216";
"A3":   PN = "71"  !CDS_PN = "71";
"A4":   PN = "214"  !CDS_PN = "214";
"A5":   PN = "213"  !CDS_PN = "213";
"A6":   PN = "69"  !CDS_PN = "69";
"A7":   PN = "211"  !CDS_PN = "211";
"A8":   PN = "68"  !CDS_PN = "68";
"A9":   PN = "66"  !CDS_PN = "66";
"A10":   PN = "225"  !CDS_PN = "225";
"A11":   PN = "210"  !CDS_PN = "210";
"A12":   PN = "65"  !CDS_PN = "65";
"A13":   PN = "232"  !CDS_PN = "232";
"A14_WE_N":   PN = "228"  !CDS_PN = "228";
"A15_CAS_N":   PN = "86"  !CDS_PN = "86";
"A16_RAS_N":   PN = "82"  !CDS_PN = "82";
"A17":   PN = "234"  !CDS_PN = "234";
"ACT_N":   PN = "62"  !CDS_PN = "62";
"ALERT_N":   PN = "208"  !CDS_PN = "208";
"BA<0>":   PN = "81"  !CDS_PN = "81";
"BA<1>":   PN = "224"  !CDS_PN = "224";
"BG<0>":   PN = "63"  !CDS_PN = "63";
"BG<1>":   PN = "207"  !CDS_PN = "207";
"C<2>":   PN = "235"  !CDS_PN = "235";
"CB<0>":   PN = "49"  !CDS_PN = "49";
"CB<1>":   PN = "194"  !CDS_PN = "194";
"CB<2>":   PN = "56"  !CDS_PN = "56";
"CB<3>":   PN = "201"  !CDS_PN = "201";
"CB<4>":   PN = "47"  !CDS_PN = "47";
"CB<5>":   PN = "192"  !CDS_PN = "192";
"CB<6>":   PN = "54"  !CDS_PN = "54";
"CB<7>":   PN = "199"  !CDS_PN = "199";
"CK0N":   PN = "75"  !CDS_PN = "75";
"CK0P":   PN = "74"  !CDS_PN = "74";
"CK1N":   PN = "219"  !CDS_PN = "219";
"CK1P":   PN = "218"  !CDS_PN = "218";
"CKE<0>":   PN = "60"  !CDS_PN = "60";
"CKE<1>":   PN = "203"  !CDS_PN = "203";
"DQ<0>":   PN = "5"  !CDS_PN = "5";
"DQ<1>":   PN = "150"  !CDS_PN = "150";
"DQ<2>":   PN = "12"  !CDS_PN = "12";
"DQ<3>":   PN = "157"  !CDS_PN = "157";
"DQ<4>":   PN = "3"  !CDS_PN = "3";
"DQ<5>":   PN = "148"  !CDS_PN = "148";
"DQ<6>":   PN = "10"  !CDS_PN = "10";
"DQ<7>":   PN = "155"  !CDS_PN = "155";
"DQ<8>":   PN = "16"  !CDS_PN = "16";
"DQ<9>":   PN = "161"  !CDS_PN = "161";
"DQ<10>":   PN = "23"  !CDS_PN = "23";
"DQ<11>":   PN = "168"  !CDS_PN = "168";
"DQ<12>":   PN = "14"  !CDS_PN = "14";
"DQ<13>":   PN = "159"  !CDS_PN = "159";
"DQ<14>":   PN = "21"  !CDS_PN = "21";
"DQ<15>":   PN = "166"  !CDS_PN = "166";
"DQ<16>":   PN = "27"  !CDS_PN = "27";
"DQ<17>":   PN = "172"  !CDS_PN = "172";
"DQ<18>":   PN = "34"  !CDS_PN = "34";
"DQ<19>":   PN = "179"  !CDS_PN = "179";
"DQ<20>":   PN = "25"  !CDS_PN = "25";
"DQ<21>":   PN = "170"  !CDS_PN = "170";
"DQ<22>":   PN = "32"  !CDS_PN = "32";
"DQ<23>":   PN = "177"  !CDS_PN = "177";
"DQ<24>":   PN = "38"  !CDS_PN = "38";
"DQ<25>":   PN = "183"  !CDS_PN = "183";
"DQ<26>":   PN = "45"  !CDS_PN = "45";
"DQ<27>":   PN = "190"  !CDS_PN = "190";
"DQ<28>":   PN = "36"  !CDS_PN = "36";
"DQ<29>":   PN = "181"  !CDS_PN = "181";
"DQ<30>":   PN = "43"  !CDS_PN = "43";
"DQ<31>":   PN = "188"  !CDS_PN = "188";
"DQ<32>":   PN = "97"  !CDS_PN = "97";
"DQ<33>":   PN = "242"  !CDS_PN = "242";
"DQ<34>":   PN = "104"  !CDS_PN = "104";
"DQ<35>":   PN = "249"  !CDS_PN = "249";
"DQ<36>":   PN = "95"  !CDS_PN = "95";
"DQ<37>":   PN = "240"  !CDS_PN = "240";
"DQ<38>":   PN = "102"  !CDS_PN = "102";
"DQ<39>":   PN = "247"  !CDS_PN = "247";
"DQ<40>":   PN = "108"  !CDS_PN = "108";
"DQ<41>":   PN = "253"  !CDS_PN = "253";
"DQ<42>":   PN = "115"  !CDS_PN = "115";
"DQ<43>":   PN = "260"  !CDS_PN = "260";
"DQ<44>":   PN = "106"  !CDS_PN = "106";
"DQ<45>":   PN = "251"  !CDS_PN = "251";
"DQ<46>":   PN = "113"  !CDS_PN = "113";
"DQ<47>":   PN = "258"  !CDS_PN = "258";
"DQ<48>":   PN = "119"  !CDS_PN = "119";
"DQ<49>":   PN = "264"  !CDS_PN = "264";
"DQ<50>":   PN = "126"  !CDS_PN = "126";
"DQ<51>":   PN = "271"  !CDS_PN = "271";
"DQ<52>":   PN = "117"  !CDS_PN = "117";
"DQ<53>":   PN = "262"  !CDS_PN = "262";
"DQ<54>":   PN = "124"  !CDS_PN = "124";
"DQ<55>":   PN = "269"  !CDS_PN = "269";
"DQ<56>":   PN = "130"  !CDS_PN = "130";
"DQ<57>":   PN = "275"  !CDS_PN = "275";
"DQ<58>":   PN = "137"  !CDS_PN = "137";
"DQ<59>":   PN = "282"  !CDS_PN = "282";
"DQ<60>":   PN = "128"  !CDS_PN = "128";
"DQ<61>":   PN = "273"  !CDS_PN = "273";
"DQ<62>":   PN = "135"  !CDS_PN = "135";
"DQ<63>":   PN = "280"  !CDS_PN = "280";
"EVENT_N":   PN = "78"  !CDS_PN = "78";
"ODT<0>":   PN = "87"  !CDS_PN = "87";
"ODT<1>":   PN = "91"  !CDS_PN = "91";
"PAR":   PN = "222"  !CDS_PN = "222";
"RESET_N":   PN = "58"  !CDS_PN = "58";
"RFU<0>":   PN = "205"  !CDS_PN = "205";
"RFU<1>":   PN = "227"  !CDS_PN = "227";
"RFU<2>":   PN = "144"  !CDS_PN = "144";
"S0_N":   PN = "84"  !CDS_PN = "84";
"S1_N":   PN = "89"  !CDS_PN = "89";
"S2_N_C<0>":   PN = "93"  !CDS_PN = "93";
"S3_N_C<1>":   PN = "237"  !CDS_PN = "237";
"SA<0>":   PN = "139"  !CDS_PN = "139";
"SA<1>":   PN = "140"  !CDS_PN = "140";
"SA<2>":   PN = "238"  !CDS_PN = "238";
"SAVE_N_NC":   PN = "230"  !CDS_PN = "230";
"SCL":   PN = "141"  !CDS_PN = "141";
"SDA":   PN = "285"  !CDS_PN = "285";
"VDDSPD":   PN = "284"  !CDS_PN = "284";
"VREFCA":   PN = "146"  !CDS_PN = "146";
BODY = "SCONN288_H44441004","I169": #LOCATION = "J4B1" !CDS_LOCATION = "J4B1" #SEC = "4" !CDS_SEC = "4";
"12V<0>":   PN = "145"  !CDS_PN = "145";
"12V<1>":   PN = "1"  !CDS_PN = "1";
"VDD<0>":   PN = "236"  !CDS_PN = "236";
"VDD<1>":   PN = "233"  !CDS_PN = "233";
"VDD<2>":   PN = "231"  !CDS_PN = "231";
"VDD<3>":   PN = "229"  !CDS_PN = "229";
"VDD<4>":   PN = "226"  !CDS_PN = "226";
"VDD<5>":   PN = "223"  !CDS_PN = "223";
"VDD<6>":   PN = "220"  !CDS_PN = "220";
"VDD<7>":   PN = "217"  !CDS_PN = "217";
"VDD<8>":   PN = "215"  !CDS_PN = "215";
"VDD<9>":   PN = "212"  !CDS_PN = "212";
"VDD<10>":   PN = "209"  !CDS_PN = "209";
"VDD<11>":   PN = "206"  !CDS_PN = "206";
"VDD<12>":   PN = "204"  !CDS_PN = "204";
"VDD<13>":   PN = "92"  !CDS_PN = "92";
"VDD<14>":   PN = "90"  !CDS_PN = "90";
"VDD<15>":   PN = "88"  !CDS_PN = "88";
"VDD<16>":   PN = "85"  !CDS_PN = "85";
"VDD<17>":   PN = "83"  !CDS_PN = "83";
"VDD<18>":   PN = "80"  !CDS_PN = "80";
"VDD<19>":   PN = "76"  !CDS_PN = "76";
"VDD<20>":   PN = "73"  !CDS_PN = "73";
"VDD<21>":   PN = "70"  !CDS_PN = "70";
"VDD<22>":   PN = "67"  !CDS_PN = "67";
"VDD<23>":   PN = "64"  !CDS_PN = "64";
"VDD<24>":   PN = "61"  !CDS_PN = "61";
"VDD<25>":   PN = "59"  !CDS_PN = "59";
"VPP<0>":   PN = "287"  !CDS_PN = "287";
"VPP<1>":   PN = "286"  !CDS_PN = "286";
"VPP<2>":   PN = "288"  !CDS_PN = "288";
"VPP<3>":   PN = "143"  !CDS_PN = "143";
"VPP<4>":   PN = "142"  !CDS_PN = "142";
"VTT<0>":   PN = "221"  !CDS_PN = "221";
"VTT<1>":   PN = "77"  !CDS_PN = "77";
BODY = "CAP_A","I179": #LOCATION = "C4B12" !CDS_LOCATION = "C4B12" &SEC = "1" #&CDS_SEC = "1";
"A":   PN = "1"  !CDS_PN = "1";
"B":   PN = "2"  !CDS_PN = "2";
DRAWING = "@baseboard_fab2_lib.baseboard_fab2(sch_1):page50";
BODY = "SCONN288_H44441003","I44": #LOCATION = "J6M1" !CDS_LOCATION = "J6M1" #SEC = "3" !CDS_SEC = "3";
"VSS<0>":   PN = "283"  !CDS_PN = "283";
"VSS<1>":   PN = "281"  !CDS_PN = "281";
"VSS<2>":   PN = "279"  !CDS_PN = "279";
"VSS<3>":   PN = "276"  !CDS_PN = "276";
"VSS<4>":   PN = "274"  !CDS_PN = "274";
"VSS<5>":   PN = "272"  !CDS_PN = "272";
"VSS<6>":   PN = "270"  !CDS_PN = "270";
"VSS<7>":   PN = "268"  !CDS_PN = "268";
"VSS<8>":   PN = "265"  !CDS_PN = "265";
"VSS<9>":   PN = "263"  !CDS_PN = "263";
"VSS<10>":   PN = "261"  !CDS_PN = "261";
"VSS<11>":   PN = "259"  !CDS_PN = "259";
"VSS<12>":   PN = "257"  !CDS_PN = "257";
"VSS<13>":   PN = "254"  !CDS_PN = "254";
"VSS<14>":   PN = "252"  !CDS_PN = "252";
"VSS<15>":   PN = "250"  !CDS_PN = "250";
"VSS<16>":   PN = "248"  !CDS_PN = "248";
"VSS<17>":   PN = "246"  !CDS_PN = "246";
"VSS<18>":   PN = "243"  !CDS_PN = "243";
"VSS<19>":   PN = "241"  !CDS_PN = "241";
"VSS<20>":   PN = "239"  !CDS_PN = "239";
"VSS<21>":   PN = "202"  !CDS_PN = "202";
"VSS<22>":   PN = "200"  !CDS_PN = "200";
"VSS<23>":   PN = "198"  !CDS_PN = "198";
"VSS<24>":   PN = "195"  !CDS_PN = "195";
"VSS<25>":   PN = "193"  !CDS_PN = "193";
"VSS<26>":   PN = "191"  !CDS_PN = "191";
"VSS<27>":   PN = "189"  !CDS_PN = "189";
"VSS<28>":   PN = "187"  !CDS_PN = "187";
"VSS<29>":   PN = "184"  !CDS_PN = "184";
"VSS<30>":   PN = "182"  !CDS_PN = "182";
"VSS<31>":   PN = "180"  !CDS_PN = "180";
"VSS<32>":   PN = "178"  !CDS_PN = "178";
"VSS<33>":   PN = "176"  !CDS_PN = "176";
"VSS<34>":   PN = "173"  !CDS_PN = "173";
"VSS<35>":   PN = "171"  !CDS_PN = "171";
"VSS<36>":   PN = "169"  !CDS_PN = "169";
"VSS<37>":   PN = "167"  !CDS_PN = "167";
"VSS<38>":   PN = "165"  !CDS_PN = "165";
"VSS<39>":   PN = "162"  !CDS_PN = "162";
"VSS<40>":   PN = "160"  !CDS_PN = "160";
"VSS<41>":   PN = "158"  !CDS_PN = "158";
"VSS<42>":   PN = "156"  !CDS_PN = "156";
"VSS<43>":   PN = "154"  !CDS_PN = "154";
"VSS<44>":   PN = "151"  !CDS_PN = "151";
"VSS<45>":   PN = "149"  !CDS_PN = "149";
"VSS<46>":   PN = "147"  !CDS_PN = "147";
"VSS<47>":   PN = "138"  !CDS_PN = "138";
"VSS<48>":   PN = "136"  !CDS_PN = "136";
"VSS<49>":   PN = "134"  !CDS_PN = "134";
"VSS<50>":   PN = "131"  !CDS_PN = "131";
"VSS<51>":   PN = "129"  !CDS_PN = "129";
"VSS<52>":   PN = "127"  !CDS_PN = "127";
"VSS<53>":   PN = "125"  !CDS_PN = "125";
"VSS<54>":   PN = "123"  !CDS_PN = "123";
"VSS<55>":   PN = "120"  !CDS_PN = "120";
"VSS<56>":   PN = "118"  !CDS_PN = "118";
"VSS<57>":   PN = "116"  !CDS_PN = "116";
"VSS<58>":   PN = "114"  !CDS_PN = "114";
"VSS<59>":   PN = "112"  !CDS_PN = "112";
"VSS<60>":   PN = "109"  !CDS_PN = "109";
"VSS<61>":   PN = "107"  !CDS_PN = "107";
"VSS<62>":   PN = "105"  !CDS_PN = "105";
"VSS<63>":   PN = "103"  !CDS_PN = "103";
"VSS<64>":   PN = "101"  !CDS_PN = "101";
"VSS<65>":   PN = "98"  !CDS_PN = "98";
"VSS<66>":   PN = "96"  !CDS_PN = "96";
"VSS<67>":   PN = "94"  !CDS_PN = "94";
"VSS<68>":   PN = "57"  !CDS_PN = "57";
"VSS<69>":   PN = "55"  !CDS_PN = "55";
"VSS<70>":   PN = "53"  !CDS_PN = "53";
"VSS<71>":   PN = "50"  !CDS_PN = "50";
"VSS<72>":   PN = "48"  !CDS_PN = "48";
"VSS<73>":   PN = "46"  !CDS_PN = "46";
"VSS<74>":   PN = "44"  !CDS_PN = "44";
"VSS<75>":   PN = "42"  !CDS_PN = "42";
"VSS<76>":   PN = "39"  !CDS_PN = "39";
"VSS<77>":   PN = "37"  !CDS_PN = "37";
"VSS<78>":   PN = "35"  !CDS_PN = "35";
"VSS<79>":   PN = "33"  !CDS_PN = "33";
"VSS<80>":   PN = "31"  !CDS_PN = "31";
"VSS<81>":   PN = "28"  !CDS_PN = "28";
"VSS<82>":   PN = "26"  !CDS_PN = "26";
"VSS<83>":   PN = "24"  !CDS_PN = "24";
"VSS<84>":   PN = "22"  !CDS_PN = "22";
"VSS<85>":   PN = "20"  !CDS_PN = "20";
"VSS<86>":   PN = "17"  !CDS_PN = "17";
"VSS<87>":   PN = "15"  !CDS_PN = "15";
"VSS<88>":   PN = "13"  !CDS_PN = "13";
"VSS<89>":   PN = "11"  !CDS_PN = "11";
"VSS<90>":   PN = "9"  !CDS_PN = "9";
"VSS<91>":   PN = "6"  !CDS_PN = "6";
"VSS<92>":   PN = "4"  !CDS_PN = "4";
"VSS<93>":   PN = "2"  !CDS_PN = "2";
BODY = "SCONN288_H44441003","I46": #LOCATION = "J6M1" !CDS_LOCATION = "J6M1" #SEC = "2" !CDS_SEC = "2";
"DQS0N":   PN = "152"  !CDS_PN = "152";
"DQS0P":   PN = "153"  !CDS_PN = "153";
"DQS1N":   PN = "163"  !CDS_PN = "163";
"DQS1P":   PN = "164"  !CDS_PN = "164";
"DQS2N":   PN = "174"  !CDS_PN = "174";
"DQS2P":   PN = "175"  !CDS_PN = "175";
"DQS3N":   PN = "185"  !CDS_PN = "185";
"DQS3P":   PN = "186"  !CDS_PN = "186";
"DQS4N":   PN = "244"  !CDS_PN = "244";
"DQS4P":   PN = "245"  !CDS_PN = "245";
"DQS5N":   PN = "255"  !CDS_PN = "255";
"DQS5P":   PN = "256"  !CDS_PN = "256";
"DQS6N":   PN = "266"  !CDS_PN = "266";
"DQS6P":   PN = "267"  !CDS_PN = "267";
"DQS7N":   PN = "277"  !CDS_PN = "277";
"DQS7P":   PN = "278"  !CDS_PN = "278";
"DQS8N":   PN = "196"  !CDS_PN = "196";
"DQS8P":   PN = "197"  !CDS_PN = "197";
"DQS9N":   PN = "8"  !CDS_PN = "8";
"DQS9P":   PN = "7"  !CDS_PN = "7";
"DQS10N":   PN = "19"  !CDS_PN = "19";
"DQS10P":   PN = "18"  !CDS_PN = "18";
"DQS11N":   PN = "30"  !CDS_PN = "30";
"DQS11P":   PN = "29"  !CDS_PN = "29";
"DQS12N":   PN = "41"  !CDS_PN = "41";
"DQS12P":   PN = "40"  !CDS_PN = "40";
"DQS13N":   PN = "100"  !CDS_PN = "100";
"DQS13P":   PN = "99"  !CDS_PN = "99";
"DQS14N":   PN = "111"  !CDS_PN = "111";
"DQS14P":   PN = "110"  !CDS_PN = "110";
"DQS15N":   PN = "122"  !CDS_PN = "122";
"DQS15P":   PN = "121"  !CDS_PN = "121";
"DQS16N":   PN = "133"  !CDS_PN = "133";
"DQS16P":   PN = "132"  !CDS_PN = "132";
"DQS17N":   PN = "52"  !CDS_PN = "52";
"DQS17P":   PN = "51"  !CDS_PN = "51";
BODY = "SCONN288_H44441003","I50": #LOCATION = "J6M1" !CDS_LOCATION = "J6M1" #SEC = "4" !CDS_SEC = "4";
"12V<0>":   PN = "145"  !CDS_PN = "145";
"12V<1>":   PN = "1"  !CDS_PN = "1";
"VDD<0>":   PN = "236"  !CDS_PN = "236";
"VDD<1>":   PN = "233"  !CDS_PN = "233";
"VDD<2>":   PN = "231"  !CDS_PN = "231";
"VDD<3>":   PN = "229"  !CDS_PN = "229";
"VDD<4>":   PN = "226"  !CDS_PN = "226";
"VDD<5>":   PN = "223"  !CDS_PN = "223";
"VDD<6>":   PN = "220"  !CDS_PN = "220";
"VDD<7>":   PN = "217"  !CDS_PN = "217";
"VDD<8>":   PN = "215"  !CDS_PN = "215";
"VDD<9>":   PN = "212"  !CDS_PN = "212";
"VDD<10>":   PN = "209"  !CDS_PN = "209";
"VDD<11>":   PN = "206"  !CDS_PN = "206";
"VDD<12>":   PN = "204"  !CDS_PN = "204";
"VDD<13>":   PN = "92"  !CDS_PN = "92";
"VDD<14>":   PN = "90"  !CDS_PN = "90";
"VDD<15>":   PN = "88"  !CDS_PN = "88";
"VDD<16>":   PN = "85"  !CDS_PN = "85";
"VDD<17>":   PN = "83"  !CDS_PN = "83";
"VDD<18>":   PN = "80"  !CDS_PN = "80";
"VDD<19>":   PN = "76"  !CDS_PN = "76";
"VDD<20>":   PN = "73"  !CDS_PN = "73";
"VDD<21>":   PN = "70"  !CDS_PN = "70";
"VDD<22>":   PN = "67"  !CDS_PN = "67";
"VDD<23>":   PN = "64"  !CDS_PN = "64";
"VDD<24>":   PN = "61"  !CDS_PN = "61";
"VDD<25>":   PN = "59"  !CDS_PN = "59";
"VPP<0>":   PN = "287"  !CDS_PN = "287";
"VPP<1>":   PN = "286"  !CDS_PN = "286";
"VPP<2>":   PN = "288"  !CDS_PN = "288";
"VPP<3>":   PN = "143"  !CDS_PN = "143";
"VPP<4>":   PN = "142"  !CDS_PN = "142";
"VTT<0>":   PN = "221"  !CDS_PN = "221";
"VTT<1>":   PN = "77"  !CDS_PN = "77";
BODY = "SCONN288_H44441003","I158": #LOCATION = "J6M1" !CDS_LOCATION = "J6M1" #SEC = "1" !CDS_SEC = "1";
"A0":   PN = "79"  !CDS_PN = "79";
"A1":   PN = "72"  !CDS_PN = "72";
"A2":   PN = "216"  !CDS_PN = "216";
"A3":   PN = "71"  !CDS_PN = "71";
"A4":   PN = "214"  !CDS_PN = "214";
"A5":   PN = "213"  !CDS_PN = "213";
"A6":   PN = "69"  !CDS_PN = "69";
"A7":   PN = "211"  !CDS_PN = "211";
"A8":   PN = "68"  !CDS_PN = "68";
"A9":   PN = "66"  !CDS_PN = "66";
"A10":   PN = "225"  !CDS_PN = "225";
"A11":   PN = "210"  !CDS_PN = "210";
"A12":   PN = "65"  !CDS_PN = "65";
"A13":   PN = "232"  !CDS_PN = "232";
"A14_WE_N":   PN = "228"  !CDS_PN = "228";
"A15_CAS_N":   PN = "86"  !CDS_PN = "86";
"A16_RAS_N":   PN = "82"  !CDS_PN = "82";
"A17":   PN = "234"  !CDS_PN = "234";
"ACT_N":   PN = "62"  !CDS_PN = "62";
"ALERT_N":   PN = "208"  !CDS_PN = "208";
"BA<0>":   PN = "81"  !CDS_PN = "81";
"BA<1>":   PN = "224"  !CDS_PN = "224";
"BG<0>":   PN = "63"  !CDS_PN = "63";
"BG<1>":   PN = "207"  !CDS_PN = "207";
"C<2>":   PN = "235"  !CDS_PN = "235";
"CB<0>":   PN = "49"  !CDS_PN = "49";
"CB<1>":   PN = "194"  !CDS_PN = "194";
"CB<2>":   PN = "56"  !CDS_PN = "56";
"CB<3>":   PN = "201"  !CDS_PN = "201";
"CB<4>":   PN = "47"  !CDS_PN = "47";
"CB<5>":   PN = "192"  !CDS_PN = "192";
"CB<6>":   PN = "54"  !CDS_PN = "54";
"CB<7>":   PN = "199"  !CDS_PN = "199";
"CK0N":   PN = "75"  !CDS_PN = "75";
"CK0P":   PN = "74"  !CDS_PN = "74";
"CK1N":   PN = "219"  !CDS_PN = "219";
"CK1P":   PN = "218"  !CDS_PN = "218";
"CKE<0>":   PN = "60"  !CDS_PN = "60";
"CKE<1>":   PN = "203"  !CDS_PN = "203";
"DQ<0>":   PN = "5"  !CDS_PN = "5";
"DQ<1>":   PN = "150"  !CDS_PN = "150";
"DQ<2>":   PN = "12"  !CDS_PN = "12";
"DQ<3>":   PN = "157"  !CDS_PN = "157";
"DQ<4>":   PN = "3"  !CDS_PN = "3";
"DQ<5>":   PN = "148"  !CDS_PN = "148";
"DQ<6>":   PN = "10"  !CDS_PN = "10";
"DQ<7>":   PN = "155"  !CDS_PN = "155";
"DQ<8>":   PN = "16"  !CDS_PN = "16";
"DQ<9>":   PN = "161"  !CDS_PN = "161";
"DQ<10>":   PN = "23"  !CDS_PN = "23";
"DQ<11>":   PN = "168"  !CDS_PN = "168";
"DQ<12>":   PN = "14"  !CDS_PN = "14";
"DQ<13>":   PN = "159"  !CDS_PN = "159";
"DQ<14>":   PN = "21"  !CDS_PN = "21";
"DQ<15>":   PN = "166"  !CDS_PN = "166";
"DQ<16>":   PN = "27"  !CDS_PN = "27";
"DQ<17>":   PN = "172"  !CDS_PN = "172";
"DQ<18>":   PN = "34"  !CDS_PN = "34";
"DQ<19>":   PN = "179"  !CDS_PN = "179";
"DQ<20>":   PN = "25"  !CDS_PN = "25";
"DQ<21>":   PN = "170"  !CDS_PN = "170";
"DQ<22>":   PN = "32"  !CDS_PN = "32";
"DQ<23>":   PN = "177"  !CDS_PN = "177";
"DQ<24>":   PN = "38"  !CDS_PN = "38";
"DQ<25>":   PN = "183"  !CDS_PN = "183";
"DQ<26>":   PN = "45"  !CDS_PN = "45";
"DQ<27>":   PN = "190"  !CDS_PN = "190";
"DQ<28>":   PN = "36"  !CDS_PN = "36";
"DQ<29>":   PN = "181"  !CDS_PN = "181";
"DQ<30>":   PN = "43"  !CDS_PN = "43";
"DQ<31>":   PN = "188"  !CDS_PN = "188";
"DQ<32>":   PN = "97"  !CDS_PN = "97";
"DQ<33>":   PN = "242"  !CDS_PN = "242";
"DQ<34>":   PN = "104"  !CDS_PN = "104";
"DQ<35>":   PN = "249"  !CDS_PN = "249";
"DQ<36>":   PN = "95"  !CDS_PN = "95";
"DQ<37>":   PN = "240"  !CDS_PN = "240";
"DQ<38>":   PN = "102"  !CDS_PN = "102";
"DQ<39>":   PN = "247"  !CDS_PN = "247";
"DQ<40>":   PN = "108"  !CDS_PN = "108";
"DQ<41>":   PN = "253"  !CDS_PN = "253";
"DQ<42>":   PN = "115"  !CDS_PN = "115";
"DQ<43>":   PN = "260"  !CDS_PN = "260";
"DQ<44>":   PN = "106"  !CDS_PN = "106";
"DQ<45>":   PN = "251"  !CDS_PN = "251";
"DQ<46>":   PN = "113"  !CDS_PN = "113";
"DQ<47>":   PN = "258"  !CDS_PN = "258";
"DQ<48>":   PN = "119"  !CDS_PN = "119";
"DQ<49>":   PN = "264"  !CDS_PN = "264";
"DQ<50>":   PN = "126"  !CDS_PN = "126";
"DQ<51>":   PN = "271"  !CDS_PN = "271";
"DQ<52>":   PN = "117"  !CDS_PN = "117";
"DQ<53>":   PN = "262"  !CDS_PN = "262";
"DQ<54>":   PN = "124"  !CDS_PN = "124";
"DQ<55>":   PN = "269"  !CDS_PN = "269";
"DQ<56>":   PN = "130"  !CDS_PN = "130";
"DQ<57>":   PN = "275"  !CDS_PN = "275";
"DQ<58>":   PN = "137"  !CDS_PN = "137";
"DQ<59>":   PN = "282"  !CDS_PN = "282";
"DQ<60>":   PN = "128"  !CDS_PN = "128";
"DQ<61>":   PN = "273"  !CDS_PN = "273";
"DQ<62>":   PN = "135"  !CDS_PN = "135";
"DQ<63>":   PN = "280"  !CDS_PN = "280";
"EVENT_N":   PN = "78"  !CDS_PN = "78";
"ODT<0>":   PN = "87"  !CDS_PN = "87";
"ODT<1>":   PN = "91"  !CDS_PN = "91";
"PAR":   PN = "222"  !CDS_PN = "222";
"RESET_N":   PN = "58"  !CDS_PN = "58";
"RFU<0>":   PN = "205"  !CDS_PN = "205";
"RFU<1>":   PN = "227"  !CDS_PN = "227";
"RFU<2>":   PN = "144"  !CDS_PN = "144";
"S0_N":   PN = "84"  !CDS_PN = "84";
"S1_N":   PN = "89"  !CDS_PN = "89";
"S2_N_C<0>":   PN = "93"  !CDS_PN = "93";
"S3_N_C<1>":   PN = "237"  !CDS_PN = "237";
"SA<0>":   PN = "139"  !CDS_PN = "139";
"SA<1>":   PN = "140"  !CDS_PN = "140";
"SA<2>":   PN = "238"  !CDS_PN = "238";
"SAVE_N_NC":   PN = "230"  !CDS_PN = "230";
"SCL":   PN = "141"  !CDS_PN = "141";
"SDA":   PN = "285"  !CDS_PN = "285";
"VDDSPD":   PN = "284"  !CDS_PN = "284";
"VREFCA":   PN = "146"  !CDS_PN = "146";
BODY = "CAP_A","I177": #LOCATION = "C6M1" !CDS_LOCATION = "C6M1" &SEC = "1" #&CDS_SEC = "1";
"A":   PN = "1"  !CDS_PN = "1";
"B":   PN = "2"  !CDS_PN = "2";
DRAWING = "@baseboard_fab2_lib.baseboard_fab2(sch_1):page51";
BODY = "SCONN288_H44441004","I43": #LOCATION = "J4A2" !CDS_LOCATION = "J4A2" #SEC = "3" !CDS_SEC = "3";
"VSS<0>":   PN = "283"  !CDS_PN = "283";
"VSS<1>":   PN = "281"  !CDS_PN = "281";
"VSS<2>":   PN = "279"  !CDS_PN = "279";
"VSS<3>":   PN = "276"  !CDS_PN = "276";
"VSS<4>":   PN = "274"  !CDS_PN = "274";
"VSS<5>":   PN = "272"  !CDS_PN = "272";
"VSS<6>":   PN = "270"  !CDS_PN = "270";
"VSS<7>":   PN = "268"  !CDS_PN = "268";
"VSS<8>":   PN = "265"  !CDS_PN = "265";
"VSS<9>":   PN = "263"  !CDS_PN = "263";
"VSS<10>":   PN = "261"  !CDS_PN = "261";
"VSS<11>":   PN = "259"  !CDS_PN = "259";
"VSS<12>":   PN = "257"  !CDS_PN = "257";
"VSS<13>":   PN = "254"  !CDS_PN = "254";
"VSS<14>":   PN = "252"  !CDS_PN = "252";
"VSS<15>":   PN = "250"  !CDS_PN = "250";
"VSS<16>":   PN = "248"  !CDS_PN = "248";
"VSS<17>":   PN = "246"  !CDS_PN = "246";
"VSS<18>":   PN = "243"  !CDS_PN = "243";
"VSS<19>":   PN = "241"  !CDS_PN = "241";
"VSS<20>":   PN = "239"  !CDS_PN = "239";
"VSS<21>":   PN = "202"  !CDS_PN = "202";
"VSS<22>":   PN = "200"  !CDS_PN = "200";
"VSS<23>":   PN = "198"  !CDS_PN = "198";
"VSS<24>":   PN = "195"  !CDS_PN = "195";
"VSS<25>":   PN = "193"  !CDS_PN = "193";
"VSS<26>":   PN = "191"  !CDS_PN = "191";
"VSS<27>":   PN = "189"  !CDS_PN = "189";
"VSS<28>":   PN = "187"  !CDS_PN = "187";
"VSS<29>":   PN = "184"  !CDS_PN = "184";
"VSS<30>":   PN = "182"  !CDS_PN = "182";
"VSS<31>":   PN = "180"  !CDS_PN = "180";
"VSS<32>":   PN = "178"  !CDS_PN = "178";
"VSS<33>":   PN = "176"  !CDS_PN = "176";
"VSS<34>":   PN = "173"  !CDS_PN = "173";
"VSS<35>":   PN = "171"  !CDS_PN = "171";
"VSS<36>":   PN = "169"  !CDS_PN = "169";
"VSS<37>":   PN = "167"  !CDS_PN = "167";
"VSS<38>":   PN = "165"  !CDS_PN = "165";
"VSS<39>":   PN = "162"  !CDS_PN = "162";
"VSS<40>":   PN = "160"  !CDS_PN = "160";
"VSS<41>":   PN = "158"  !CDS_PN = "158";
"VSS<42>":   PN = "156"  !CDS_PN = "156";
"VSS<43>":   PN = "154"  !CDS_PN = "154";
"VSS<44>":   PN = "151"  !CDS_PN = "151";
"VSS<45>":   PN = "149"  !CDS_PN = "149";
"VSS<46>":   PN = "147"  !CDS_PN = "147";
"VSS<47>":   PN = "138"  !CDS_PN = "138";
"VSS<48>":   PN = "136"  !CDS_PN = "136";
"VSS<49>":   PN = "134"  !CDS_PN = "134";
"VSS<50>":   PN = "131"  !CDS_PN = "131";
"VSS<51>":   PN = "129"  !CDS_PN = "129";
"VSS<52>":   PN = "127"  !CDS_PN = "127";
"VSS<53>":   PN = "125"  !CDS_PN = "125";
"VSS<54>":   PN = "123"  !CDS_PN = "123";
"VSS<55>":   PN = "120"  !CDS_PN = "120";
"VSS<56>":   PN = "118"  !CDS_PN = "118";
"VSS<57>":   PN = "116"  !CDS_PN = "116";
"VSS<58>":   PN = "114"  !CDS_PN = "114";
"VSS<59>":   PN = "112"  !CDS_PN = "112";
"VSS<60>":   PN = "109"  !CDS_PN = "109";
"VSS<61>":   PN = "107"  !CDS_PN = "107";
"VSS<62>":   PN = "105"  !CDS_PN = "105";
"VSS<63>":   PN = "103"  !CDS_PN = "103";
"VSS<64>":   PN = "101"  !CDS_PN = "101";
"VSS<65>":   PN = "98"  !CDS_PN = "98";
"VSS<66>":   PN = "96"  !CDS_PN = "96";
"VSS<67>":   PN = "94"  !CDS_PN = "94";
"VSS<68>":   PN = "57"  !CDS_PN = "57";
"VSS<69>":   PN = "55"  !CDS_PN = "55";
"VSS<70>":   PN = "53"  !CDS_PN = "53";
"VSS<71>":   PN = "50"  !CDS_PN = "50";
"VSS<72>":   PN = "48"  !CDS_PN = "48";
"VSS<73>":   PN = "46"  !CDS_PN = "46";
"VSS<74>":   PN = "44"  !CDS_PN = "44";
"VSS<75>":   PN = "42"  !CDS_PN = "42";
"VSS<76>":   PN = "39"  !CDS_PN = "39";
"VSS<77>":   PN = "37"  !CDS_PN = "37";
"VSS<78>":   PN = "35"  !CDS_PN = "35";
"VSS<79>":   PN = "33"  !CDS_PN = "33";
"VSS<80>":   PN = "31"  !CDS_PN = "31";
"VSS<81>":   PN = "28"  !CDS_PN = "28";
"VSS<82>":   PN = "26"  !CDS_PN = "26";
"VSS<83>":   PN = "24"  !CDS_PN = "24";
"VSS<84>":   PN = "22"  !CDS_PN = "22";
"VSS<85>":   PN = "20"  !CDS_PN = "20";
"VSS<86>":   PN = "17"  !CDS_PN = "17";
"VSS<87>":   PN = "15"  !CDS_PN = "15";
"VSS<88>":   PN = "13"  !CDS_PN = "13";
"VSS<89>":   PN = "11"  !CDS_PN = "11";
"VSS<90>":   PN = "9"  !CDS_PN = "9";
"VSS<91>":   PN = "6"  !CDS_PN = "6";
"VSS<92>":   PN = "4"  !CDS_PN = "4";
"VSS<93>":   PN = "2"  !CDS_PN = "2";
BODY = "SCONN288_H44441004","I66": #LOCATION = "J4A2" !CDS_LOCATION = "J4A2" #SEC = "2" !CDS_SEC = "2";
"DQS0N":   PN = "152"  !CDS_PN = "152";
"DQS0P":   PN = "153"  !CDS_PN = "153";
"DQS1N":   PN = "163"  !CDS_PN = "163";
"DQS1P":   PN = "164"  !CDS_PN = "164";
"DQS2N":   PN = "174"  !CDS_PN = "174";
"DQS2P":   PN = "175"  !CDS_PN = "175";
"DQS3N":   PN = "185"  !CDS_PN = "185";
"DQS3P":   PN = "186"  !CDS_PN = "186";
"DQS4N":   PN = "244"  !CDS_PN = "244";
"DQS4P":   PN = "245"  !CDS_PN = "245";
"DQS5N":   PN = "255"  !CDS_PN = "255";
"DQS5P":   PN = "256"  !CDS_PN = "256";
"DQS6N":   PN = "266"  !CDS_PN = "266";
"DQS6P":   PN = "267"  !CDS_PN = "267";
"DQS7N":   PN = "277"  !CDS_PN = "277";
"DQS7P":   PN = "278"  !CDS_PN = "278";
"DQS8N":   PN = "196"  !CDS_PN = "196";
"DQS8P":   PN = "197"  !CDS_PN = "197";
"DQS9N":   PN = "8"  !CDS_PN = "8";
"DQS9P":   PN = "7"  !CDS_PN = "7";
"DQS10N":   PN = "19"  !CDS_PN = "19";
"DQS10P":   PN = "18"  !CDS_PN = "18";
"DQS11N":   PN = "30"  !CDS_PN = "30";
"DQS11P":   PN = "29"  !CDS_PN = "29";
"DQS12N":   PN = "41"  !CDS_PN = "41";
"DQS12P":   PN = "40"  !CDS_PN = "40";
"DQS13N":   PN = "100"  !CDS_PN = "100";
"DQS13P":   PN = "99"  !CDS_PN = "99";
"DQS14N":   PN = "111"  !CDS_PN = "111";
"DQS14P":   PN = "110"  !CDS_PN = "110";
"DQS15N":   PN = "122"  !CDS_PN = "122";
"DQS15P":   PN = "121"  !CDS_PN = "121";
"DQS16N":   PN = "133"  !CDS_PN = "133";
"DQS16P":   PN = "132"  !CDS_PN = "132";
"DQS17N":   PN = "52"  !CDS_PN = "52";
"DQS17P":   PN = "51"  !CDS_PN = "51";
BODY = "SCONN288_H44441004","I111": #LOCATION = "J4A2" !CDS_LOCATION = "J4A2" #SEC = "1" !CDS_SEC = "1";
"A0":   PN = "79"  !CDS_PN = "79";
"A1":   PN = "72"  !CDS_PN = "72";
"A2":   PN = "216"  !CDS_PN = "216";
"A3":   PN = "71"  !CDS_PN = "71";
"A4":   PN = "214"  !CDS_PN = "214";
"A5":   PN = "213"  !CDS_PN = "213";
"A6":   PN = "69"  !CDS_PN = "69";
"A7":   PN = "211"  !CDS_PN = "211";
"A8":   PN = "68"  !CDS_PN = "68";
"A9":   PN = "66"  !CDS_PN = "66";
"A10":   PN = "225"  !CDS_PN = "225";
"A11":   PN = "210"  !CDS_PN = "210";
"A12":   PN = "65"  !CDS_PN = "65";
"A13":   PN = "232"  !CDS_PN = "232";
"A14_WE_N":   PN = "228"  !CDS_PN = "228";
"A15_CAS_N":   PN = "86"  !CDS_PN = "86";
"A16_RAS_N":   PN = "82"  !CDS_PN = "82";
"A17":   PN = "234"  !CDS_PN = "234";
"ACT_N":   PN = "62"  !CDS_PN = "62";
"ALERT_N":   PN = "208"  !CDS_PN = "208";
"BA<0>":   PN = "81"  !CDS_PN = "81";
"BA<1>":   PN = "224"  !CDS_PN = "224";
"BG<0>":   PN = "63"  !CDS_PN = "63";
"BG<1>":   PN = "207"  !CDS_PN = "207";
"C<2>":   PN = "235"  !CDS_PN = "235";
"CB<0>":   PN = "49"  !CDS_PN = "49";
"CB<1>":   PN = "194"  !CDS_PN = "194";
"CB<2>":   PN = "56"  !CDS_PN = "56";
"CB<3>":   PN = "201"  !CDS_PN = "201";
"CB<4>":   PN = "47"  !CDS_PN = "47";
"CB<5>":   PN = "192"  !CDS_PN = "192";
"CB<6>":   PN = "54"  !CDS_PN = "54";
"CB<7>":   PN = "199"  !CDS_PN = "199";
"CK0N":   PN = "75"  !CDS_PN = "75";
"CK0P":   PN = "74"  !CDS_PN = "74";
"CK1N":   PN = "219"  !CDS_PN = "219";
"CK1P":   PN = "218"  !CDS_PN = "218";
"CKE<0>":   PN = "60"  !CDS_PN = "60";
"CKE<1>":   PN = "203"  !CDS_PN = "203";
"DQ<0>":   PN = "5"  !CDS_PN = "5";
"DQ<1>":   PN = "150"  !CDS_PN = "150";
"DQ<2>":   PN = "12"  !CDS_PN = "12";
"DQ<3>":   PN = "157"  !CDS_PN = "157";
"DQ<4>":   PN = "3"  !CDS_PN = "3";
"DQ<5>":   PN = "148"  !CDS_PN = "148";
"DQ<6>":   PN = "10"  !CDS_PN = "10";
"DQ<7>":   PN = "155"  !CDS_PN = "155";
"DQ<8>":   PN = "16"  !CDS_PN = "16";
"DQ<9>":   PN = "161"  !CDS_PN = "161";
"DQ<10>":   PN = "23"  !CDS_PN = "23";
"DQ<11>":   PN = "168"  !CDS_PN = "168";
"DQ<12>":   PN = "14"  !CDS_PN = "14";
"DQ<13>":   PN = "159"  !CDS_PN = "159";
"DQ<14>":   PN = "21"  !CDS_PN = "21";
"DQ<15>":   PN = "166"  !CDS_PN = "166";
"DQ<16>":   PN = "27"  !CDS_PN = "27";
"DQ<17>":   PN = "172"  !CDS_PN = "172";
"DQ<18>":   PN = "34"  !CDS_PN = "34";
"DQ<19>":   PN = "179"  !CDS_PN = "179";
"DQ<20>":   PN = "25"  !CDS_PN = "25";
"DQ<21>":   PN = "170"  !CDS_PN = "170";
"DQ<22>":   PN = "32"  !CDS_PN = "32";
"DQ<23>":   PN = "177"  !CDS_PN = "177";
"DQ<24>":   PN = "38"  !CDS_PN = "38";
"DQ<25>":   PN = "183"  !CDS_PN = "183";
"DQ<26>":   PN = "45"  !CDS_PN = "45";
"DQ<27>":   PN = "190"  !CDS_PN = "190";
"DQ<28>":   PN = "36"  !CDS_PN = "36";
"DQ<29>":   PN = "181"  !CDS_PN = "181";
"DQ<30>":   PN = "43"  !CDS_PN = "43";
"DQ<31>":   PN = "188"  !CDS_PN = "188";
"DQ<32>":   PN = "97"  !CDS_PN = "97";
"DQ<33>":   PN = "242"  !CDS_PN = "242";
"DQ<34>":   PN = "104"  !CDS_PN = "104";
"DQ<35>":   PN = "249"  !CDS_PN = "249";
"DQ<36>":   PN = "95"  !CDS_PN = "95";
"DQ<37>":   PN = "240"  !CDS_PN = "240";
"DQ<38>":   PN = "102"  !CDS_PN = "102";
"DQ<39>":   PN = "247"  !CDS_PN = "247";
"DQ<40>":   PN = "108"  !CDS_PN = "108";
"DQ<41>":   PN = "253"  !CDS_PN = "253";
"DQ<42>":   PN = "115"  !CDS_PN = "115";
"DQ<43>":   PN = "260"  !CDS_PN = "260";
"DQ<44>":   PN = "106"  !CDS_PN = "106";
"DQ<45>":   PN = "251"  !CDS_PN = "251";
"DQ<46>":   PN = "113"  !CDS_PN = "113";
"DQ<47>":   PN = "258"  !CDS_PN = "258";
"DQ<48>":   PN = "119"  !CDS_PN = "119";
"DQ<49>":   PN = "264"  !CDS_PN = "264";
"DQ<50>":   PN = "126"  !CDS_PN = "126";
"DQ<51>":   PN = "271"  !CDS_PN = "271";
"DQ<52>":   PN = "117"  !CDS_PN = "117";
"DQ<53>":   PN = "262"  !CDS_PN = "262";
"DQ<54>":   PN = "124"  !CDS_PN = "124";
"DQ<55>":   PN = "269"  !CDS_PN = "269";
"DQ<56>":   PN = "130"  !CDS_PN = "130";
"DQ<57>":   PN = "275"  !CDS_PN = "275";
"DQ<58>":   PN = "137"  !CDS_PN = "137";
"DQ<59>":   PN = "282"  !CDS_PN = "282";
"DQ<60>":   PN = "128"  !CDS_PN = "128";
"DQ<61>":   PN = "273"  !CDS_PN = "273";
"DQ<62>":   PN = "135"  !CDS_PN = "135";
"DQ<63>":   PN = "280"  !CDS_PN = "280";
"EVENT_N":   PN = "78"  !CDS_PN = "78";
"ODT<0>":   PN = "87"  !CDS_PN = "87";
"ODT<1>":   PN = "91"  !CDS_PN = "91";
"PAR":   PN = "222"  !CDS_PN = "222";
"RESET_N":   PN = "58"  !CDS_PN = "58";
"RFU<0>":   PN = "205"  !CDS_PN = "205";
"RFU<1>":   PN = "227"  !CDS_PN = "227";
"RFU<2>":   PN = "144"  !CDS_PN = "144";
"S0_N":   PN = "84"  !CDS_PN = "84";
"S1_N":   PN = "89"  !CDS_PN = "89";
"S2_N_C<0>":   PN = "93"  !CDS_PN = "93";
"S3_N_C<1>":   PN = "237"  !CDS_PN = "237";
"SA<0>":   PN = "139"  !CDS_PN = "139";
"SA<1>":   PN = "140"  !CDS_PN = "140";
"SA<2>":   PN = "238"  !CDS_PN = "238";
"SAVE_N_NC":   PN = "230"  !CDS_PN = "230";
"SCL":   PN = "141"  !CDS_PN = "141";
"SDA":   PN = "285"  !CDS_PN = "285";
"VDDSPD":   PN = "284"  !CDS_PN = "284";
"VREFCA":   PN = "146"  !CDS_PN = "146";
BODY = "SCONN288_H44441004","I167": #LOCATION = "J4A2" !CDS_LOCATION = "J4A2" #SEC = "4" !CDS_SEC = "4";
"12V<0>":   PN = "145"  !CDS_PN = "145";
"12V<1>":   PN = "1"  !CDS_PN = "1";
"VDD<0>":   PN = "236"  !CDS_PN = "236";
"VDD<1>":   PN = "233"  !CDS_PN = "233";
"VDD<2>":   PN = "231"  !CDS_PN = "231";
"VDD<3>":   PN = "229"  !CDS_PN = "229";
"VDD<4>":   PN = "226"  !CDS_PN = "226";
"VDD<5>":   PN = "223"  !CDS_PN = "223";
"VDD<6>":   PN = "220"  !CDS_PN = "220";
"VDD<7>":   PN = "217"  !CDS_PN = "217";
"VDD<8>":   PN = "215"  !CDS_PN = "215";
"VDD<9>":   PN = "212"  !CDS_PN = "212";
"VDD<10>":   PN = "209"  !CDS_PN = "209";
"VDD<11>":   PN = "206"  !CDS_PN = "206";
"VDD<12>":   PN = "204"  !CDS_PN = "204";
"VDD<13>":   PN = "92"  !CDS_PN = "92";
"VDD<14>":   PN = "90"  !CDS_PN = "90";
"VDD<15>":   PN = "88"  !CDS_PN = "88";
"VDD<16>":   PN = "85"  !CDS_PN = "85";
"VDD<17>":   PN = "83"  !CDS_PN = "83";
"VDD<18>":   PN = "80"  !CDS_PN = "80";
"VDD<19>":   PN = "76"  !CDS_PN = "76";
"VDD<20>":   PN = "73"  !CDS_PN = "73";
"VDD<21>":   PN = "70"  !CDS_PN = "70";
"VDD<22>":   PN = "67"  !CDS_PN = "67";
"VDD<23>":   PN = "64"  !CDS_PN = "64";
"VDD<24>":   PN = "61"  !CDS_PN = "61";
"VDD<25>":   PN = "59"  !CDS_PN = "59";
"VPP<0>":   PN = "287"  !CDS_PN = "287";
"VPP<1>":   PN = "286"  !CDS_PN = "286";
"VPP<2>":   PN = "288"  !CDS_PN = "288";
"VPP<3>":   PN = "143"  !CDS_PN = "143";
"VPP<4>":   PN = "142"  !CDS_PN = "142";
"VTT<0>":   PN = "221"  !CDS_PN = "221";
"VTT<1>":   PN = "77"  !CDS_PN = "77";
BODY = "CAP_A","I175": #LOCATION = "C6L6" !CDS_LOCATION = "C6L6" &SEC = "1" #&CDS_SEC = "1";
"A":   PN = "1"  !CDS_PN = "1";
"B":   PN = "2"  !CDS_PN = "2";
DRAWING = "@baseboard_fab2_lib.baseboard_fab2(sch_1):page52";
BODY = "CAP_A","I3": #LOCATION = "C4A18" !CDS_LOCATION = "C4A18" &SEC = "1" #&CDS_SEC = "1";
"A":   PN = "1"  !CDS_PN = "1";
"B":   PN = "2"  !CDS_PN = "2";
BODY = "SCONN288_H44441003","I12": #LOCATION = "J6L2" !CDS_LOCATION = "J6L2" #SEC = "1" !CDS_SEC = "1";
"A0":   PN = "79"  !CDS_PN = "79";
"A1":   PN = "72"  !CDS_PN = "72";
"A2":   PN = "216"  !CDS_PN = "216";
"A3":   PN = "71"  !CDS_PN = "71";
"A4":   PN = "214"  !CDS_PN = "214";
"A5":   PN = "213"  !CDS_PN = "213";
"A6":   PN = "69"  !CDS_PN = "69";
"A7":   PN = "211"  !CDS_PN = "211";
"A8":   PN = "68"  !CDS_PN = "68";
"A9":   PN = "66"  !CDS_PN = "66";
"A10":   PN = "225"  !CDS_PN = "225";
"A11":   PN = "210"  !CDS_PN = "210";
"A12":   PN = "65"  !CDS_PN = "65";
"A13":   PN = "232"  !CDS_PN = "232";
"A14_WE_N":   PN = "228"  !CDS_PN = "228";
"A15_CAS_N":   PN = "86"  !CDS_PN = "86";
"A16_RAS_N":   PN = "82"  !CDS_PN = "82";
"A17":   PN = "234"  !CDS_PN = "234";
"ACT_N":   PN = "62"  !CDS_PN = "62";
"ALERT_N":   PN = "208"  !CDS_PN = "208";
"BA<0>":   PN = "81"  !CDS_PN = "81";
"BA<1>":   PN = "224"  !CDS_PN = "224";
"BG<0>":   PN = "63"  !CDS_PN = "63";
"BG<1>":   PN = "207"  !CDS_PN = "207";
"C<2>":   PN = "235"  !CDS_PN = "235";
"CB<0>":   PN = "49"  !CDS_PN = "49";
"CB<1>":   PN = "194"  !CDS_PN = "194";
"CB<2>":   PN = "56"  !CDS_PN = "56";
"CB<3>":   PN = "201"  !CDS_PN = "201";
"CB<4>":   PN = "47"  !CDS_PN = "47";
"CB<5>":   PN = "192"  !CDS_PN = "192";
"CB<6>":   PN = "54"  !CDS_PN = "54";
"CB<7>":   PN = "199"  !CDS_PN = "199";
"CK0N":   PN = "75"  !CDS_PN = "75";
"CK0P":   PN = "74"  !CDS_PN = "74";
"CK1N":   PN = "219"  !CDS_PN = "219";
"CK1P":   PN = "218"  !CDS_PN = "218";
"CKE<0>":   PN = "60"  !CDS_PN = "60";
"CKE<1>":   PN = "203"  !CDS_PN = "203";
"DQ<0>":   PN = "5"  !CDS_PN = "5";
"DQ<1>":   PN = "150"  !CDS_PN = "150";
"DQ<2>":   PN = "12"  !CDS_PN = "12";
"DQ<3>":   PN = "157"  !CDS_PN = "157";
"DQ<4>":   PN = "3"  !CDS_PN = "3";
"DQ<5>":   PN = "148"  !CDS_PN = "148";
"DQ<6>":   PN = "10"  !CDS_PN = "10";
"DQ<7>":   PN = "155"  !CDS_PN = "155";
"DQ<8>":   PN = "16"  !CDS_PN = "16";
"DQ<9>":   PN = "161"  !CDS_PN = "161";
"DQ<10>":   PN = "23"  !CDS_PN = "23";
"DQ<11>":   PN = "168"  !CDS_PN = "168";
"DQ<12>":   PN = "14"  !CDS_PN = "14";
"DQ<13>":   PN = "159"  !CDS_PN = "159";
"DQ<14>":   PN = "21"  !CDS_PN = "21";
"DQ<15>":   PN = "166"  !CDS_PN = "166";
"DQ<16>":   PN = "27"  !CDS_PN = "27";
"DQ<17>":   PN = "172"  !CDS_PN = "172";
"DQ<18>":   PN = "34"  !CDS_PN = "34";
"DQ<19>":   PN = "179"  !CDS_PN = "179";
"DQ<20>":   PN = "25"  !CDS_PN = "25";
"DQ<21>":   PN = "170"  !CDS_PN = "170";
"DQ<22>":   PN = "32"  !CDS_PN = "32";
"DQ<23>":   PN = "177"  !CDS_PN = "177";
"DQ<24>":   PN = "38"  !CDS_PN = "38";
"DQ<25>":   PN = "183"  !CDS_PN = "183";
"DQ<26>":   PN = "45"  !CDS_PN = "45";
"DQ<27>":   PN = "190"  !CDS_PN = "190";
"DQ<28>":   PN = "36"  !CDS_PN = "36";
"DQ<29>":   PN = "181"  !CDS_PN = "181";
"DQ<30>":   PN = "43"  !CDS_PN = "43";
"DQ<31>":   PN = "188"  !CDS_PN = "188";
"DQ<32>":   PN = "97"  !CDS_PN = "97";
"DQ<33>":   PN = "242"  !CDS_PN = "242";
"DQ<34>":   PN = "104"  !CDS_PN = "104";
"DQ<35>":   PN = "249"  !CDS_PN = "249";
"DQ<36>":   PN = "95"  !CDS_PN = "95";
"DQ<37>":   PN = "240"  !CDS_PN = "240";
"DQ<38>":   PN = "102"  !CDS_PN = "102";
"DQ<39>":   PN = "247"  !CDS_PN = "247";
"DQ<40>":   PN = "108"  !CDS_PN = "108";
"DQ<41>":   PN = "253"  !CDS_PN = "253";
"DQ<42>":   PN = "115"  !CDS_PN = "115";
"DQ<43>":   PN = "260"  !CDS_PN = "260";
"DQ<44>":   PN = "106"  !CDS_PN = "106";
"DQ<45>":   PN = "251"  !CDS_PN = "251";
"DQ<46>":   PN = "113"  !CDS_PN = "113";
"DQ<47>":   PN = "258"  !CDS_PN = "258";
"DQ<48>":   PN = "119"  !CDS_PN = "119";
"DQ<49>":   PN = "264"  !CDS_PN = "264";
"DQ<50>":   PN = "126"  !CDS_PN = "126";
"DQ<51>":   PN = "271"  !CDS_PN = "271";
"DQ<52>":   PN = "117"  !CDS_PN = "117";
"DQ<53>":   PN = "262"  !CDS_PN = "262";
"DQ<54>":   PN = "124"  !CDS_PN = "124";
"DQ<55>":   PN = "269"  !CDS_PN = "269";
"DQ<56>":   PN = "130"  !CDS_PN = "130";
"DQ<57>":   PN = "275"  !CDS_PN = "275";
"DQ<58>":   PN = "137"  !CDS_PN = "137";
"DQ<59>":   PN = "282"  !CDS_PN = "282";
"DQ<60>":   PN = "128"  !CDS_PN = "128";
"DQ<61>":   PN = "273"  !CDS_PN = "273";
"DQ<62>":   PN = "135"  !CDS_PN = "135";
"DQ<63>":   PN = "280"  !CDS_PN = "280";
"EVENT_N":   PN = "78"  !CDS_PN = "78";
"ODT<0>":   PN = "87"  !CDS_PN = "87";
"ODT<1>":   PN = "91"  !CDS_PN = "91";
"PAR":   PN = "222"  !CDS_PN = "222";
"RESET_N":   PN = "58"  !CDS_PN = "58";
"RFU<0>":   PN = "205"  !CDS_PN = "205";
"RFU<1>":   PN = "227"  !CDS_PN = "227";
"RFU<2>":   PN = "144"  !CDS_PN = "144";
"S0_N":   PN = "84"  !CDS_PN = "84";
"S1_N":   PN = "89"  !CDS_PN = "89";
"S2_N_C<0>":   PN = "93"  !CDS_PN = "93";
"S3_N_C<1>":   PN = "237"  !CDS_PN = "237";
"SA<0>":   PN = "139"  !CDS_PN = "139";
"SA<1>":   PN = "140"  !CDS_PN = "140";
"SA<2>":   PN = "238"  !CDS_PN = "238";
"SAVE_N_NC":   PN = "230"  !CDS_PN = "230";
"SCL":   PN = "141"  !CDS_PN = "141";
"SDA":   PN = "285"  !CDS_PN = "285";
"VDDSPD":   PN = "284"  !CDS_PN = "284";
"VREFCA":   PN = "146"  !CDS_PN = "146";
BODY = "SCONN288_H44441003","I55": #LOCATION = "J6L2" !CDS_LOCATION = "J6L2" #SEC = "4" !CDS_SEC = "4";
"12V<0>":   PN = "145"  !CDS_PN = "145";
"12V<1>":   PN = "1"  !CDS_PN = "1";
"VDD<0>":   PN = "236"  !CDS_PN = "236";
"VDD<1>":   PN = "233"  !CDS_PN = "233";
"VDD<2>":   PN = "231"  !CDS_PN = "231";
"VDD<3>":   PN = "229"  !CDS_PN = "229";
"VDD<4>":   PN = "226"  !CDS_PN = "226";
"VDD<5>":   PN = "223"  !CDS_PN = "223";
"VDD<6>":   PN = "220"  !CDS_PN = "220";
"VDD<7>":   PN = "217"  !CDS_PN = "217";
"VDD<8>":   PN = "215"  !CDS_PN = "215";
"VDD<9>":   PN = "212"  !CDS_PN = "212";
"VDD<10>":   PN = "209"  !CDS_PN = "209";
"VDD<11>":   PN = "206"  !CDS_PN = "206";
"VDD<12>":   PN = "204"  !CDS_PN = "204";
"VDD<13>":   PN = "92"  !CDS_PN = "92";
"VDD<14>":   PN = "90"  !CDS_PN = "90";
"VDD<15>":   PN = "88"  !CDS_PN = "88";
"VDD<16>":   PN = "85"  !CDS_PN = "85";
"VDD<17>":   PN = "83"  !CDS_PN = "83";
"VDD<18>":   PN = "80"  !CDS_PN = "80";
"VDD<19>":   PN = "76"  !CDS_PN = "76";
"VDD<20>":   PN = "73"  !CDS_PN = "73";
"VDD<21>":   PN = "70"  !CDS_PN = "70";
"VDD<22>":   PN = "67"  !CDS_PN = "67";
"VDD<23>":   PN = "64"  !CDS_PN = "64";
"VDD<24>":   PN = "61"  !CDS_PN = "61";
"VDD<25>":   PN = "59"  !CDS_PN = "59";
"VPP<0>":   PN = "287"  !CDS_PN = "287";
"VPP<1>":   PN = "286"  !CDS_PN = "286";
"VPP<2>":   PN = "288"  !CDS_PN = "288";
"VPP<3>":   PN = "143"  !CDS_PN = "143";
"VPP<4>":   PN = "142"  !CDS_PN = "142";
"VTT<0>":   PN = "221"  !CDS_PN = "221";
"VTT<1>":   PN = "77"  !CDS_PN = "77";
BODY = "SCONN288_H44441003","I100": #LOCATION = "J6L2" !CDS_LOCATION = "J6L2" #SEC = "2" !CDS_SEC = "2";
"DQS0N":   PN = "152"  !CDS_PN = "152";
"DQS0P":   PN = "153"  !CDS_PN = "153";
"DQS1N":   PN = "163"  !CDS_PN = "163";
"DQS1P":   PN = "164"  !CDS_PN = "164";
"DQS2N":   PN = "174"  !CDS_PN = "174";
"DQS2P":   PN = "175"  !CDS_PN = "175";
"DQS3N":   PN = "185"  !CDS_PN = "185";
"DQS3P":   PN = "186"  !CDS_PN = "186";
"DQS4N":   PN = "244"  !CDS_PN = "244";
"DQS4P":   PN = "245"  !CDS_PN = "245";
"DQS5N":   PN = "255"  !CDS_PN = "255";
"DQS5P":   PN = "256"  !CDS_PN = "256";
"DQS6N":   PN = "266"  !CDS_PN = "266";
"DQS6P":   PN = "267"  !CDS_PN = "267";
"DQS7N":   PN = "277"  !CDS_PN = "277";
"DQS7P":   PN = "278"  !CDS_PN = "278";
"DQS8N":   PN = "196"  !CDS_PN = "196";
"DQS8P":   PN = "197"  !CDS_PN = "197";
"DQS9N":   PN = "8"  !CDS_PN = "8";
"DQS9P":   PN = "7"  !CDS_PN = "7";
"DQS10N":   PN = "19"  !CDS_PN = "19";
"DQS10P":   PN = "18"  !CDS_PN = "18";
"DQS11N":   PN = "30"  !CDS_PN = "30";
"DQS11P":   PN = "29"  !CDS_PN = "29";
"DQS12N":   PN = "41"  !CDS_PN = "41";
"DQS12P":   PN = "40"  !CDS_PN = "40";
"DQS13N":   PN = "100"  !CDS_PN = "100";
"DQS13P":   PN = "99"  !CDS_PN = "99";
"DQS14N":   PN = "111"  !CDS_PN = "111";
"DQS14P":   PN = "110"  !CDS_PN = "110";
"DQS15N":   PN = "122"  !CDS_PN = "122";
"DQS15P":   PN = "121"  !CDS_PN = "121";
"DQS16N":   PN = "133"  !CDS_PN = "133";
"DQS16P":   PN = "132"  !CDS_PN = "132";
"DQS17N":   PN = "52"  !CDS_PN = "52";
"DQS17P":   PN = "51"  !CDS_PN = "51";
BODY = "SCONN288_H44441003","I138": #LOCATION = "J6L2" !CDS_LOCATION = "J6L2" #SEC = "3" !CDS_SEC = "3";
"VSS<0>":   PN = "283"  !CDS_PN = "283";
"VSS<1>":   PN = "281"  !CDS_PN = "281";
"VSS<2>":   PN = "279"  !CDS_PN = "279";
"VSS<3>":   PN = "276"  !CDS_PN = "276";
"VSS<4>":   PN = "274"  !CDS_PN = "274";
"VSS<5>":   PN = "272"  !CDS_PN = "272";
"VSS<6>":   PN = "270"  !CDS_PN = "270";
"VSS<7>":   PN = "268"  !CDS_PN = "268";
"VSS<8>":   PN = "265"  !CDS_PN = "265";
"VSS<9>":   PN = "263"  !CDS_PN = "263";
"VSS<10>":   PN = "261"  !CDS_PN = "261";
"VSS<11>":   PN = "259"  !CDS_PN = "259";
"VSS<12>":   PN = "257"  !CDS_PN = "257";
"VSS<13>":   PN = "254"  !CDS_PN = "254";
"VSS<14>":   PN = "252"  !CDS_PN = "252";
"VSS<15>":   PN = "250"  !CDS_PN = "250";
"VSS<16>":   PN = "248"  !CDS_PN = "248";
"VSS<17>":   PN = "246"  !CDS_PN = "246";
"VSS<18>":   PN = "243"  !CDS_PN = "243";
"VSS<19>":   PN = "241"  !CDS_PN = "241";
"VSS<20>":   PN = "239"  !CDS_PN = "239";
"VSS<21>":   PN = "202"  !CDS_PN = "202";
"VSS<22>":   PN = "200"  !CDS_PN = "200";
"VSS<23>":   PN = "198"  !CDS_PN = "198";
"VSS<24>":   PN = "195"  !CDS_PN = "195";
"VSS<25>":   PN = "193"  !CDS_PN = "193";
"VSS<26>":   PN = "191"  !CDS_PN = "191";
"VSS<27>":   PN = "189"  !CDS_PN = "189";
"VSS<28>":   PN = "187"  !CDS_PN = "187";
"VSS<29>":   PN = "184"  !CDS_PN = "184";
"VSS<30>":   PN = "182"  !CDS_PN = "182";
"VSS<31>":   PN = "180"  !CDS_PN = "180";
"VSS<32>":   PN = "178"  !CDS_PN = "178";
"VSS<33>":   PN = "176"  !CDS_PN = "176";
"VSS<34>":   PN = "173"  !CDS_PN = "173";
"VSS<35>":   PN = "171"  !CDS_PN = "171";
"VSS<36>":   PN = "169"  !CDS_PN = "169";
"VSS<37>":   PN = "167"  !CDS_PN = "167";
"VSS<38>":   PN = "165"  !CDS_PN = "165";
"VSS<39>":   PN = "162"  !CDS_PN = "162";
"VSS<40>":   PN = "160"  !CDS_PN = "160";
"VSS<41>":   PN = "158"  !CDS_PN = "158";
"VSS<42>":   PN = "156"  !CDS_PN = "156";
"VSS<43>":   PN = "154"  !CDS_PN = "154";
"VSS<44>":   PN = "151"  !CDS_PN = "151";
"VSS<45>":   PN = "149"  !CDS_PN = "149";
"VSS<46>":   PN = "147"  !CDS_PN = "147";
"VSS<47>":   PN = "138"  !CDS_PN = "138";
"VSS<48>":   PN = "136"  !CDS_PN = "136";
"VSS<49>":   PN = "134"  !CDS_PN = "134";
"VSS<50>":   PN = "131"  !CDS_PN = "131";
"VSS<51>":   PN = "129"  !CDS_PN = "129";
"VSS<52>":   PN = "127"  !CDS_PN = "127";
"VSS<53>":   PN = "125"  !CDS_PN = "125";
"VSS<54>":   PN = "123"  !CDS_PN = "123";
"VSS<55>":   PN = "120"  !CDS_PN = "120";
"VSS<56>":   PN = "118"  !CDS_PN = "118";
"VSS<57>":   PN = "116"  !CDS_PN = "116";
"VSS<58>":   PN = "114"  !CDS_PN = "114";
"VSS<59>":   PN = "112"  !CDS_PN = "112";
"VSS<60>":   PN = "109"  !CDS_PN = "109";
"VSS<61>":   PN = "107"  !CDS_PN = "107";
"VSS<62>":   PN = "105"  !CDS_PN = "105";
"VSS<63>":   PN = "103"  !CDS_PN = "103";
"VSS<64>":   PN = "101"  !CDS_PN = "101";
"VSS<65>":   PN = "98"  !CDS_PN = "98";
"VSS<66>":   PN = "96"  !CDS_PN = "96";
"VSS<67>":   PN = "94"  !CDS_PN = "94";
"VSS<68>":   PN = "57"  !CDS_PN = "57";
"VSS<69>":   PN = "55"  !CDS_PN = "55";
"VSS<70>":   PN = "53"  !CDS_PN = "53";
"VSS<71>":   PN = "50"  !CDS_PN = "50";
"VSS<72>":   PN = "48"  !CDS_PN = "48";
"VSS<73>":   PN = "46"  !CDS_PN = "46";
"VSS<74>":   PN = "44"  !CDS_PN = "44";
"VSS<75>":   PN = "42"  !CDS_PN = "42";
"VSS<76>":   PN = "39"  !CDS_PN = "39";
"VSS<77>":   PN = "37"  !CDS_PN = "37";
"VSS<78>":   PN = "35"  !CDS_PN = "35";
"VSS<79>":   PN = "33"  !CDS_PN = "33";
"VSS<80>":   PN = "31"  !CDS_PN = "31";
"VSS<81>":   PN = "28"  !CDS_PN = "28";
"VSS<82>":   PN = "26"  !CDS_PN = "26";
"VSS<83>":   PN = "24"  !CDS_PN = "24";
"VSS<84>":   PN = "22"  !CDS_PN = "22";
"VSS<85>":   PN = "20"  !CDS_PN = "20";
"VSS<86>":   PN = "17"  !CDS_PN = "17";
"VSS<87>":   PN = "15"  !CDS_PN = "15";
"VSS<88>":   PN = "13"  !CDS_PN = "13";
"VSS<89>":   PN = "11"  !CDS_PN = "11";
"VSS<90>":   PN = "9"  !CDS_PN = "9";
"VSS<91>":   PN = "6"  !CDS_PN = "6";
"VSS<92>":   PN = "4"  !CDS_PN = "4";
"VSS<93>":   PN = "2"  !CDS_PN = "2";
DRAWING = "@baseboard_fab2_lib.baseboard_fab2(sch_1):page53";
BODY = "SCONN288_H44441004","I43": #LOCATION = "J4A1" !CDS_LOCATION = "J4A1" #SEC = "3" !CDS_SEC = "3";
"VSS<0>":   PN = "283"  !CDS_PN = "283";
"VSS<1>":   PN = "281"  !CDS_PN = "281";
"VSS<2>":   PN = "279"  !CDS_PN = "279";
"VSS<3>":   PN = "276"  !CDS_PN = "276";
"VSS<4>":   PN = "274"  !CDS_PN = "274";
"VSS<5>":   PN = "272"  !CDS_PN = "272";
"VSS<6>":   PN = "270"  !CDS_PN = "270";
"VSS<7>":   PN = "268"  !CDS_PN = "268";
"VSS<8>":   PN = "265"  !CDS_PN = "265";
"VSS<9>":   PN = "263"  !CDS_PN = "263";
"VSS<10>":   PN = "261"  !CDS_PN = "261";
"VSS<11>":   PN = "259"  !CDS_PN = "259";
"VSS<12>":   PN = "257"  !CDS_PN = "257";
"VSS<13>":   PN = "254"  !CDS_PN = "254";
"VSS<14>":   PN = "252"  !CDS_PN = "252";
"VSS<15>":   PN = "250"  !CDS_PN = "250";
"VSS<16>":   PN = "248"  !CDS_PN = "248";
"VSS<17>":   PN = "246"  !CDS_PN = "246";
"VSS<18>":   PN = "243"  !CDS_PN = "243";
"VSS<19>":   PN = "241"  !CDS_PN = "241";
"VSS<20>":   PN = "239"  !CDS_PN = "239";
"VSS<21>":   PN = "202"  !CDS_PN = "202";
"VSS<22>":   PN = "200"  !CDS_PN = "200";
"VSS<23>":   PN = "198"  !CDS_PN = "198";
"VSS<24>":   PN = "195"  !CDS_PN = "195";
"VSS<25>":   PN = "193"  !CDS_PN = "193";
"VSS<26>":   PN = "191"  !CDS_PN = "191";
"VSS<27>":   PN = "189"  !CDS_PN = "189";
"VSS<28>":   PN = "187"  !CDS_PN = "187";
"VSS<29>":   PN = "184"  !CDS_PN = "184";
"VSS<30>":   PN = "182"  !CDS_PN = "182";
"VSS<31>":   PN = "180"  !CDS_PN = "180";
"VSS<32>":   PN = "178"  !CDS_PN = "178";
"VSS<33>":   PN = "176"  !CDS_PN = "176";
"VSS<34>":   PN = "173"  !CDS_PN = "173";
"VSS<35>":   PN = "171"  !CDS_PN = "171";
"VSS<36>":   PN = "169"  !CDS_PN = "169";
"VSS<37>":   PN = "167"  !CDS_PN = "167";
"VSS<38>":   PN = "165"  !CDS_PN = "165";
"VSS<39>":   PN = "162"  !CDS_PN = "162";
"VSS<40>":   PN = "160"  !CDS_PN = "160";
"VSS<41>":   PN = "158"  !CDS_PN = "158";
"VSS<42>":   PN = "156"  !CDS_PN = "156";
"VSS<43>":   PN = "154"  !CDS_PN = "154";
"VSS<44>":   PN = "151"  !CDS_PN = "151";
"VSS<45>":   PN = "149"  !CDS_PN = "149";
"VSS<46>":   PN = "147"  !CDS_PN = "147";
"VSS<47>":   PN = "138"  !CDS_PN = "138";
"VSS<48>":   PN = "136"  !CDS_PN = "136";
"VSS<49>":   PN = "134"  !CDS_PN = "134";
"VSS<50>":   PN = "131"  !CDS_PN = "131";
"VSS<51>":   PN = "129"  !CDS_PN = "129";
"VSS<52>":   PN = "127"  !CDS_PN = "127";
"VSS<53>":   PN = "125"  !CDS_PN = "125";
"VSS<54>":   PN = "123"  !CDS_PN = "123";
"VSS<55>":   PN = "120"  !CDS_PN = "120";
"VSS<56>":   PN = "118"  !CDS_PN = "118";
"VSS<57>":   PN = "116"  !CDS_PN = "116";
"VSS<58>":   PN = "114"  !CDS_PN = "114";
"VSS<59>":   PN = "112"  !CDS_PN = "112";
"VSS<60>":   PN = "109"  !CDS_PN = "109";
"VSS<61>":   PN = "107"  !CDS_PN = "107";
"VSS<62>":   PN = "105"  !CDS_PN = "105";
"VSS<63>":   PN = "103"  !CDS_PN = "103";
"VSS<64>":   PN = "101"  !CDS_PN = "101";
"VSS<65>":   PN = "98"  !CDS_PN = "98";
"VSS<66>":   PN = "96"  !CDS_PN = "96";
"VSS<67>":   PN = "94"  !CDS_PN = "94";
"VSS<68>":   PN = "57"  !CDS_PN = "57";
"VSS<69>":   PN = "55"  !CDS_PN = "55";
"VSS<70>":   PN = "53"  !CDS_PN = "53";
"VSS<71>":   PN = "50"  !CDS_PN = "50";
"VSS<72>":   PN = "48"  !CDS_PN = "48";
"VSS<73>":   PN = "46"  !CDS_PN = "46";
"VSS<74>":   PN = "44"  !CDS_PN = "44";
"VSS<75>":   PN = "42"  !CDS_PN = "42";
"VSS<76>":   PN = "39"  !CDS_PN = "39";
"VSS<77>":   PN = "37"  !CDS_PN = "37";
"VSS<78>":   PN = "35"  !CDS_PN = "35";
"VSS<79>":   PN = "33"  !CDS_PN = "33";
"VSS<80>":   PN = "31"  !CDS_PN = "31";
"VSS<81>":   PN = "28"  !CDS_PN = "28";
"VSS<82>":   PN = "26"  !CDS_PN = "26";
"VSS<83>":   PN = "24"  !CDS_PN = "24";
"VSS<84>":   PN = "22"  !CDS_PN = "22";
"VSS<85>":   PN = "20"  !CDS_PN = "20";
"VSS<86>":   PN = "17"  !CDS_PN = "17";
"VSS<87>":   PN = "15"  !CDS_PN = "15";
"VSS<88>":   PN = "13"  !CDS_PN = "13";
"VSS<89>":   PN = "11"  !CDS_PN = "11";
"VSS<90>":   PN = "9"  !CDS_PN = "9";
"VSS<91>":   PN = "6"  !CDS_PN = "6";
"VSS<92>":   PN = "4"  !CDS_PN = "4";
"VSS<93>":   PN = "2"  !CDS_PN = "2";
BODY = "SCONN288_H44441004","I66": #LOCATION = "J4A1" !CDS_LOCATION = "J4A1" #SEC = "2" !CDS_SEC = "2";
"DQS0N":   PN = "152"  !CDS_PN = "152";
"DQS0P":   PN = "153"  !CDS_PN = "153";
"DQS1N":   PN = "163"  !CDS_PN = "163";
"DQS1P":   PN = "164"  !CDS_PN = "164";
"DQS2N":   PN = "174"  !CDS_PN = "174";
"DQS2P":   PN = "175"  !CDS_PN = "175";
"DQS3N":   PN = "185"  !CDS_PN = "185";
"DQS3P":   PN = "186"  !CDS_PN = "186";
"DQS4N":   PN = "244"  !CDS_PN = "244";
"DQS4P":   PN = "245"  !CDS_PN = "245";
"DQS5N":   PN = "255"  !CDS_PN = "255";
"DQS5P":   PN = "256"  !CDS_PN = "256";
"DQS6N":   PN = "266"  !CDS_PN = "266";
"DQS6P":   PN = "267"  !CDS_PN = "267";
"DQS7N":   PN = "277"  !CDS_PN = "277";
"DQS7P":   PN = "278"  !CDS_PN = "278";
"DQS8N":   PN = "196"  !CDS_PN = "196";
"DQS8P":   PN = "197"  !CDS_PN = "197";
"DQS9N":   PN = "8"  !CDS_PN = "8";
"DQS9P":   PN = "7"  !CDS_PN = "7";
"DQS10N":   PN = "19"  !CDS_PN = "19";
"DQS10P":   PN = "18"  !CDS_PN = "18";
"DQS11N":   PN = "30"  !CDS_PN = "30";
"DQS11P":   PN = "29"  !CDS_PN = "29";
"DQS12N":   PN = "41"  !CDS_PN = "41";
"DQS12P":   PN = "40"  !CDS_PN = "40";
"DQS13N":   PN = "100"  !CDS_PN = "100";
"DQS13P":   PN = "99"  !CDS_PN = "99";
"DQS14N":   PN = "111"  !CDS_PN = "111";
"DQS14P":   PN = "110"  !CDS_PN = "110";
"DQS15N":   PN = "122"  !CDS_PN = "122";
"DQS15P":   PN = "121"  !CDS_PN = "121";
"DQS16N":   PN = "133"  !CDS_PN = "133";
"DQS16P":   PN = "132"  !CDS_PN = "132";
"DQS17N":   PN = "52"  !CDS_PN = "52";
"DQS17P":   PN = "51"  !CDS_PN = "51";
BODY = "SCONN288_H44441004","I111": #LOCATION = "J4A1" !CDS_LOCATION = "J4A1" #SEC = "1" !CDS_SEC = "1";
"A0":   PN = "79"  !CDS_PN = "79";
"A1":   PN = "72"  !CDS_PN = "72";
"A2":   PN = "216"  !CDS_PN = "216";
"A3":   PN = "71"  !CDS_PN = "71";
"A4":   PN = "214"  !CDS_PN = "214";
"A5":   PN = "213"  !CDS_PN = "213";
"A6":   PN = "69"  !CDS_PN = "69";
"A7":   PN = "211"  !CDS_PN = "211";
"A8":   PN = "68"  !CDS_PN = "68";
"A9":   PN = "66"  !CDS_PN = "66";
"A10":   PN = "225"  !CDS_PN = "225";
"A11":   PN = "210"  !CDS_PN = "210";
"A12":   PN = "65"  !CDS_PN = "65";
"A13":   PN = "232"  !CDS_PN = "232";
"A14_WE_N":   PN = "228"  !CDS_PN = "228";
"A15_CAS_N":   PN = "86"  !CDS_PN = "86";
"A16_RAS_N":   PN = "82"  !CDS_PN = "82";
"A17":   PN = "234"  !CDS_PN = "234";
"ACT_N":   PN = "62"  !CDS_PN = "62";
"ALERT_N":   PN = "208"  !CDS_PN = "208";
"BA<0>":   PN = "81"  !CDS_PN = "81";
"BA<1>":   PN = "224"  !CDS_PN = "224";
"BG<0>":   PN = "63"  !CDS_PN = "63";
"BG<1>":   PN = "207"  !CDS_PN = "207";
"C<2>":   PN = "235"  !CDS_PN = "235";
"CB<0>":   PN = "49"  !CDS_PN = "49";
"CB<1>":   PN = "194"  !CDS_PN = "194";
"CB<2>":   PN = "56"  !CDS_PN = "56";
"CB<3>":   PN = "201"  !CDS_PN = "201";
"CB<4>":   PN = "47"  !CDS_PN = "47";
"CB<5>":   PN = "192"  !CDS_PN = "192";
"CB<6>":   PN = "54"  !CDS_PN = "54";
"CB<7>":   PN = "199"  !CDS_PN = "199";
"CK0N":   PN = "75"  !CDS_PN = "75";
"CK0P":   PN = "74"  !CDS_PN = "74";
"CK1N":   PN = "219"  !CDS_PN = "219";
"CK1P":   PN = "218"  !CDS_PN = "218";
"CKE<0>":   PN = "60"  !CDS_PN = "60";
"CKE<1>":   PN = "203"  !CDS_PN = "203";
"DQ<0>":   PN = "5"  !CDS_PN = "5";
"DQ<1>":   PN = "150"  !CDS_PN = "150";
"DQ<2>":   PN = "12"  !CDS_PN = "12";
"DQ<3>":   PN = "157"  !CDS_PN = "157";
"DQ<4>":   PN = "3"  !CDS_PN = "3";
"DQ<5>":   PN = "148"  !CDS_PN = "148";
"DQ<6>":   PN = "10"  !CDS_PN = "10";
"DQ<7>":   PN = "155"  !CDS_PN = "155";
"DQ<8>":   PN = "16"  !CDS_PN = "16";
"DQ<9>":   PN = "161"  !CDS_PN = "161";
"DQ<10>":   PN = "23"  !CDS_PN = "23";
"DQ<11>":   PN = "168"  !CDS_PN = "168";
"DQ<12>":   PN = "14"  !CDS_PN = "14";
"DQ<13>":   PN = "159"  !CDS_PN = "159";
"DQ<14>":   PN = "21"  !CDS_PN = "21";
"DQ<15>":   PN = "166"  !CDS_PN = "166";
"DQ<16>":   PN = "27"  !CDS_PN = "27";
"DQ<17>":   PN = "172"  !CDS_PN = "172";
"DQ<18>":   PN = "34"  !CDS_PN = "34";
"DQ<19>":   PN = "179"  !CDS_PN = "179";
"DQ<20>":   PN = "25"  !CDS_PN = "25";
"DQ<21>":   PN = "170"  !CDS_PN = "170";
"DQ<22>":   PN = "32"  !CDS_PN = "32";
"DQ<23>":   PN = "177"  !CDS_PN = "177";
"DQ<24>":   PN = "38"  !CDS_PN = "38";
"DQ<25>":   PN = "183"  !CDS_PN = "183";
"DQ<26>":   PN = "45"  !CDS_PN = "45";
"DQ<27>":   PN = "190"  !CDS_PN = "190";
"DQ<28>":   PN = "36"  !CDS_PN = "36";
"DQ<29>":   PN = "181"  !CDS_PN = "181";
"DQ<30>":   PN = "43"  !CDS_PN = "43";
"DQ<31>":   PN = "188"  !CDS_PN = "188";
"DQ<32>":   PN = "97"  !CDS_PN = "97";
"DQ<33>":   PN = "242"  !CDS_PN = "242";
"DQ<34>":   PN = "104"  !CDS_PN = "104";
"DQ<35>":   PN = "249"  !CDS_PN = "249";
"DQ<36>":   PN = "95"  !CDS_PN = "95";
"DQ<37>":   PN = "240"  !CDS_PN = "240";
"DQ<38>":   PN = "102"  !CDS_PN = "102";
"DQ<39>":   PN = "247"  !CDS_PN = "247";
"DQ<40>":   PN = "108"  !CDS_PN = "108";
"DQ<41>":   PN = "253"  !CDS_PN = "253";
"DQ<42>":   PN = "115"  !CDS_PN = "115";
"DQ<43>":   PN = "260"  !CDS_PN = "260";
"DQ<44>":   PN = "106"  !CDS_PN = "106";
"DQ<45>":   PN = "251"  !CDS_PN = "251";
"DQ<46>":   PN = "113"  !CDS_PN = "113";
"DQ<47>":   PN = "258"  !CDS_PN = "258";
"DQ<48>":   PN = "119"  !CDS_PN = "119";
"DQ<49>":   PN = "264"  !CDS_PN = "264";
"DQ<50>":   PN = "126"  !CDS_PN = "126";
"DQ<51>":   PN = "271"  !CDS_PN = "271";
"DQ<52>":   PN = "117"  !CDS_PN = "117";
"DQ<53>":   PN = "262"  !CDS_PN = "262";
"DQ<54>":   PN = "124"  !CDS_PN = "124";
"DQ<55>":   PN = "269"  !CDS_PN = "269";
"DQ<56>":   PN = "130"  !CDS_PN = "130";
"DQ<57>":   PN = "275"  !CDS_PN = "275";
"DQ<58>":   PN = "137"  !CDS_PN = "137";
"DQ<59>":   PN = "282"  !CDS_PN = "282";
"DQ<60>":   PN = "128"  !CDS_PN = "128";
"DQ<61>":   PN = "273"  !CDS_PN = "273";
"DQ<62>":   PN = "135"  !CDS_PN = "135";
"DQ<63>":   PN = "280"  !CDS_PN = "280";
"EVENT_N":   PN = "78"  !CDS_PN = "78";
"ODT<0>":   PN = "87"  !CDS_PN = "87";
"ODT<1>":   PN = "91"  !CDS_PN = "91";
"PAR":   PN = "222"  !CDS_PN = "222";
"RESET_N":   PN = "58"  !CDS_PN = "58";
"RFU<0>":   PN = "205"  !CDS_PN = "205";
"RFU<1>":   PN = "227"  !CDS_PN = "227";
"RFU<2>":   PN = "144"  !CDS_PN = "144";
"S0_N":   PN = "84"  !CDS_PN = "84";
"S1_N":   PN = "89"  !CDS_PN = "89";
"S2_N_C<0>":   PN = "93"  !CDS_PN = "93";
"S3_N_C<1>":   PN = "237"  !CDS_PN = "237";
"SA<0>":   PN = "139"  !CDS_PN = "139";
"SA<1>":   PN = "140"  !CDS_PN = "140";
"SA<2>":   PN = "238"  !CDS_PN = "238";
"SAVE_N_NC":   PN = "230"  !CDS_PN = "230";
"SCL":   PN = "141"  !CDS_PN = "141";
"SDA":   PN = "285"  !CDS_PN = "285";
"VDDSPD":   PN = "284"  !CDS_PN = "284";
"VREFCA":   PN = "146"  !CDS_PN = "146";
BODY = "SCONN288_H44441004","I171": #LOCATION = "J4A1" !CDS_LOCATION = "J4A1" #SEC = "4" !CDS_SEC = "4";
"12V<0>":   PN = "145"  !CDS_PN = "145";
"12V<1>":   PN = "1"  !CDS_PN = "1";
"VDD<0>":   PN = "236"  !CDS_PN = "236";
"VDD<1>":   PN = "233"  !CDS_PN = "233";
"VDD<2>":   PN = "231"  !CDS_PN = "231";
"VDD<3>":   PN = "229"  !CDS_PN = "229";
"VDD<4>":   PN = "226"  !CDS_PN = "226";
"VDD<5>":   PN = "223"  !CDS_PN = "223";
"VDD<6>":   PN = "220"  !CDS_PN = "220";
"VDD<7>":   PN = "217"  !CDS_PN = "217";
"VDD<8>":   PN = "215"  !CDS_PN = "215";
"VDD<9>":   PN = "212"  !CDS_PN = "212";
"VDD<10>":   PN = "209"  !CDS_PN = "209";
"VDD<11>":   PN = "206"  !CDS_PN = "206";
"VDD<12>":   PN = "204"  !CDS_PN = "204";
"VDD<13>":   PN = "92"  !CDS_PN = "92";
"VDD<14>":   PN = "90"  !CDS_PN = "90";
"VDD<15>":   PN = "88"  !CDS_PN = "88";
"VDD<16>":   PN = "85"  !CDS_PN = "85";
"VDD<17>":   PN = "83"  !CDS_PN = "83";
"VDD<18>":   PN = "80"  !CDS_PN = "80";
"VDD<19>":   PN = "76"  !CDS_PN = "76";
"VDD<20>":   PN = "73"  !CDS_PN = "73";
"VDD<21>":   PN = "70"  !CDS_PN = "70";
"VDD<22>":   PN = "67"  !CDS_PN = "67";
"VDD<23>":   PN = "64"  !CDS_PN = "64";
"VDD<24>":   PN = "61"  !CDS_PN = "61";
"VDD<25>":   PN = "59"  !CDS_PN = "59";
"VPP<0>":   PN = "287"  !CDS_PN = "287";
"VPP<1>":   PN = "286"  !CDS_PN = "286";
"VPP<2>":   PN = "288"  !CDS_PN = "288";
"VPP<3>":   PN = "143"  !CDS_PN = "143";
"VPP<4>":   PN = "142"  !CDS_PN = "142";
"VTT<0>":   PN = "221"  !CDS_PN = "221";
"VTT<1>":   PN = "77"  !CDS_PN = "77";
BODY = "CAP_A","I178": #LOCATION = "C6L1" !CDS_LOCATION = "C6L1" &SEC = "1" #&CDS_SEC = "1";
"A":   PN = "1"  !CDS_PN = "1";
"B":   PN = "2"  !CDS_PN = "2";
DRAWING = "@baseboard_fab2_lib.baseboard_fab2(sch_1):page54";
BODY = "SCONN288_H44441003","I43": #LOCATION = "J6L1" !CDS_LOCATION = "J6L1" #SEC = "3" !CDS_SEC = "3";
"VSS<0>":   PN = "283"  !CDS_PN = "283";
"VSS<1>":   PN = "281"  !CDS_PN = "281";
"VSS<2>":   PN = "279"  !CDS_PN = "279";
"VSS<3>":   PN = "276"  !CDS_PN = "276";
"VSS<4>":   PN = "274"  !CDS_PN = "274";
"VSS<5>":   PN = "272"  !CDS_PN = "272";
"VSS<6>":   PN = "270"  !CDS_PN = "270";
"VSS<7>":   PN = "268"  !CDS_PN = "268";
"VSS<8>":   PN = "265"  !CDS_PN = "265";
"VSS<9>":   PN = "263"  !CDS_PN = "263";
"VSS<10>":   PN = "261"  !CDS_PN = "261";
"VSS<11>":   PN = "259"  !CDS_PN = "259";
"VSS<12>":   PN = "257"  !CDS_PN = "257";
"VSS<13>":   PN = "254"  !CDS_PN = "254";
"VSS<14>":   PN = "252"  !CDS_PN = "252";
"VSS<15>":   PN = "250"  !CDS_PN = "250";
"VSS<16>":   PN = "248"  !CDS_PN = "248";
"VSS<17>":   PN = "246"  !CDS_PN = "246";
"VSS<18>":   PN = "243"  !CDS_PN = "243";
"VSS<19>":   PN = "241"  !CDS_PN = "241";
"VSS<20>":   PN = "239"  !CDS_PN = "239";
"VSS<21>":   PN = "202"  !CDS_PN = "202";
"VSS<22>":   PN = "200"  !CDS_PN = "200";
"VSS<23>":   PN = "198"  !CDS_PN = "198";
"VSS<24>":   PN = "195"  !CDS_PN = "195";
"VSS<25>":   PN = "193"  !CDS_PN = "193";
"VSS<26>":   PN = "191"  !CDS_PN = "191";
"VSS<27>":   PN = "189"  !CDS_PN = "189";
"VSS<28>":   PN = "187"  !CDS_PN = "187";
"VSS<29>":   PN = "184"  !CDS_PN = "184";
"VSS<30>":   PN = "182"  !CDS_PN = "182";
"VSS<31>":   PN = "180"  !CDS_PN = "180";
"VSS<32>":   PN = "178"  !CDS_PN = "178";
"VSS<33>":   PN = "176"  !CDS_PN = "176";
"VSS<34>":   PN = "173"  !CDS_PN = "173";
"VSS<35>":   PN = "171"  !CDS_PN = "171";
"VSS<36>":   PN = "169"  !CDS_PN = "169";
"VSS<37>":   PN = "167"  !CDS_PN = "167";
"VSS<38>":   PN = "165"  !CDS_PN = "165";
"VSS<39>":   PN = "162"  !CDS_PN = "162";
"VSS<40>":   PN = "160"  !CDS_PN = "160";
"VSS<41>":   PN = "158"  !CDS_PN = "158";
"VSS<42>":   PN = "156"  !CDS_PN = "156";
"VSS<43>":   PN = "154"  !CDS_PN = "154";
"VSS<44>":   PN = "151"  !CDS_PN = "151";
"VSS<45>":   PN = "149"  !CDS_PN = "149";
"VSS<46>":   PN = "147"  !CDS_PN = "147";
"VSS<47>":   PN = "138"  !CDS_PN = "138";
"VSS<48>":   PN = "136"  !CDS_PN = "136";
"VSS<49>":   PN = "134"  !CDS_PN = "134";
"VSS<50>":   PN = "131"  !CDS_PN = "131";
"VSS<51>":   PN = "129"  !CDS_PN = "129";
"VSS<52>":   PN = "127"  !CDS_PN = "127";
"VSS<53>":   PN = "125"  !CDS_PN = "125";
"VSS<54>":   PN = "123"  !CDS_PN = "123";
"VSS<55>":   PN = "120"  !CDS_PN = "120";
"VSS<56>":   PN = "118"  !CDS_PN = "118";
"VSS<57>":   PN = "116"  !CDS_PN = "116";
"VSS<58>":   PN = "114"  !CDS_PN = "114";
"VSS<59>":   PN = "112"  !CDS_PN = "112";
"VSS<60>":   PN = "109"  !CDS_PN = "109";
"VSS<61>":   PN = "107"  !CDS_PN = "107";
"VSS<62>":   PN = "105"  !CDS_PN = "105";
"VSS<63>":   PN = "103"  !CDS_PN = "103";
"VSS<64>":   PN = "101"  !CDS_PN = "101";
"VSS<65>":   PN = "98"  !CDS_PN = "98";
"VSS<66>":   PN = "96"  !CDS_PN = "96";
"VSS<67>":   PN = "94"  !CDS_PN = "94";
"VSS<68>":   PN = "57"  !CDS_PN = "57";
"VSS<69>":   PN = "55"  !CDS_PN = "55";
"VSS<70>":   PN = "53"  !CDS_PN = "53";
"VSS<71>":   PN = "50"  !CDS_PN = "50";
"VSS<72>":   PN = "48"  !CDS_PN = "48";
"VSS<73>":   PN = "46"  !CDS_PN = "46";
"VSS<74>":   PN = "44"  !CDS_PN = "44";
"VSS<75>":   PN = "42"  !CDS_PN = "42";
"VSS<76>":   PN = "39"  !CDS_PN = "39";
"VSS<77>":   PN = "37"  !CDS_PN = "37";
"VSS<78>":   PN = "35"  !CDS_PN = "35";
"VSS<79>":   PN = "33"  !CDS_PN = "33";
"VSS<80>":   PN = "31"  !CDS_PN = "31";
"VSS<81>":   PN = "28"  !CDS_PN = "28";
"VSS<82>":   PN = "26"  !CDS_PN = "26";
"VSS<83>":   PN = "24"  !CDS_PN = "24";
"VSS<84>":   PN = "22"  !CDS_PN = "22";
"VSS<85>":   PN = "20"  !CDS_PN = "20";
"VSS<86>":   PN = "17"  !CDS_PN = "17";
"VSS<87>":   PN = "15"  !CDS_PN = "15";
"VSS<88>":   PN = "13"  !CDS_PN = "13";
"VSS<89>":   PN = "11"  !CDS_PN = "11";
"VSS<90>":   PN = "9"  !CDS_PN = "9";
"VSS<91>":   PN = "6"  !CDS_PN = "6";
"VSS<92>":   PN = "4"  !CDS_PN = "4";
"VSS<93>":   PN = "2"  !CDS_PN = "2";
BODY = "SCONN288_H44441003","I66": #LOCATION = "J6L1" !CDS_LOCATION = "J6L1" #SEC = "2" !CDS_SEC = "2";
"DQS0N":   PN = "152"  !CDS_PN = "152";
"DQS0P":   PN = "153"  !CDS_PN = "153";
"DQS1N":   PN = "163"  !CDS_PN = "163";
"DQS1P":   PN = "164"  !CDS_PN = "164";
"DQS2N":   PN = "174"  !CDS_PN = "174";
"DQS2P":   PN = "175"  !CDS_PN = "175";
"DQS3N":   PN = "185"  !CDS_PN = "185";
"DQS3P":   PN = "186"  !CDS_PN = "186";
"DQS4N":   PN = "244"  !CDS_PN = "244";
"DQS4P":   PN = "245"  !CDS_PN = "245";
"DQS5N":   PN = "255"  !CDS_PN = "255";
"DQS5P":   PN = "256"  !CDS_PN = "256";
"DQS6N":   PN = "266"  !CDS_PN = "266";
"DQS6P":   PN = "267"  !CDS_PN = "267";
"DQS7N":   PN = "277"  !CDS_PN = "277";
"DQS7P":   PN = "278"  !CDS_PN = "278";
"DQS8N":   PN = "196"  !CDS_PN = "196";
"DQS8P":   PN = "197"  !CDS_PN = "197";
"DQS9N":   PN = "8"  !CDS_PN = "8";
"DQS9P":   PN = "7"  !CDS_PN = "7";
"DQS10N":   PN = "19"  !CDS_PN = "19";
"DQS10P":   PN = "18"  !CDS_PN = "18";
"DQS11N":   PN = "30"  !CDS_PN = "30";
"DQS11P":   PN = "29"  !CDS_PN = "29";
"DQS12N":   PN = "41"  !CDS_PN = "41";
"DQS12P":   PN = "40"  !CDS_PN = "40";
"DQS13N":   PN = "100"  !CDS_PN = "100";
"DQS13P":   PN = "99"  !CDS_PN = "99";
"DQS14N":   PN = "111"  !CDS_PN = "111";
"DQS14P":   PN = "110"  !CDS_PN = "110";
"DQS15N":   PN = "122"  !CDS_PN = "122";
"DQS15P":   PN = "121"  !CDS_PN = "121";
"DQS16N":   PN = "133"  !CDS_PN = "133";
"DQS16P":   PN = "132"  !CDS_PN = "132";
"DQS17N":   PN = "52"  !CDS_PN = "52";
"DQS17P":   PN = "51"  !CDS_PN = "51";
BODY = "SCONN288_H44441003","I111": #LOCATION = "J6L1" !CDS_LOCATION = "J6L1" #SEC = "1" !CDS_SEC = "1";
"A0":   PN = "79"  !CDS_PN = "79";
"A1":   PN = "72"  !CDS_PN = "72";
"A2":   PN = "216"  !CDS_PN = "216";
"A3":   PN = "71"  !CDS_PN = "71";
"A4":   PN = "214"  !CDS_PN = "214";
"A5":   PN = "213"  !CDS_PN = "213";
"A6":   PN = "69"  !CDS_PN = "69";
"A7":   PN = "211"  !CDS_PN = "211";
"A8":   PN = "68"  !CDS_PN = "68";
"A9":   PN = "66"  !CDS_PN = "66";
"A10":   PN = "225"  !CDS_PN = "225";
"A11":   PN = "210"  !CDS_PN = "210";
"A12":   PN = "65"  !CDS_PN = "65";
"A13":   PN = "232"  !CDS_PN = "232";
"A14_WE_N":   PN = "228"  !CDS_PN = "228";
"A15_CAS_N":   PN = "86"  !CDS_PN = "86";
"A16_RAS_N":   PN = "82"  !CDS_PN = "82";
"A17":   PN = "234"  !CDS_PN = "234";
"ACT_N":   PN = "62"  !CDS_PN = "62";
"ALERT_N":   PN = "208"  !CDS_PN = "208";
"BA<0>":   PN = "81"  !CDS_PN = "81";
"BA<1>":   PN = "224"  !CDS_PN = "224";
"BG<0>":   PN = "63"  !CDS_PN = "63";
"BG<1>":   PN = "207"  !CDS_PN = "207";
"C<2>":   PN = "235"  !CDS_PN = "235";
"CB<0>":   PN = "49"  !CDS_PN = "49";
"CB<1>":   PN = "194"  !CDS_PN = "194";
"CB<2>":   PN = "56"  !CDS_PN = "56";
"CB<3>":   PN = "201"  !CDS_PN = "201";
"CB<4>":   PN = "47"  !CDS_PN = "47";
"CB<5>":   PN = "192"  !CDS_PN = "192";
"CB<6>":   PN = "54"  !CDS_PN = "54";
"CB<7>":   PN = "199"  !CDS_PN = "199";
"CK0N":   PN = "75"  !CDS_PN = "75";
"CK0P":   PN = "74"  !CDS_PN = "74";
"CK1N":   PN = "219"  !CDS_PN = "219";
"CK1P":   PN = "218"  !CDS_PN = "218";
"CKE<0>":   PN = "60"  !CDS_PN = "60";
"CKE<1>":   PN = "203"  !CDS_PN = "203";
"DQ<0>":   PN = "5"  !CDS_PN = "5";
"DQ<1>":   PN = "150"  !CDS_PN = "150";
"DQ<2>":   PN = "12"  !CDS_PN = "12";
"DQ<3>":   PN = "157"  !CDS_PN = "157";
"DQ<4>":   PN = "3"  !CDS_PN = "3";
"DQ<5>":   PN = "148"  !CDS_PN = "148";
"DQ<6>":   PN = "10"  !CDS_PN = "10";
"DQ<7>":   PN = "155"  !CDS_PN = "155";
"DQ<8>":   PN = "16"  !CDS_PN = "16";
"DQ<9>":   PN = "161"  !CDS_PN = "161";
"DQ<10>":   PN = "23"  !CDS_PN = "23";
"DQ<11>":   PN = "168"  !CDS_PN = "168";
"DQ<12>":   PN = "14"  !CDS_PN = "14";
"DQ<13>":   PN = "159"  !CDS_PN = "159";
"DQ<14>":   PN = "21"  !CDS_PN = "21";
"DQ<15>":   PN = "166"  !CDS_PN = "166";
"DQ<16>":   PN = "27"  !CDS_PN = "27";
"DQ<17>":   PN = "172"  !CDS_PN = "172";
"DQ<18>":   PN = "34"  !CDS_PN = "34";
"DQ<19>":   PN = "179"  !CDS_PN = "179";
"DQ<20>":   PN = "25"  !CDS_PN = "25";
"DQ<21>":   PN = "170"  !CDS_PN = "170";
"DQ<22>":   PN = "32"  !CDS_PN = "32";
"DQ<23>":   PN = "177"  !CDS_PN = "177";
"DQ<24>":   PN = "38"  !CDS_PN = "38";
"DQ<25>":   PN = "183"  !CDS_PN = "183";
"DQ<26>":   PN = "45"  !CDS_PN = "45";
"DQ<27>":   PN = "190"  !CDS_PN = "190";
"DQ<28>":   PN = "36"  !CDS_PN = "36";
"DQ<29>":   PN = "181"  !CDS_PN = "181";
"DQ<30>":   PN = "43"  !CDS_PN = "43";
"DQ<31>":   PN = "188"  !CDS_PN = "188";
"DQ<32>":   PN = "97"  !CDS_PN = "97";
"DQ<33>":   PN = "242"  !CDS_PN = "242";
"DQ<34>":   PN = "104"  !CDS_PN = "104";
"DQ<35>":   PN = "249"  !CDS_PN = "249";
"DQ<36>":   PN = "95"  !CDS_PN = "95";
"DQ<37>":   PN = "240"  !CDS_PN = "240";
"DQ<38>":   PN = "102"  !CDS_PN = "102";
"DQ<39>":   PN = "247"  !CDS_PN = "247";
"DQ<40>":   PN = "108"  !CDS_PN = "108";
"DQ<41>":   PN = "253"  !CDS_PN = "253";
"DQ<42>":   PN = "115"  !CDS_PN = "115";
"DQ<43>":   PN = "260"  !CDS_PN = "260";
"DQ<44>":   PN = "106"  !CDS_PN = "106";
"DQ<45>":   PN = "251"  !CDS_PN = "251";
"DQ<46>":   PN = "113"  !CDS_PN = "113";
"DQ<47>":   PN = "258"  !CDS_PN = "258";
"DQ<48>":   PN = "119"  !CDS_PN = "119";
"DQ<49>":   PN = "264"  !CDS_PN = "264";
"DQ<50>":   PN = "126"  !CDS_PN = "126";
"DQ<51>":   PN = "271"  !CDS_PN = "271";
"DQ<52>":   PN = "117"  !CDS_PN = "117";
"DQ<53>":   PN = "262"  !CDS_PN = "262";
"DQ<54>":   PN = "124"  !CDS_PN = "124";
"DQ<55>":   PN = "269"  !CDS_PN = "269";
"DQ<56>":   PN = "130"  !CDS_PN = "130";
"DQ<57>":   PN = "275"  !CDS_PN = "275";
"DQ<58>":   PN = "137"  !CDS_PN = "137";
"DQ<59>":   PN = "282"  !CDS_PN = "282";
"DQ<60>":   PN = "128"  !CDS_PN = "128";
"DQ<61>":   PN = "273"  !CDS_PN = "273";
"DQ<62>":   PN = "135"  !CDS_PN = "135";
"DQ<63>":   PN = "280"  !CDS_PN = "280";
"EVENT_N":   PN = "78"  !CDS_PN = "78";
"ODT<0>":   PN = "87"  !CDS_PN = "87";
"ODT<1>":   PN = "91"  !CDS_PN = "91";
"PAR":   PN = "222"  !CDS_PN = "222";
"RESET_N":   PN = "58"  !CDS_PN = "58";
"RFU<0>":   PN = "205"  !CDS_PN = "205";
"RFU<1>":   PN = "227"  !CDS_PN = "227";
"RFU<2>":   PN = "144"  !CDS_PN = "144";
"S0_N":   PN = "84"  !CDS_PN = "84";
"S1_N":   PN = "89"  !CDS_PN = "89";
"S2_N_C<0>":   PN = "93"  !CDS_PN = "93";
"S3_N_C<1>":   PN = "237"  !CDS_PN = "237";
"SA<0>":   PN = "139"  !CDS_PN = "139";
"SA<1>":   PN = "140"  !CDS_PN = "140";
"SA<2>":   PN = "238"  !CDS_PN = "238";
"SAVE_N_NC":   PN = "230"  !CDS_PN = "230";
"SCL":   PN = "141"  !CDS_PN = "141";
"SDA":   PN = "285"  !CDS_PN = "285";
"VDDSPD":   PN = "284"  !CDS_PN = "284";
"VREFCA":   PN = "146"  !CDS_PN = "146";
BODY = "SCONN288_H44441003","I170": #LOCATION = "J6L1" !CDS_LOCATION = "J6L1" #SEC = "4" !CDS_SEC = "4";
"12V<0>":   PN = "145"  !CDS_PN = "145";
"12V<1>":   PN = "1"  !CDS_PN = "1";
"VDD<0>":   PN = "236"  !CDS_PN = "236";
"VDD<1>":   PN = "233"  !CDS_PN = "233";
"VDD<2>":   PN = "231"  !CDS_PN = "231";
"VDD<3>":   PN = "229"  !CDS_PN = "229";
"VDD<4>":   PN = "226"  !CDS_PN = "226";
"VDD<5>":   PN = "223"  !CDS_PN = "223";
"VDD<6>":   PN = "220"  !CDS_PN = "220";
"VDD<7>":   PN = "217"  !CDS_PN = "217";
"VDD<8>":   PN = "215"  !CDS_PN = "215";
"VDD<9>":   PN = "212"  !CDS_PN = "212";
"VDD<10>":   PN = "209"  !CDS_PN = "209";
"VDD<11>":   PN = "206"  !CDS_PN = "206";
"VDD<12>":   PN = "204"  !CDS_PN = "204";
"VDD<13>":   PN = "92"  !CDS_PN = "92";
"VDD<14>":   PN = "90"  !CDS_PN = "90";
"VDD<15>":   PN = "88"  !CDS_PN = "88";
"VDD<16>":   PN = "85"  !CDS_PN = "85";
"VDD<17>":   PN = "83"  !CDS_PN = "83";
"VDD<18>":   PN = "80"  !CDS_PN = "80";
"VDD<19>":   PN = "76"  !CDS_PN = "76";
"VDD<20>":   PN = "73"  !CDS_PN = "73";
"VDD<21>":   PN = "70"  !CDS_PN = "70";
"VDD<22>":   PN = "67"  !CDS_PN = "67";
"VDD<23>":   PN = "64"  !CDS_PN = "64";
"VDD<24>":   PN = "61"  !CDS_PN = "61";
"VDD<25>":   PN = "59"  !CDS_PN = "59";
"VPP<0>":   PN = "287"  !CDS_PN = "287";
"VPP<1>":   PN = "286"  !CDS_PN = "286";
"VPP<2>":   PN = "288"  !CDS_PN = "288";
"VPP<3>":   PN = "143"  !CDS_PN = "143";
"VPP<4>":   PN = "142"  !CDS_PN = "142";
"VTT<0>":   PN = "221"  !CDS_PN = "221";
"VTT<1>":   PN = "77"  !CDS_PN = "77";
BODY = "CAP_A","I179": #LOCATION = "C4A5" !CDS_LOCATION = "C4A5" &SEC = "1" #&CDS_SEC = "1";
"A":   PN = "1"  !CDS_PN = "1";
"B":   PN = "2"  !CDS_PN = "2";
DRAWING = "@baseboard_fab2_lib.baseboard_fab2(sch_1):page55";
BODY = "RES","I4": #LOCATION = "R9N1" !CDS_LOCATION = "R9N1" #SEC = "1" !CDS_SEC = "1";
"A":   PN = "1"  !CDS_PN = "1";
"B":   PN = "2"  !CDS_PN = "2";
BODY = "RES","I7": #LOCATION = "R9N2" !CDS_LOCATION = "R9N2" #SEC = "1" !CDS_SEC = "1";
"A":   PN = "1"  !CDS_PN = "1";
"B":   PN = "2"  !CDS_PN = "2";
BODY = "RES","I19": #LOCATION = "R3B2" !CDS_LOCATION = "R3B2" #SEC = "1" !CDS_SEC = "1";
"A":   PN = "1"  !CDS_PN = "1";
"B":   PN = "2"  !CDS_PN = "2";
BODY = "RES","I21": #LOCATION = "R3B4" !CDS_LOCATION = "R3B4" #SEC = "1" !CDS_SEC = "1";
"A":   PN = "1"  !CDS_PN = "1";
"B":   PN = "2"  !CDS_PN = "2";
BODY = "RES","I24": #LOCATION = "R1C2" !CDS_LOCATION = "R1C2" &SEC = "1" #&CDS_SEC = "1";
"A":   PN = "1"  !CDS_PN = "1";
"B":   PN = "2"  !CDS_PN = "2";
BODY = "RES","I25": #LOCATION = "R1C3" !CDS_LOCATION = "R1C3" &SEC = "1" #&CDS_SEC = "1";
"A":   PN = "1"  !CDS_PN = "1";
"B":   PN = "2"  !CDS_PN = "2";
BODY = "RES","I26": #LOCATION = "R1C1" !CDS_LOCATION = "R1C1" &SEC = "1" #&CDS_SEC = "1";
"A":   PN = "1"  !CDS_PN = "1";
"B":   PN = "2"  !CDS_PN = "2";
BODY = "RES","I27": #LOCATION = "R3B1" !CDS_LOCATION = "R3B1" &SEC = "1" #&CDS_SEC = "1";
"A":   PN = "1"  !CDS_PN = "1";
"B":   PN = "2"  !CDS_PN = "2";
BODY = "RES","I28": #LOCATION = "R3B5" !CDS_LOCATION = "R3B5" &SEC = "1" #&CDS_SEC = "1";
"A":   PN = "1"  !CDS_PN = "1";
"B":   PN = "2"  !CDS_PN = "2";
BODY = "RES","I29": #LOCATION = "R3B3" !CDS_LOCATION = "R3B3" &SEC = "1" #&CDS_SEC = "1";
"A":   PN = "1"  !CDS_PN = "1";
"B":   PN = "2"  !CDS_PN = "2";
BODY = "RES","I115": #LOCATION = "R7P19" !CDS_LOCATION = "R7P19" #SEC = "1" !CDS_SEC = "1";
"A":   PN = "1"  !CDS_PN = "1";
"B":   PN = "2"  !CDS_PN = "2";
BODY = "RES","I116": #LOCATION = "R3D1" !CDS_LOCATION = "R3D1" #SEC = "1" !CDS_SEC = "1";
"A":   PN = "1"  !CDS_PN = "1";
"B":   PN = "2"  !CDS_PN = "2";
BODY = "RES","I117": #LOCATION = "R3D2" !CDS_LOCATION = "R3D2" #SEC = "1" !CDS_SEC = "1";
"A":   PN = "1"  !CDS_PN = "1";
"B":   PN = "2"  !CDS_PN = "2";
BODY = "RES","I118": #LOCATION = "R3D3" !CDS_LOCATION = "R3D3" #SEC = "1" !CDS_SEC = "1";
"A":   PN = "1"  !CDS_PN = "1";
"B":   PN = "2"  !CDS_PN = "2";
BODY = "RES","I119": #LOCATION = "R7P16" !CDS_LOCATION = "R7P16" #SEC = "1" !CDS_SEC = "1";
"A":   PN = "1"  !CDS_PN = "1";
"B":   PN = "2"  !CDS_PN = "2";
BODY = "RES","I123": #LOCATION = "R7P8" !CDS_LOCATION = "R7P8" #SEC = "1" !CDS_SEC = "1";
"A":   PN = "1"  !CDS_PN = "1";
"B":   PN = "2"  !CDS_PN = "2";
BODY = "RES","I124": #LOCATION = "R7P10" !CDS_LOCATION = "R7P10" #SEC = "1" !CDS_SEC = "1";
"A":   PN = "1"  !CDS_PN = "1";
"B":   PN = "2"  !CDS_PN = "2";
BODY = "RES","I125": #LOCATION = "R3D19" !CDS_LOCATION = "R3D19" #SEC = "1" !CDS_SEC = "1";
"A":   PN = "1"  !CDS_PN = "1";
"B":   PN = "2"  !CDS_PN = "2";
BODY = "RES","I126": #LOCATION = "R7P11" !CDS_LOCATION = "R7P11" #SEC = "1" !CDS_SEC = "1";
"A":   PN = "1"  !CDS_PN = "1";
"B":   PN = "2"  !CDS_PN = "2";
BODY = "RES","I140": #LOCATION = "R7P17" !CDS_LOCATION = "R7P17" #SEC = "1" !CDS_SEC = "1";
"A":   PN = "1"  !CDS_PN = "1";
"B":   PN = "2"  !CDS_PN = "2";
BODY = "SOCKET_P_MECH_A","I152": #LOCATION = "XRU2" !CDS_LOCATION = "XRU2";
BODY = "SOCKET_P_MECH_A","I153": #LOCATION = "XLU2" !CDS_LOCATION = "XLU2";
BODY = "RES","I155": #LOCATION = "R3D4" !CDS_LOCATION = "R3D4" #SEC = "1" !CDS_SEC = "1";
"A":   PN = "1"  !CDS_PN = "1";
"B":   PN = "2"  !CDS_PN = "2";
BODY = "RES","I156": #LOCATION = "R7P26" !CDS_LOCATION = "R7P26" #SEC = "1" !CDS_SEC = "1";
"A":   PN = "1"  !CDS_PN = "1";
"B":   PN = "2"  !CDS_PN = "2";
BODY = "RES","I157": #LOCATION = "R8N1" !CDS_LOCATION = "R8N1" #SEC = "1" !CDS_SEC = "1";
"A":   PN = "1"  !CDS_PN = "1";
"B":   PN = "2"  !CDS_PN = "2";
BODY = "RES","I158": #LOCATION = "R8N4" !CDS_LOCATION = "R8N4" #SEC = "1" !CDS_SEC = "1";
"A":   PN = "1"  !CDS_PN = "1";
"B":   PN = "2"  !CDS_PN = "2";
BODY = "RES","I159": #LOCATION = "R8N3" !CDS_LOCATION = "R8N3" #SEC = "1" !CDS_SEC = "1";
"A":   PN = "1"  !CDS_PN = "1";
"B":   PN = "2"  !CDS_PN = "2";
BODY = "RES","I160": #LOCATION = "R8N5" !CDS_LOCATION = "R8N5" #SEC = "1" !CDS_SEC = "1";
"A":   PN = "1"  !CDS_PN = "1";
"B":   PN = "2"  !CDS_PN = "2";
BODY = "RES","I161": #LOCATION = "R8N2" !CDS_LOCATION = "R8N2" #SEC = "1" !CDS_SEC = "1";
"A":   PN = "1"  !CDS_PN = "1";
"B":   PN = "2"  !CDS_PN = "2";
BODY = "RES","I170": #LOCATION = "R7P25" !CDS_LOCATION = "R7P25" #SEC = "1" !CDS_SEC = "1";
"A":   PN = "1"  !CDS_PN = "1";
"B":   PN = "2"  !CDS_PN = "2";
BODY = "SKX_EXT_B","I172": #LOCATION = "U2D1" !CDS_LOCATION = "U2D1" #SEC = "1" !CDS_SEC = "1";
"BCLK0_DN":   PN = "AU24"  !CDS_PN = "AU24";
"BCLK0_DP":   PN = "AW24"  !CDS_PN = "AW24";
"BCLK1_DN":   PN = "CR26"  !CDS_PN = "CR26";
"BCLK1_DP":   PN = "CP27"  !CDS_PN = "CP27";
"BCLK2_DN":   PN = "CT25"  !CDS_PN = "CT25";
"BCLK2_DP":   PN = "CU26"  !CDS_PN = "CU26";
"BIST_ENABLE":   PN = "BA20"  !CDS_PN = "BA20";
"BMCINIT":   PN = "BD23"  !CDS_PN = "BD23";
"BPM<0>_N":   PN = "AJ10"  !CDS_PN = "AJ10";
"BPM<1>_N":   PN = "AH11"  !CDS_PN = "AH11";
"BPM<2>_N":   PN = "AG10"  !CDS_PN = "AG10";
"BPM<3>_N":   PN = "AF11"  !CDS_PN = "AF11";
"BPM<4>_N":   PN = "AA12"  !CDS_PN = "AA12";
"BPM<5>_N":   PN = "Y11"  !CDS_PN = "Y11";
"BPM<6>_N":   PN = "AE12"  !CDS_PN = "AE12";
"BPM<7>_N":   PN = "AC12"  !CDS_PN = "AC12";
"CATERR_N":   PN = "AL14"  !CDS_PN = "AL14";
"DDR0_CAVREF":   PN = "AJ64"  !CDS_PN = "AJ64";
"DDR1_CAVREF":   PN = "AK63"  !CDS_PN = "AK63";
"DDR2_CAVREF":   PN = "AH63"  !CDS_PN = "AH63";
"DDR3_CAVREF":   PN = "CP61"  !CDS_PN = "CP61";
"DDR4_CAVREF":   PN = "CT61"  !CDS_PN = "CT61";
"DDR5_CAVREF":   PN = "CV61"  !CDS_PN = "CV61";
"DDR012_DRAM_PWR_OK":   PN = "AN30"  !CDS_PN = "AN30";
"DDR012_RCOMP<0>":   PN = "Y43"  !CDS_PN = "Y43";
"DDR012_RCOMP<1>":   PN = "AB43"  !CDS_PN = "AB43";
"DDR012_RCOMP<2>":   PN = "AC42"  !CDS_PN = "AC42";
"DDR012_RESET_N":   PN = "U64"  !CDS_PN = "U64";
"DDR012_SPDSCL":   PN = "AJ18"  !CDS_PN = "AJ18";
"DDR012_SPDSDA":   PN = "AF17"  !CDS_PN = "AF17";
"DDR345_DRAM_PWR_OK":   PN = "CR28"  !CDS_PN = "CR28";
"DDR345_RCOMP<0>":   PN = "DC48"  !CDS_PN = "DC48";
"DDR345_RCOMP<1>":   PN = "DD47"  !CDS_PN = "DD47";
"DDR345_RCOMP<2>":   PN = "DD49"  !CDS_PN = "DD49";
"DDR345_RESET_N":   PN = "DV63"  !CDS_PN = "DV63";
"DDR345_SPDSCL":   PN = "AE18"  !CDS_PN = "AE18";
"DDR345_SPDSDA":   PN = "AD17"  !CDS_PN = "AD17";
"EAR_N":   PN = "AJ14"  !CDS_PN = "AJ14";
"ERROR<0>_N":   PN = "AJ12"  !CDS_PN = "AJ12";
"ERROR<1>_N":   PN = "AK11"  !CDS_PN = "AK11";
"ERROR<2>_N":   PN = "AL12"  !CDS_PN = "AL12";
"FRMAGENT":   PN = "AV17"  !CDS_PN = "AV17";
"LEGACY_SKT":   PN = "AE20"  !CDS_PN = "AE20";
"MCP01_RBIAS<0>":   PN = "CU32"  !CDS_PN = "CU32";
"MCP01_RBIAS<1>":   PN = "CT31"  !CDS_PN = "CT31";
"MEM_HOT_C012_N":   PN = "AH13"  !CDS_PN = "AH13";
"MEM_HOT_C345_N":   PN = "AF13"  !CDS_PN = "AF13";
"MSMI_N":   PN = "AN20"  !CDS_PN = "AN20";
"NMI":   PN = "AP11"  !CDS_PN = "AP11";
"PE3_RBIAS<0>":   PN = "CP29"  !CDS_PN = "CP29";
"PE3_RBIAS<1>":   PN = "CR30"  !CDS_PN = "CR30";
"PE012_RBIAS<0>":   PN = "CN30"  !CDS_PN = "CN30";
"PE012_RBIAS<1>":   PN = "CL30"  !CDS_PN = "CL30";
"PE_HP_SCL":   PN = "AM19"  !CDS_PN = "AM19";
"PE_HP_SDA":   PN = "AL18"  !CDS_PN = "AL18";
"PECI":   PN = "AU12"  !CDS_PN = "AU12";
"PIROM_ADDR<0>":   PN = "CU58"  !CDS_PN = "CU58";
"PIROM_ADDR<1>":   PN = "CV57"  !CDS_PN = "CV57";
"PIROM_ADDR<2>":   PN = "CW56"  !CDS_PN = "CW56";
"PKGID<0>":   PN = "DC72"  !CDS_PN = "DC72";
"PKGID<1>":   PN = "CW72"  !CDS_PN = "CW72";
"PKGID<2>":   PN = "DA72"  !CDS_PN = "DA72";
"PM_FAST_WAKE_N":   PN = "AF15"  !CDS_PN = "AF15";
"PMSYNC":   PN = "AR14"  !CDS_PN = "AR14";
"PMSYNC_CLK":   PN = "AT19"  !CDS_PN = "AT19";
"PRDY_N":   PN = "AG16"  !CDS_PN = "AG16";
"PREQ_N":   PN = "AR12"  !CDS_PN = "AR12";
"PROC_ID<0>":   PN = "CY71"  !CDS_PN = "CY71";
"PROC_ID<1>":   PN = "DB71"  !CDS_PN = "DB71";
"PROCDIS_N":   PN = "AB17"  !CDS_PN = "AB17";
"PROCHOT_N":   PN = "AC16"  !CDS_PN = "AC16";
"PWRGOOD":   PN = "BC24"  !CDS_PN = "BC24";
"RESET_N":   PN = "AP21"  !CDS_PN = "AP21";
"SAFE_MODE_BOOT":   PN = "AR18"  !CDS_PN = "AR18";
"SKTOCC_N":   PN = "AB13"  !CDS_PN = "AB13";
"SM_WP":   PN = "CV59"  !CDS_PN = "CV59";
"SMBCLK":   PN = "CT59"  !CDS_PN = "CT59";
"SMBDAT":   PN = "CW58"  !CDS_PN = "CW58";
"SOCKET_ID<0>":   PN = "AU22"  !CDS_PN = "AU22";
"SOCKET_ID<1>":   PN = "AU16"  !CDS_PN = "AU16";
"SOCKET_ID<2>":   PN = "AU20"  !CDS_PN = "AU20";
"SVIDALERT<0>_N":   PN = "DE44"  !CDS_PN = "DE44";
"SVIDALERT<1>_N":   PN = "DL44"  !CDS_PN = "DL44";
"SVIDCLK<0>":   PN = "DC44"  !CDS_PN = "DC44";
"SVIDCLK<1>":   PN = "DG44"  !CDS_PN = "DG44";
"SVIDDATA<0>":   PN = "DB45"  !CDS_PN = "DB45";
"SVIDDATA<1>":   PN = "DJ44"  !CDS_PN = "DJ44";
"TCK":   PN = "AA14"  !CDS_PN = "AA14";
"TDI":   PN = "AC14"  !CDS_PN = "AC14";
"TDO":   PN = "AE14"  !CDS_PN = "AE14";
"TEST_12":   PN = "AY19"  !CDS_PN = "AY19";
"TEST_13":   PN = "DB51"  !CDS_PN = "DB51";
"TEST_14":   PN = "DC50"  !CDS_PN = "DC50";
"TEST_15":   PN = "AW14"  !CDS_PN = "AW14";
"THERMTRIP_N":   PN = "AB15"  !CDS_PN = "AB15";
"TMS":   PN = "W14"  !CDS_PN = "W14";
"TRST_N":   PN = "Y13"  !CDS_PN = "Y13";
"TSC_SYNC":   PN = "AM11"  !CDS_PN = "AM11";
"TXT_AGENT":   PN = "AW18"  !CDS_PN = "AW18";
"TXT_PLTEN":   PN = "AV15"  !CDS_PN = "AV15";
"UPI01_RBIAS<0>":   PN = "AT29"  !CDS_PN = "AT29";
"UPI01_RBIAS<1>":   PN = "AP29"  !CDS_PN = "AP29";
"UPI2_RBIAS<0>":   PN = "CL28"  !CDS_PN = "CL28";
"UPI2_RBIAS<1>":   PN = "CK29"  !CDS_PN = "CK29";
BODY = "RES","I181": #LOCATION = "R6P39" !CDS_LOCATION = "R6P39" #SEC = "1" !CDS_SEC = "1";
"A":   PN = "1"  !CDS_PN = "1";
"B":   PN = "2"  !CDS_PN = "2";
DRAWING = "@baseboard_fab2_lib.baseboard_fab2(sch_1):page56";
BODY = "SKX_EXT_B","I169": #LOCATION = "U2D1" !CDS_LOCATION = "U2D1" #SEC = "2" !CDS_SEC = "2";
"DEBUG_EN_N":   PN = "AV21"  !CDS_PN = "AV21";
"DMIMODE_OVERRIDE":   PN = "AW12"  !CDS_PN = "AW12";
"FIVR_FAULT":   PN = "AU14"  !CDS_PN = "AU14";
"PWR_DEBUG_N":   PN = "AP17"  !CDS_PN = "AP17";
"RSVD<194>":   PN = "AP61"  !CDS_PN = "AP61";
"RSVD<195>":   PN = "AP27"  !CDS_PN = "AP27";
"RSVD<196>":   PN = "AP25"  !CDS_PN = "AP25";
"RSVD<197>":   PN = "AP23"  !CDS_PN = "AP23";
"RSVD<198>":   PN = "AN62"  !CDS_PN = "AN62";
"RSVD<199>":   PN = "AN60"  !CDS_PN = "AN60";
"RSVD<200>":   PN = "AN26"  !CDS_PN = "AN26";
"RSVD<201>":   PN = "AN24"  !CDS_PN = "AN24";
"RSVD<202>":   PN = "AN22"  !CDS_PN = "AN22";
"RSVD<203>":   PN = "AN18"  !CDS_PN = "AN18";
"RSVD<204>":   PN = "AM61"  !CDS_PN = "AM61";
"RSVD<205>":   PN = "AM59"  !CDS_PN = "AM59";
"RSVD<206>":   PN = "AM27"  !CDS_PN = "AM27";
"RSVD<207>":   PN = "AM25"  !CDS_PN = "AM25";
"RSVD<208>":   PN = "AM23"  !CDS_PN = "AM23";
"RSVD<209>":   PN = "AM21"  !CDS_PN = "AM21";
"RSVD<210>":   PN = "AL62"  !CDS_PN = "AL62";
"RSVD<211>":   PN = "AL60"  !CDS_PN = "AL60";
"RSVD<212>":   PN = "AL58"  !CDS_PN = "AL58";
"RSVD<213>":   PN = "AL26"  !CDS_PN = "AL26";
"RSVD<214>":   PN = "AL22"  !CDS_PN = "AL22";
"RSVD<215>":   PN = "AL20"  !CDS_PN = "AL20";
"RSVD<216>":   PN = "AK69"  !CDS_PN = "AK69";
"RSVD<217>":   PN = "AK61"  !CDS_PN = "AK61";
"RSVD<218>":   PN = "AK59"  !CDS_PN = "AK59";
"RSVD<219>":   PN = "AK57"  !CDS_PN = "AK57";
"RSVD<220>":   PN = "AK27"  !CDS_PN = "AK27";
"RSVD<221>":   PN = "AK21"  !CDS_PN = "AK21";
"RSVD<222>":   PN = "AJ70"  !CDS_PN = "AJ70";
"RSVD<223>":   PN = "AJ62"  !CDS_PN = "AJ62";
"RSVD<224>":   PN = "AJ60"  !CDS_PN = "AJ60";
"RSVD<225>":   PN = "AJ58"  !CDS_PN = "AJ58";
"RSVD<226>":   PN = "AJ56"  !CDS_PN = "AJ56";
"RSVD<227>":   PN = "AJ20"  !CDS_PN = "AJ20";
"RSVD<228>":   PN = "AH73"  !CDS_PN = "AH73";
"RSVD<229>":   PN = "AH71"  !CDS_PN = "AH71";
"RSVD<230>":   PN = "AH57"  !CDS_PN = "AH57";
"RSVD<231>":   PN = "AH55"  !CDS_PN = "AH55";
"RSVD<232>":   PN = "AH19"  !CDS_PN = "AH19";
"RSVD<233>":   PN = "AH15"  !CDS_PN = "AH15";
"RSVD<234>":   PN = "AG72"  !CDS_PN = "AG72";
"RSVD<235>":   PN = "AG56"  !CDS_PN = "AG56";
"RSVD<236>":   PN = "AG54"  !CDS_PN = "AG54";
"RSVD<237>":   PN = "AG52"  !CDS_PN = "AG52";
"RSVD<238>":   PN = "AG50"  !CDS_PN = "AG50";
"RSVD<239>":   PN = "AG48"  !CDS_PN = "AG48";
"RSVD<240>":   PN = "AG20"  !CDS_PN = "AG20";
"RSVD<241>":   PN = "AF71"  !CDS_PN = "AF71";
"RSVD<242>":   PN = "AF53"  !CDS_PN = "AF53";
"RSVD<243>":   PN = "AF51"  !CDS_PN = "AF51";
"RSVD<244>":   PN = "AF49"  !CDS_PN = "AF49";
"RSVD<245>":   PN = "AF47"  !CDS_PN = "AF47";
"RSVD<246>":   PN = "AF19"  !CDS_PN = "AF19";
"RSVD<247>":   PN = "AE72"  !CDS_PN = "AE72";
"RSVD<248>":   PN = "AE52"  !CDS_PN = "AE52";
"RSVD<249>":   PN = "AE50"  !CDS_PN = "AE50";
"RSVD<250>":   PN = "AE48"  !CDS_PN = "AE48";
"RSVD<251>":   PN = "AE46"  !CDS_PN = "AE46";
"RSVD<252>":   PN = "AD51"  !CDS_PN = "AD51";
"RSVD<253>":   PN = "AD49"  !CDS_PN = "AD49";
"RSVD<254>":   PN = "AD47"  !CDS_PN = "AD47";
"RSVD<256>":   PN = "Y65"  !CDS_PN = "Y65";
"RSVD<257>":   PN = "Y23"  !CDS_PN = "Y23";
"RSVD<258>":   PN = "W66"  !CDS_PN = "W66";
"RSVD<259>":   PN = "V67"  !CDS_PN = "V67";
"RSVD<260>":   PN = "V65"  !CDS_PN = "V65";
"RSVD<261>":   PN = "U66"  !CDS_PN = "U66";
"RSVD<262>":   PN = "T67"  !CDS_PN = "T67";
"RSVD<263>":   PN = "R66"  !CDS_PN = "R66";
"RSVD<264>":   PN = "R62"  !CDS_PN = "R62";
"RSVD<265>":   PN = "P65"  !CDS_PN = "P65";
"RSVD<266>":   PN = "M63"  !CDS_PN = "M63";
"RSVD<267>":   PN = "K61"  !CDS_PN = "K61";
"RSVD<268>":   PN = "J62"  !CDS_PN = "J62";
"RSVD<269>":   PN = "J46"  !CDS_PN = "J46";
"RSVD<270>":   PN = "H85"  !CDS_PN = "H85";
"RSVD<271>":   PN = "H83"  !CDS_PN = "H83";
"RSVD<272>":   PN = "H1"  !CDS_PN = "H1";
"RSVD<273>":   PN = "G84"  !CDS_PN = "G84";
"RSVD<274>":   PN = "G64"  !CDS_PN = "G64";
"RSVD<275>":   PN = "G2"  !CDS_PN = "G2";
"RSVD<276>":   PN = "F83"  !CDS_PN = "F83";
"RSVD<277>":   PN = "F65"  !CDS_PN = "F65";
"RSVD<278>":   PN = "F23"  !CDS_PN = "F23";
"RSVD<279>":   PN = "F3"  !CDS_PN = "F3";
"RSVD<280>":   PN = "E84"  !CDS_PN = "E84";
"RSVD<281>":   PN = "E24"  !CDS_PN = "E24";
"RSVD<282>":   PN = "E4"  !CDS_PN = "E4";
"RSVD<283>":   PN = "E2"  !CDS_PN = "E2";
"RSVD<284>":   PN = "D83"  !CDS_PN = "D83";
"RSVD<285>":   PN = "D65"  !CDS_PN = "D65";
"RSVD<286>":   PN = "D17"  !CDS_PN = "D17";
"RSVD<287>":   PN = "D5"  !CDS_PN = "D5";
"RSVD<288>":   PN = "C82"  !CDS_PN = "C82";
"RSVD<289>":   PN = "C24"  !CDS_PN = "C24";
"RSVD<290>":   PN = "C18"  !CDS_PN = "C18";
"RSVD<291>":   PN = "C6"  !CDS_PN = "C6";
"RSVD<292>":   PN = "B81"  !CDS_PN = "B81";
"RSVD<293>":   PN = "B77"  !CDS_PN = "B77";
"RSVD<294>":   PN = "B17"  !CDS_PN = "B17";
"RSVD<295>":   PN = "B15"  !CDS_PN = "B15";
"RSVD<296>":   PN = "B13"  !CDS_PN = "B13";
"RSVD<298>":   PN = "B7"  !CDS_PN = "B7";
"RSVD<299>":   PN = "B3"  !CDS_PN = "B3";
"RSVD<300>":   PN = "A24"  !CDS_PN = "A24";
"RSVD<301>":   PN = "A16"  !CDS_PN = "A16";
"RSVD<302>":   PN = "A14"  !CDS_PN = "A14";
"RSVD<303>":   PN = "A6"  !CDS_PN = "A6";
"RSVD<304>":   PN = "A4"  !CDS_PN = "A4";
"TEST_1":   PN = "AF45"  !CDS_PN = "AF45";
"TEST_2":   PN = "AG46"  !CDS_PN = "AG46";
"TEST_3":   PN = "AM13"  !CDS_PN = "AM13";
"TEST_4":   PN = "AN12"  !CDS_PN = "AN12";
"TEST_5":   PN = "AN14"  !CDS_PN = "AN14";
"TEST_11":   PN = "AY13"  !CDS_PN = "AY13";
BODY = "RES","I173": #LOCATION = "R8P3" !CDS_LOCATION = "R8P3" #SEC = "1" !CDS_SEC = "1";
"A":   PN = "1"  !CDS_PN = "1";
"B":   PN = "2"  !CDS_PN = "2";
BODY = "RES","I174": #LOCATION = "R8R1" !CDS_LOCATION = "R8R1" #SEC = "1" !CDS_SEC = "1";
"A":   PN = "1"  !CDS_PN = "1";
"B":   PN = "2"  !CDS_PN = "2";
DRAWING = "@baseboard_fab2_lib.baseboard_fab2(sch_1):page57";
BODY = "SKX_EXT_B","I172": #LOCATION = "U2D1" !CDS_LOCATION = "U2D1" #SEC = "3" !CDS_SEC = "3";
"DDR0_ACT_N":   PN = "J60"  !CDS_PN = "J60";
"DDR0_ALERT_N":   PN = "B61"  !CDS_PN = "B61";
"DDR0_BA<0>":   PN = "C52"  !CDS_PN = "C52";
"DDR0_BA<1>":   PN = "G54"  !CDS_PN = "G54";
"DDR0_BG<0>":   PN = "D61"  !CDS_PN = "D61";
"DDR0_BG<1>":   PN = "F63"  !CDS_PN = "F63";
"DDR0_CID<2>":   PN = "G46"  !CDS_PN = "G46";
"DDR0_CKE<0>":   PN = "C62"  !CDS_PN = "C62";
"DDR0_CKE<1>":   PN = "C64"  !CDS_PN = "C64";
"DDR0_CKE<2>":   PN = "B63"  !CDS_PN = "B63";
"DDR0_CKE<3>":   PN = "D63"  !CDS_PN = "D63";
"DDR0_CLK_DN<0>":   PN = "F55"  !CDS_PN = "F55";
"DDR0_CLK_DN<1>":   PN = "C54"  !CDS_PN = "C54";
"DDR0_CLK_DN<2>":   PN = "J56"  !CDS_PN = "J56";
"DDR0_CLK_DN<3>":   PN = "C56"  !CDS_PN = "C56";
"DDR0_CLK_DP<0>":   PN = "D55"  !CDS_PN = "D55";
"DDR0_CLK_DP<1>":   PN = "B55"  !CDS_PN = "B55";
"DDR0_CLK_DP<2>":   PN = "G56"  !CDS_PN = "G56";
"DDR0_CLK_DP<3>":   PN = "B57"  !CDS_PN = "B57";
"DDR0_CS<0>_N":   PN = "G52"  !CDS_PN = "G52";
"DDR0_CS<1>_N":   PN = "F49"  !CDS_PN = "F49";
"DDR0_CS<2>_N":   PN = "D47"  !CDS_PN = "D47";
"DDR0_CS<3>_N":   PN = "F47"  !CDS_PN = "F47";
"DDR0_CS<4>_N":   PN = "B51"  !CDS_PN = "B51";
"DDR0_CS<5>_N":   PN = "D49"  !CDS_PN = "D49";
"DDR0_CS<6>_N":   PN = "F45"  !CDS_PN = "F45";
"DDR0_CS<7>_N":   PN = "K45"  !CDS_PN = "K45";
"DDR0_DQ<0>":   PN = "AN86"  !CDS_PN = "AN86";
"DDR0_DQ<1>":   PN = "AN84"  !CDS_PN = "AN84";
"DDR0_DQ<2>":   PN = "AE86"  !CDS_PN = "AE86";
"DDR0_DQ<3>":   PN = "AE84"  !CDS_PN = "AE84";
"DDR0_DQ<4>":   PN = "AR86"  !CDS_PN = "AR86";
"DDR0_DQ<5>":   PN = "AR84"  !CDS_PN = "AR84";
"DDR0_DQ<6>":   PN = "AG86"  !CDS_PN = "AG86";
"DDR0_DQ<7>":   PN = "AG84"  !CDS_PN = "AG84";
"DDR0_DQ<8>":   PN = "W86"  !CDS_PN = "W86";
"DDR0_DQ<9>":   PN = "W84"  !CDS_PN = "W84";
"DDR0_DQ<10>":   PN = "L86"  !CDS_PN = "L86";
"DDR0_DQ<11>":   PN = "L84"  !CDS_PN = "L84";
"DDR0_DQ<12>":   PN = "AA86"  !CDS_PN = "AA86";
"DDR0_DQ<13>":   PN = "AA84"  !CDS_PN = "AA84";
"DDR0_DQ<14>":   PN = "N86"  !CDS_PN = "N86";
"DDR0_DQ<15>":   PN = "N84"  !CDS_PN = "N84";
"DDR0_DQ<16>":   PN = "V81"  !CDS_PN = "V81";
"DDR0_DQ<17>":   PN = "T79"  !CDS_PN = "T79";
"DDR0_DQ<18>":   PN = "N82"  !CDS_PN = "N82";
"DDR0_DQ<19>":   PN = "M81"  !CDS_PN = "M81";
"DDR0_DQ<20>":   PN = "W80"  !CDS_PN = "W80";
"DDR0_DQ<21>":   PN = "V79"  !CDS_PN = "V79";
"DDR0_DQ<22>":   PN = "R82"  !CDS_PN = "R82";
"DDR0_DQ<23>":   PN = "N80"  !CDS_PN = "N80";
"DDR0_DQ<24>":   PN = "L76"  !CDS_PN = "L76";
"DDR0_DQ<25>":   PN = "R76"  !CDS_PN = "R76";
"DDR0_DQ<26>":   PN = "M73"  !CDS_PN = "M73";
"DDR0_DQ<27>":   PN = "P73"  !CDS_PN = "P73";
"DDR0_DQ<28>":   PN = "M77"  !CDS_PN = "M77";
"DDR0_DQ<29>":   PN = "P77"  !CDS_PN = "P77";
"DDR0_DQ<30>":   PN = "L74"  !CDS_PN = "L74";
"DDR0_DQ<31>":   PN = "R74"  !CDS_PN = "R74";
"DDR0_DQ<32>":   PN = "C42"  !CDS_PN = "C42";
"DDR0_DQ<33>":   PN = "B41"  !CDS_PN = "B41";
"DDR0_DQ<34>":   PN = "C38"  !CDS_PN = "C38";
"DDR0_DQ<35>":   PN = "E38"  !CDS_PN = "E38";
"DDR0_DQ<36>":   PN = "E42"  !CDS_PN = "E42";
"DDR0_DQ<37>":   PN = "F41"  !CDS_PN = "F41";
"DDR0_DQ<38>":   PN = "B39"  !CDS_PN = "B39";
"DDR0_DQ<39>":   PN = "F39"  !CDS_PN = "F39";
"DDR0_DQ<40>":   PN = "K37"  !CDS_PN = "K37";
"DDR0_DQ<41>":   PN = "P37"  !CDS_PN = "P37";
"DDR0_DQ<42>":   PN = "L34"  !CDS_PN = "L34";
"DDR0_DQ<43>":   PN = "N34"  !CDS_PN = "N34";
"DDR0_DQ<44>":   PN = "L38"  !CDS_PN = "L38";
"DDR0_DQ<45>":   PN = "N38"  !CDS_PN = "N38";
"DDR0_DQ<46>":   PN = "K35"  !CDS_PN = "K35";
"DDR0_DQ<47>":   PN = "P35"  !CDS_PN = "P35";
"DDR0_DQ<48>":   PN = "K31"  !CDS_PN = "K31";
"DDR0_DQ<49>":   PN = "P31"  !CDS_PN = "P31";
"DDR0_DQ<50>":   PN = "L28"  !CDS_PN = "L28";
"DDR0_DQ<51>":   PN = "N28"  !CDS_PN = "N28";
"DDR0_DQ<52>":   PN = "L32"  !CDS_PN = "L32";
"DDR0_DQ<53>":   PN = "N32"  !CDS_PN = "N32";
"DDR0_DQ<54>":   PN = "K29"  !CDS_PN = "K29";
"DDR0_DQ<55>":   PN = "P29"  !CDS_PN = "P29";
"DDR0_DQ<56>":   PN = "K25"  !CDS_PN = "K25";
"DDR0_DQ<57>":   PN = "P25"  !CDS_PN = "P25";
"DDR0_DQ<58>":   PN = "P23"  !CDS_PN = "P23";
"DDR0_DQ<59>":   PN = "T23"  !CDS_PN = "T23";
"DDR0_DQ<60>":   PN = "L26"  !CDS_PN = "L26";
"DDR0_DQ<61>":   PN = "N26"  !CDS_PN = "N26";
"DDR0_DQ<62>":   PN = "H23"  !CDS_PN = "H23";
"DDR0_DQ<63>":   PN = "K23"  !CDS_PN = "K23";
"DDR0_DQS_DN<0>":   PN = "AJ84"  !CDS_PN = "AJ84";
"DDR0_DQS_DN<1>":   PN = "R84"  !CDS_PN = "R84";
"DDR0_DQS_DN<2>":   PN = "P79"  !CDS_PN = "P79";
"DDR0_DQS_DN<3>":   PN = "T75"  !CDS_PN = "T75";
"DDR0_DQS_DN<4>":   PN = "G40"  !CDS_PN = "G40";
"DDR0_DQS_DN<5>":   PN = "R36"  !CDS_PN = "R36";
"DDR0_DQS_DN<6>":   PN = "R30"  !CDS_PN = "R30";
"DDR0_DQS_DN<7>":   PN = "N24"  !CDS_PN = "N24";
"DDR0_DQS_DN<8>":   PN = "AH67"  !CDS_PN = "AH67";
"DDR0_DQS_DN<9>":   PN = "AL84"  !CDS_PN = "AL84";
"DDR0_DQS_DN<10>":   PN = "U84"  !CDS_PN = "U84";
"DDR0_DQS_DN<11>":   PN = "U82"  !CDS_PN = "U82";
"DDR0_DQS_DN<12>":   PN = "K75"  !CDS_PN = "K75";
"DDR0_DQS_DN<13>":   PN = "A40"  !CDS_PN = "A40";
"DDR0_DQS_DN<14>":   PN = "J36"  !CDS_PN = "J36";
"DDR0_DQS_DN<15>":   PN = "J30"  !CDS_PN = "J30";
"DDR0_DQS_DN<16>":   PN = "J24"  !CDS_PN = "J24";
"DDR0_DQS_DN<17>":   PN = "AB67"  !CDS_PN = "AB67";
"DDR0_DQS_DP<0>":   PN = "AH85"  !CDS_PN = "AH85";
"DDR0_DQS_DP<1>":   PN = "P85"  !CDS_PN = "P85";
"DDR0_DQS_DP<2>":   PN = "R80"  !CDS_PN = "R80";
"DDR0_DQS_DP<3>":   PN = "P75"  !CDS_PN = "P75";
"DDR0_DQS_DP<4>":   PN = "E40"  !CDS_PN = "E40";
"DDR0_DQS_DP<5>":   PN = "N36"  !CDS_PN = "N36";
"DDR0_DQS_DP<6>":   PN = "N30"  !CDS_PN = "N30";
"DDR0_DQS_DP<7>":   PN = "R24"  !CDS_PN = "R24";
"DDR0_DQS_DP<8>":   PN = "AF67"  !CDS_PN = "AF67";
"DDR0_DQS_DP<9>":   PN = "AM85"  !CDS_PN = "AM85";
"DDR0_DQS_DP<10>":   PN = "V85"  !CDS_PN = "V85";
"DDR0_DQS_DP<11>":   PN = "T81"  !CDS_PN = "T81";
"DDR0_DQS_DP<12>":   PN = "M75"  !CDS_PN = "M75";
"DDR0_DQS_DP<13>":   PN = "C40"  !CDS_PN = "C40";
"DDR0_DQS_DP<14>":   PN = "L36"  !CDS_PN = "L36";
"DDR0_DQS_DP<15>":   PN = "L30"  !CDS_PN = "L30";
"DDR0_DQS_DP<16>":   PN = "L24"  !CDS_PN = "L24";
"DDR0_DQS_DP<17>":   PN = "AD67"  !CDS_PN = "AD67";
"DDR0_ECC<0>":   PN = "AC68"  !CDS_PN = "AC68";
"DDR0_ECC<1>":   PN = "AG68"  !CDS_PN = "AG68";
"DDR0_ECC<2>":   PN = "AD65"  !CDS_PN = "AD65";
"DDR0_ECC<3>":   PN = "AF65"  !CDS_PN = "AF65";
"DDR0_ECC<4>":   PN = "AD69"  !CDS_PN = "AD69";
"DDR0_ECC<5>":   PN = "AF69"  !CDS_PN = "AF69";
"DDR0_ECC<6>":   PN = "AC66"  !CDS_PN = "AC66";
"DDR0_ECC<7>":   PN = "AG66"  !CDS_PN = "AG66";
"DDR0_MA<0>":   PN = "F53"  !CDS_PN = "F53";
"DDR0_MA<1>":   PN = "F57"  !CDS_PN = "F57";
"DDR0_MA<2>":   PN = "D57"  !CDS_PN = "D57";
"DDR0_MA<3>":   PN = "C58"  !CDS_PN = "C58";
"DDR0_MA<4>":   PN = "G58"  !CDS_PN = "G58";
"DDR0_MA<5>":   PN = "F59"  !CDS_PN = "F59";
"DDR0_MA<6>":   PN = "D59"  !CDS_PN = "D59";
"DDR0_MA<7>":   PN = "G60"  !CDS_PN = "G60";
"DDR0_MA<8>":   PN = "C60"  !CDS_PN = "C60";
"DDR0_MA<9>":   PN = "F61"  !CDS_PN = "F61";
"DDR0_MA<10>":   PN = "J54"  !CDS_PN = "J54";
"DDR0_MA<11>":   PN = "G62"  !CDS_PN = "G62";
"DDR0_MA<12>":   PN = "J64"  !CDS_PN = "J64";
"DDR0_MA<13>":   PN = "J48"  !CDS_PN = "J48";
"DDR0_MA<14>":   PN = "F51"  !CDS_PN = "F51";
"DDR0_MA<15>":   PN = "K49"  !CDS_PN = "K49";
"DDR0_MA<16>":   PN = "D51"  !CDS_PN = "D51";
"DDR0_MA<17>":   PN = "K47"  !CDS_PN = "K47";
"DDR0_ODT<0>":   PN = "C50"  !CDS_PN = "C50";
"DDR0_ODT<1>":   PN = "C48"  !CDS_PN = "C48";
"DDR0_ODT<2>":   PN = "G50"  !CDS_PN = "G50";
"DDR0_ODT<3>":   PN = "G48"  !CDS_PN = "G48";
"DDR0_PAR":   PN = "D53"  !CDS_PN = "D53";
DRAWING = "@baseboard_fab2_lib.baseboard_fab2(sch_1):page58";
BODY = "SKX_EXT_B","I172": #LOCATION = "U2D1" !CDS_LOCATION = "U2D1" #SEC = "4" !CDS_SEC = "4";
"DDR1_ACT_N":   PN = "T63"  !CDS_PN = "T63";
"DDR1_ALERT_N":   PN = "W62"  !CDS_PN = "W62";
"DDR1_BA<0>":   PN = "T53"  !CDS_PN = "T53";
"DDR1_BA<1>":   PN = "K55"  !CDS_PN = "K55";
"DDR1_BG<0>":   PN = "M61"  !CDS_PN = "M61";
"DDR1_BG<1>":   PN = "N60"  !CDS_PN = "N60";
"DDR1_CID<2>":   PN = "M47"  !CDS_PN = "M47";
"DDR1_CKE<0>":   PN = "N62"  !CDS_PN = "N62";
"DDR1_CKE<1>":   PN = "R64"  !CDS_PN = "R64";
"DDR1_CKE<2>":   PN = "K63"  !CDS_PN = "K63";
"DDR1_CKE<3>":   PN = "L64"  !CDS_PN = "L64";
"DDR1_CLK_DN<0>":   PN = "M53"  !CDS_PN = "M53";
"DDR1_CLK_DN<1>":   PN = "R54"  !CDS_PN = "R54";
"DDR1_CLK_DN<2>":   PN = "N56"  !CDS_PN = "N56";
"DDR1_CLK_DN<3>":   PN = "R56"  !CDS_PN = "R56";
"DDR1_CLK_DP<0>":   PN = "N54"  !CDS_PN = "N54";
"DDR1_CLK_DP<1>":   PN = "T55"  !CDS_PN = "T55";
"DDR1_CLK_DP<2>":   PN = "M57"  !CDS_PN = "M57";
"DDR1_CLK_DP<3>":   PN = "T57"  !CDS_PN = "T57";
"DDR1_CS<0>_N":   PN = "K51"  !CDS_PN = "K51";
"DDR1_CS<1>_N":   PN = "R50"  !CDS_PN = "R50";
"DDR1_CS<2>_N":   PN = "N46"  !CDS_PN = "N46";
"DDR1_CS<3>_N":   PN = "V47"  !CDS_PN = "V47";
"DDR1_CS<4>_N":   PN = "J50"  !CDS_PN = "J50";
"DDR1_CS<5>_N":   PN = "T49"  !CDS_PN = "T49";
"DDR1_CS<6>_N":   PN = "M45"  !CDS_PN = "M45";
"DDR1_CS<7>_N":   PN = "R46"  !CDS_PN = "R46";
"DDR1_DQ<0>":   PN = "AV81"  !CDS_PN = "AV81";
"DDR1_DQ<1>":   PN = "AT79"  !CDS_PN = "AT79";
"DDR1_DQ<2>":   PN = "AN82"  !CDS_PN = "AN82";
"DDR1_DQ<3>":   PN = "AM81"  !CDS_PN = "AM81";
"DDR1_DQ<4>":   PN = "AW80"  !CDS_PN = "AW80";
"DDR1_DQ<5>":   PN = "AV79"  !CDS_PN = "AV79";
"DDR1_DQ<6>":   PN = "AR82"  !CDS_PN = "AR82";
"DDR1_DQ<7>":   PN = "AN80"  !CDS_PN = "AN80";
"DDR1_DQ<8>":   PN = "AH81"  !CDS_PN = "AH81";
"DDR1_DQ<9>":   PN = "AF79"  !CDS_PN = "AF79";
"DDR1_DQ<10>":   PN = "AC82"  !CDS_PN = "AC82";
"DDR1_DQ<11>":   PN = "AB81"  !CDS_PN = "AB81";
"DDR1_DQ<12>":   PN = "AJ80"  !CDS_PN = "AJ80";
"DDR1_DQ<13>":   PN = "AH79"  !CDS_PN = "AH79";
"DDR1_DQ<14>":   PN = "AE82"  !CDS_PN = "AE82";
"DDR1_DQ<15>":   PN = "AC80"  !CDS_PN = "AC80";
"DDR1_DQ<16>":   PN = "E80"  !CDS_PN = "E80";
"DDR1_DQ<17>":   PN = "J80"  !CDS_PN = "J80";
"DDR1_DQ<18>":   PN = "F77"  !CDS_PN = "F77";
"DDR1_DQ<19>":   PN = "H77"  !CDS_PN = "H77";
"DDR1_DQ<20>":   PN = "F81"  !CDS_PN = "F81";
"DDR1_DQ<21>":   PN = "H81"  !CDS_PN = "H81";
"DDR1_DQ<22>":   PN = "E78"  !CDS_PN = "E78";
"DDR1_DQ<23>":   PN = "J78"  !CDS_PN = "J78";
"DDR1_DQ<24>":   PN = "D75"  !CDS_PN = "D75";
"DDR1_DQ<25>":   PN = "C74"  !CDS_PN = "C74";
"DDR1_DQ<26>":   PN = "D71"  !CDS_PN = "D71";
"DDR1_DQ<27>":   PN = "F71"  !CDS_PN = "F71";
"DDR1_DQ<28>":   PN = "F75"  !CDS_PN = "F75";
"DDR1_DQ<29>":   PN = "G74"  !CDS_PN = "G74";
"DDR1_DQ<30>":   PN = "C72"  !CDS_PN = "C72";
"DDR1_DQ<31>":   PN = "G72"  !CDS_PN = "G72";
"DDR1_DQ<32>":   PN = "K43"  !CDS_PN = "K43";
"DDR1_DQ<33>":   PN = "H43"  !CDS_PN = "H43";
"DDR1_DQ<34>":   PN = "L40"  !CDS_PN = "L40";
"DDR1_DQ<35>":   PN = "N40"  !CDS_PN = "N40";
"DDR1_DQ<36>":   PN = "P43"  !CDS_PN = "P43";
"DDR1_DQ<37>":   PN = "T43"  !CDS_PN = "T43";
"DDR1_DQ<38>":   PN = "K41"  !CDS_PN = "K41";
"DDR1_DQ<39>":   PN = "P41"  !CDS_PN = "P41";
"DDR1_DQ<40>":   PN = "C36"  !CDS_PN = "C36";
"DDR1_DQ<41>":   PN = "B35"  !CDS_PN = "B35";
"DDR1_DQ<42>":   PN = "C32"  !CDS_PN = "C32";
"DDR1_DQ<43>":   PN = "E32"  !CDS_PN = "E32";
"DDR1_DQ<44>":   PN = "E36"  !CDS_PN = "E36";
"DDR1_DQ<45>":   PN = "F35"  !CDS_PN = "F35";
"DDR1_DQ<46>":   PN = "B33"  !CDS_PN = "B33";
"DDR1_DQ<47>":   PN = "F33"  !CDS_PN = "F33";
"DDR1_DQ<48>":   PN = "C30"  !CDS_PN = "C30";
"DDR1_DQ<49>":   PN = "B29"  !CDS_PN = "B29";
"DDR1_DQ<50>":   PN = "C26"  !CDS_PN = "C26";
"DDR1_DQ<51>":   PN = "E26"  !CDS_PN = "E26";
"DDR1_DQ<52>":   PN = "E30"  !CDS_PN = "E30";
"DDR1_DQ<53>":   PN = "F29"  !CDS_PN = "F29";
"DDR1_DQ<54>":   PN = "B27"  !CDS_PN = "B27";
"DDR1_DQ<55>":   PN = "F27"  !CDS_PN = "F27";
"DDR1_DQ<56>":   PN = "U28"  !CDS_PN = "U28";
"DDR1_DQ<57>":   PN = "AA28"  !CDS_PN = "AA28";
"DDR1_DQ<58>":   PN = "V25"  !CDS_PN = "V25";
"DDR1_DQ<59>":   PN = "Y25"  !CDS_PN = "Y25";
"DDR1_DQ<60>":   PN = "V29"  !CDS_PN = "V29";
"DDR1_DQ<61>":   PN = "Y29"  !CDS_PN = "Y29";
"DDR1_DQ<62>":   PN = "U26"  !CDS_PN = "U26";
"DDR1_DQ<63>":   PN = "AA26"  !CDS_PN = "AA26";
"DDR1_DQS_DN<0>":   PN = "AP79"  !CDS_PN = "AP79";
"DDR1_DQS_DN<1>":   PN = "AD79"  !CDS_PN = "AD79";
"DDR1_DQS_DN<2>":   PN = "K79"  !CDS_PN = "K79";
"DDR1_DQS_DN<3>":   PN = "H73"  !CDS_PN = "H73";
"DDR1_DQS_DN<4>":   PN = "N42"  !CDS_PN = "N42";
"DDR1_DQS_DN<5>":   PN = "G34"  !CDS_PN = "G34";
"DDR1_DQS_DN<6>":   PN = "G28"  !CDS_PN = "G28";
"DDR1_DQS_DN<7>":   PN = "AB27"  !CDS_PN = "AB27";
"DDR1_DQS_DN<8>":   PN = "N68"  !CDS_PN = "N68";
"DDR1_DQS_DN<9>":   PN = "AU82"  !CDS_PN = "AU82";
"DDR1_DQS_DN<10>":   PN = "AG82"  !CDS_PN = "AG82";
"DDR1_DQS_DN<11>":   PN = "D79"  !CDS_PN = "D79";
"DDR1_DQS_DN<12>":   PN = "B73"  !CDS_PN = "B73";
"DDR1_DQS_DN<13>":   PN = "J42"  !CDS_PN = "J42";
"DDR1_DQS_DN<14>":   PN = "A34"  !CDS_PN = "A34";
"DDR1_DQS_DN<15>":   PN = "A28"  !CDS_PN = "A28";
"DDR1_DQS_DN<16>":   PN = "T27"  !CDS_PN = "T27";
"DDR1_DQS_DN<17>":   PN = "G68"  !CDS_PN = "G68";
"DDR1_DQS_DP<0>":   PN = "AR80"  !CDS_PN = "AR80";
"DDR1_DQS_DP<1>":   PN = "AE80"  !CDS_PN = "AE80";
"DDR1_DQS_DP<2>":   PN = "H79"  !CDS_PN = "H79";
"DDR1_DQS_DP<3>":   PN = "F73"  !CDS_PN = "F73";
"DDR1_DQS_DP<4>":   PN = "R42"  !CDS_PN = "R42";
"DDR1_DQS_DP<5>":   PN = "E34"  !CDS_PN = "E34";
"DDR1_DQS_DP<6>":   PN = "E28"  !CDS_PN = "E28";
"DDR1_DQS_DP<7>":   PN = "Y27"  !CDS_PN = "Y27";
"DDR1_DQS_DP<8>":   PN = "L68"  !CDS_PN = "L68";
"DDR1_DQS_DP<9>":   PN = "AT81"  !CDS_PN = "AT81";
"DDR1_DQS_DP<10>":   PN = "AF81"  !CDS_PN = "AF81";
"DDR1_DQS_DP<11>":   PN = "F79"  !CDS_PN = "F79";
"DDR1_DQS_DP<12>":   PN = "D73"  !CDS_PN = "D73";
"DDR1_DQS_DP<13>":   PN = "L42"  !CDS_PN = "L42";
"DDR1_DQS_DP<14>":   PN = "C34"  !CDS_PN = "C34";
"DDR1_DQS_DP<15>":   PN = "C28"  !CDS_PN = "C28";
"DDR1_DQS_DP<16>":   PN = "V27"  !CDS_PN = "V27";
"DDR1_DQS_DP<17>":   PN = "J68"  !CDS_PN = "J68";
"DDR1_ECC<0>":   PN = "J70"  !CDS_PN = "J70";
"DDR1_ECC<1>":   PN = "H69"  !CDS_PN = "H69";
"DDR1_ECC<2>":   PN = "J66"  !CDS_PN = "J66";
"DDR1_ECC<3>":   PN = "L66"  !CDS_PN = "L66";
"DDR1_ECC<4>":   PN = "L70"  !CDS_PN = "L70";
"DDR1_ECC<5>":   PN = "M69"  !CDS_PN = "M69";
"DDR1_ECC<6>":   PN = "H67"  !CDS_PN = "H67";
"DDR1_ECC<7>":   PN = "M67"  !CDS_PN = "M67";
"DDR1_MA<0>":   PN = "J52"  !CDS_PN = "J52";
"DDR1_MA<1>":   PN = "J58"  !CDS_PN = "J58";
"DDR1_MA<2>":   PN = "K57"  !CDS_PN = "K57";
"DDR1_MA<3>":   PN = "N58"  !CDS_PN = "N58";
"DDR1_MA<4>":   PN = "M59"  !CDS_PN = "M59";
"DDR1_MA<5>":   PN = "R58"  !CDS_PN = "R58";
"DDR1_MA<6>":   PN = "T59"  !CDS_PN = "T59";
"DDR1_MA<7>":   PN = "V61"  !CDS_PN = "V61";
"DDR1_MA<8>":   PN = "W60"  !CDS_PN = "W60";
"DDR1_MA<9>":   PN = "K59"  !CDS_PN = "K59";
"DDR1_MA<10>":   PN = "M55"  !CDS_PN = "M55";
"DDR1_MA<11>":   PN = "R60"  !CDS_PN = "R60";
"DDR1_MA<12>":   PN = "T61"  !CDS_PN = "T61";
"DDR1_MA<13>":   PN = "M51"  !CDS_PN = "M51";
"DDR1_MA<14>":   PN = "T51"  !CDS_PN = "T51";
"DDR1_MA<15>":   PN = "N52"  !CDS_PN = "N52";
"DDR1_MA<16>":   PN = "R52"  !CDS_PN = "R52";
"DDR1_MA<17>":   PN = "N48"  !CDS_PN = "N48";
"DDR1_ODT<0>":   PN = "N50"  !CDS_PN = "N50";
"DDR1_ODT<1>":   PN = "R48"  !CDS_PN = "R48";
"DDR1_ODT<2>":   PN = "M49"  !CDS_PN = "M49";
"DDR1_ODT<3>":   PN = "T47"  !CDS_PN = "T47";
"DDR1_PAR":   PN = "K53"  !CDS_PN = "K53";
DRAWING = "@baseboard_fab2_lib.baseboard_fab2(sch_1):page59";
BODY = "SKX_EXT_B","I172": #LOCATION = "U2D1" !CDS_LOCATION = "U2D1" #SEC = "5" !CDS_SEC = "5";
"DDR2_ACT_N":   PN = "AB61"  !CDS_PN = "AB61";
"DDR2_ALERT_N":   PN = "AD61"  !CDS_PN = "AD61";
"DDR2_BA<0>":   PN = "W52"  !CDS_PN = "W52";
"DDR2_BA<1>":   PN = "AE56"  !CDS_PN = "AE56";
"DDR2_BG<0>":   PN = "AA60"  !CDS_PN = "AA60";
"DDR2_BG<1>":   PN = "AE62"  !CDS_PN = "AE62";
"DDR2_CID<2>":   PN = "AB45"  !CDS_PN = "AB45";
"DDR2_CKE<0>":   PN = "AA62"  !CDS_PN = "AA62";
"DDR2_CKE<1>":   PN = "AD63"  !CDS_PN = "AD63";
"DDR2_CKE<2>":   PN = "V63"  !CDS_PN = "V63";
"DDR2_CKE<3>":   PN = "AB63"  !CDS_PN = "AB63";
"DDR2_CLK_DN<0>":   PN = "AA54"  !CDS_PN = "AA54";
"DDR2_CLK_DN<1>":   PN = "W54"  !CDS_PN = "W54";
"DDR2_CLK_DN<2>":   PN = "AA56"  !CDS_PN = "AA56";
"DDR2_CLK_DN<3>":   PN = "W56"  !CDS_PN = "W56";
"DDR2_CLK_DP<0>":   PN = "AB55"  !CDS_PN = "AB55";
"DDR2_CLK_DP<1>":   PN = "V55"  !CDS_PN = "V55";
"DDR2_CLK_DP<2>":   PN = "AB57"  !CDS_PN = "AB57";
"DDR2_CLK_DP<3>":   PN = "V57"  !CDS_PN = "V57";
"DDR2_CS<0>_N":   PN = "V51"  !CDS_PN = "V51";
"DDR2_CS<1>_N":   PN = "AB49"  !CDS_PN = "AB49";
"DDR2_CS<2>_N":   PN = "W46"  !CDS_PN = "W46";
"DDR2_CS<3>_N":   PN = "AA46"  !CDS_PN = "AA46";
"DDR2_CS<4>_N":   PN = "AB51"  !CDS_PN = "AB51";
"DDR2_CS<5>_N":   PN = "W48"  !CDS_PN = "W48";
"DDR2_CS<6>_N":   PN = "T45"  !CDS_PN = "T45";
"DDR2_CS<7>_N":   PN = "V45"  !CDS_PN = "V45";
"DDR2_DQ<0>":   PN = "AR76"  !CDS_PN = "AR76";
"DDR2_DQ<1>":   PN = "AN74"  !CDS_PN = "AN74";
"DDR2_DQ<2>":   PN = "AK77"  !CDS_PN = "AK77";
"DDR2_DQ<3>":   PN = "AJ76"  !CDS_PN = "AJ76";
"DDR2_DQ<4>":   PN = "AT75"  !CDS_PN = "AT75";
"DDR2_DQ<5>":   PN = "AR74"  !CDS_PN = "AR74";
"DDR2_DQ<6>":   PN = "AM77"  !CDS_PN = "AM77";
"DDR2_DQ<7>":   PN = "AK75"  !CDS_PN = "AK75";
"DDR2_DQ<8>":   PN = "AE76"  !CDS_PN = "AE76";
"DDR2_DQ<9>":   PN = "AC74"  !CDS_PN = "AC74";
"DDR2_DQ<10>":   PN = "Y77"  !CDS_PN = "Y77";
"DDR2_DQ<11>":   PN = "W76"  !CDS_PN = "W76";
"DDR2_DQ<12>":   PN = "AF75"  !CDS_PN = "AF75";
"DDR2_DQ<13>":   PN = "AE74"  !CDS_PN = "AE74";
"DDR2_DQ<14>":   PN = "AB77"  !CDS_PN = "AB77";
"DDR2_DQ<15>":   PN = "Y75"  !CDS_PN = "Y75";
"DDR2_DQ<16>":   PN = "W72"  !CDS_PN = "W72";
"DDR2_DQ<17>":   PN = "AA70"  !CDS_PN = "AA70";
"DDR2_DQ<18>":   PN = "R70"  !CDS_PN = "R70";
"DDR2_DQ<19>":   PN = "T69"  !CDS_PN = "T69";
"DDR2_DQ<20>":   PN = "AA72"  !CDS_PN = "AA72";
"DDR2_DQ<21>":   PN = "AB71"  !CDS_PN = "AB71";
"DDR2_DQ<22>":   PN = "T71"  !CDS_PN = "T71";
"DDR2_DQ<23>":   PN = "V69"  !CDS_PN = "V69";
"DDR2_DQ<24>":   PN = "AM67"  !CDS_PN = "AM67";
"DDR2_DQ<25>":   PN = "AT67"  !CDS_PN = "AT67";
"DDR2_DQ<26>":   PN = "AN64"  !CDS_PN = "AN64";
"DDR2_DQ<27>":   PN = "AR64"  !CDS_PN = "AR64";
"DDR2_DQ<28>":   PN = "AN68"  !CDS_PN = "AN68";
"DDR2_DQ<29>":   PN = "AR68"  !CDS_PN = "AR68";
"DDR2_DQ<30>":   PN = "AM65"  !CDS_PN = "AM65";
"DDR2_DQ<31>":   PN = "AT65"  !CDS_PN = "AT65";
"DDR2_DQ<32>":   PN = "U40"  !CDS_PN = "U40";
"DDR2_DQ<33>":   PN = "AA40"  !CDS_PN = "AA40";
"DDR2_DQ<34>":   PN = "V37"  !CDS_PN = "V37";
"DDR2_DQ<35>":   PN = "Y37"  !CDS_PN = "Y37";
"DDR2_DQ<36>":   PN = "V41"  !CDS_PN = "V41";
"DDR2_DQ<37>":   PN = "Y41"  !CDS_PN = "Y41";
"DDR2_DQ<38>":   PN = "U38"  !CDS_PN = "U38";
"DDR2_DQ<39>":   PN = "AA38"  !CDS_PN = "AA38";
"DDR2_DQ<40>":   PN = "U34"  !CDS_PN = "U34";
"DDR2_DQ<41>":   PN = "AA34"  !CDS_PN = "AA34";
"DDR2_DQ<42>":   PN = "V31"  !CDS_PN = "V31";
"DDR2_DQ<43>":   PN = "Y31"  !CDS_PN = "Y31";
"DDR2_DQ<44>":   PN = "V35"  !CDS_PN = "V35";
"DDR2_DQ<45>":   PN = "Y35"  !CDS_PN = "Y35";
"DDR2_DQ<46>":   PN = "U32"  !CDS_PN = "U32";
"DDR2_DQ<47>":   PN = "AA32"  !CDS_PN = "AA32";
"DDR2_DQ<48>":   PN = "AD31"  !CDS_PN = "AD31";
"DDR2_DQ<49>":   PN = "AH31"  !CDS_PN = "AH31";
"DDR2_DQ<50>":   PN = "AE28"  !CDS_PN = "AE28";
"DDR2_DQ<51>":   PN = "AG28"  !CDS_PN = "AG28";
"DDR2_DQ<52>":   PN = "AE32"  !CDS_PN = "AE32";
"DDR2_DQ<53>":   PN = "AG32"  !CDS_PN = "AG32";
"DDR2_DQ<54>":   PN = "AD29"  !CDS_PN = "AD29";
"DDR2_DQ<55>":   PN = "AH29"  !CDS_PN = "AH29";
"DDR2_DQ<56>":   PN = "AD25"  !CDS_PN = "AD25";
"DDR2_DQ<57>":   PN = "AH25"  !CDS_PN = "AH25";
"DDR2_DQ<58>":   PN = "AE22"  !CDS_PN = "AE22";
"DDR2_DQ<59>":   PN = "AG22"  !CDS_PN = "AG22";
"DDR2_DQ<60>":   PN = "AE26"  !CDS_PN = "AE26";
"DDR2_DQ<61>":   PN = "AG26"  !CDS_PN = "AG26";
"DDR2_DQ<62>":   PN = "AD23"  !CDS_PN = "AD23";
"DDR2_DQ<63>":   PN = "AH23"  !CDS_PN = "AH23";
"DDR2_DQS_DN<0>":   PN = "AL74"  !CDS_PN = "AL74";
"DDR2_DQS_DN<1>":   PN = "AA74"  !CDS_PN = "AA74";
"DDR2_DQS_DN<2>":   PN = "Y69"  !CDS_PN = "Y69";
"DDR2_DQS_DN<3>":   PN = "AU66"  !CDS_PN = "AU66";
"DDR2_DQS_DN<4>":   PN = "AB39"  !CDS_PN = "AB39";
"DDR2_DQS_DN<5>":   PN = "AB33"  !CDS_PN = "AB33";
"DDR2_DQS_DN<6>":   PN = "AJ30"  !CDS_PN = "AJ30";
"DDR2_DQS_DN<7>":   PN = "AJ24"  !CDS_PN = "AJ24";
"DDR2_DQS_DN<8>":   PN = "BB71"  !CDS_PN = "BB71";
"DDR2_DQS_DN<9>":   PN = "AP77"  !CDS_PN = "AP77";
"DDR2_DQS_DN<10>":   PN = "AD77"  !CDS_PN = "AD77";
"DDR2_DQS_DN<11>":   PN = "U72"  !CDS_PN = "U72";
"DDR2_DQS_DN<12>":   PN = "AL66"  !CDS_PN = "AL66";
"DDR2_DQS_DN<13>":   PN = "T39"  !CDS_PN = "T39";
"DDR2_DQS_DN<14>":   PN = "T33"  !CDS_PN = "T33";
"DDR2_DQS_DN<15>":   PN = "AC30"  !CDS_PN = "AC30";
"DDR2_DQS_DN<16>":   PN = "AC24"  !CDS_PN = "AC24";
"DDR2_DQS_DN<17>":   PN = "AT71"  !CDS_PN = "AT71";
"DDR2_DQS_DP<0>":   PN = "AM75"  !CDS_PN = "AM75";
"DDR2_DQS_DP<1>":   PN = "AB75"  !CDS_PN = "AB75";
"DDR2_DQS_DP<2>":   PN = "W70"  !CDS_PN = "W70";
"DDR2_DQS_DP<3>":   PN = "AR66"  !CDS_PN = "AR66";
"DDR2_DQS_DP<4>":   PN = "Y39"  !CDS_PN = "Y39";
"DDR2_DQS_DP<5>":   PN = "Y33"  !CDS_PN = "Y33";
"DDR2_DQS_DP<6>":   PN = "AG30"  !CDS_PN = "AG30";
"DDR2_DQS_DP<7>":   PN = "AG24"  !CDS_PN = "AG24";
"DDR2_DQS_DP<8>":   PN = "AY71"  !CDS_PN = "AY71";
"DDR2_DQS_DP<9>":   PN = "AN76"  !CDS_PN = "AN76";
"DDR2_DQS_DP<10>":   PN = "AC76"  !CDS_PN = "AC76";
"DDR2_DQS_DP<11>":   PN = "V71"  !CDS_PN = "V71";
"DDR2_DQS_DP<12>":   PN = "AN66"  !CDS_PN = "AN66";
"DDR2_DQS_DP<13>":   PN = "V39"  !CDS_PN = "V39";
"DDR2_DQS_DP<14>":   PN = "V33"  !CDS_PN = "V33";
"DDR2_DQS_DP<15>":   PN = "AE30"  !CDS_PN = "AE30";
"DDR2_DQS_DP<16>":   PN = "AE24"  !CDS_PN = "AE24";
"DDR2_DQS_DP<17>":   PN = "AV71"  !CDS_PN = "AV71";
"DDR2_ECC<0>":   PN = "AU72"  !CDS_PN = "AU72";
"DDR2_ECC<1>":   PN = "BA72"  !CDS_PN = "BA72";
"DDR2_ECC<2>":   PN = "AV69"  !CDS_PN = "AV69";
"DDR2_ECC<3>":   PN = "AY69"  !CDS_PN = "AY69";
"DDR2_ECC<4>":   PN = "AV73"  !CDS_PN = "AV73";
"DDR2_ECC<5>":   PN = "AY73"  !CDS_PN = "AY73";
"DDR2_ECC<6>":   PN = "AU70"  !CDS_PN = "AU70";
"DDR2_ECC<7>":   PN = "BA70"  !CDS_PN = "BA70";
"DDR2_MA<0>":   PN = "AB53"  !CDS_PN = "AB53";
"DDR2_MA<1>":   PN = "AE58"  !CDS_PN = "AE58";
"DDR2_MA<2>":   PN = "AD57"  !CDS_PN = "AD57";
"DDR2_MA<3>":   PN = "W58"  !CDS_PN = "W58";
"DDR2_MA<4>":   PN = "AA58"  !CDS_PN = "AA58";
"DDR2_MA<5>":   PN = "V59"  !CDS_PN = "V59";
"DDR2_MA<6>":   PN = "AB59"  !CDS_PN = "AB59";
"DDR2_MA<7>":   PN = "AE60"  !CDS_PN = "AE60";
"DDR2_MA<8>":   PN = "AD59"  !CDS_PN = "AD59";
"DDR2_MA<9>":   PN = "AG58"  !CDS_PN = "AG58";
"DDR2_MA<10>":   PN = "AD55"  !CDS_PN = "AD55";
"DDR2_MA<11>":   PN = "AG60"  !CDS_PN = "AG60";
"DDR2_MA<12>":   PN = "AG62"  !CDS_PN = "AG62";
"DDR2_MA<13>":   PN = "AD53"  !CDS_PN = "AD53";
"DDR2_MA<14>":   PN = "W50"  !CDS_PN = "W50";
"DDR2_MA<15>":   PN = "AE54"  !CDS_PN = "AE54";
"DDR2_MA<16>":   PN = "AA52"  !CDS_PN = "AA52";
"DDR2_MA<17>":   PN = "AC46"  !CDS_PN = "AC46";
"DDR2_ODT<0>":   PN = "AA50"  !CDS_PN = "AA50";
"DDR2_ODT<1>":   PN = "AA48"  !CDS_PN = "AA48";
"DDR2_ODT<2>":   PN = "V49"  !CDS_PN = "V49";
"DDR2_ODT<3>":   PN = "AB47"  !CDS_PN = "AB47";
"DDR2_PAR":   PN = "V53"  !CDS_PN = "V53";
DRAWING = "@baseboard_fab2_lib.baseboard_fab2(sch_1):page60";
BODY = "SKX_EXT_B","I172": #LOCATION = "U2D1" !CDS_LOCATION = "U2D1" #SEC = "6" !CDS_SEC = "6";
"DDR3_ACT_N":   PN = "DW60"  !CDS_PN = "DW60";
"DDR3_ALERT_N":   PN = "ED63"  !CDS_PN = "ED63";
"DDR3_BA<0>":   PN = "EE52"  !CDS_PN = "EE52";
"DDR3_BA<1>":   PN = "EA54"  !CDS_PN = "EA54";
"DDR3_BG<0>":   PN = "ED61"  !CDS_PN = "ED61";
"DDR3_BG<1>":   PN = "DW62"  !CDS_PN = "DW62";
"DDR3_CID<2>":   PN = "DV47"  !CDS_PN = "DV47";
"DDR3_CKE<0>":   PN = "EE62"  !CDS_PN = "EE62";
"DDR3_CKE<1>":   PN = "EF63"  !CDS_PN = "EF63";
"DDR3_CKE<2>":   PN = "EA62"  !CDS_PN = "EA62";
"DDR3_CKE<3>":   PN = "EB63"  !CDS_PN = "EB63";
"DDR3_CLK_DN<0>":   PN = "ED55"  !CDS_PN = "ED55";
"DDR3_CLK_DN<1>":   PN = "EF55"  !CDS_PN = "EF55";
"DDR3_CLK_DN<2>":   PN = "DW56"  !CDS_PN = "DW56";
"DDR3_CLK_DN<3>":   PN = "EF57"  !CDS_PN = "EF57";
"DDR3_CLK_DP<0>":   PN = "EB55"  !CDS_PN = "EB55";
"DDR3_CLK_DP<1>":   PN = "EE54"  !CDS_PN = "EE54";
"DDR3_CLK_DP<2>":   PN = "EA56"  !CDS_PN = "EA56";
"DDR3_CLK_DP<3>":   PN = "EE56"  !CDS_PN = "EE56";
"DDR3_CS<0>_N":   PN = "EF51"  !CDS_PN = "EF51";
"DDR3_CS<1>_N":   PN = "ED49"  !CDS_PN = "ED49";
"DDR3_CS<2>_N":   PN = "ED47"  !CDS_PN = "ED47";
"DDR3_CS<3>_N":   PN = "EB47"  !CDS_PN = "EB47";
"DDR3_CS<4>_N":   PN = "EB51"  !CDS_PN = "EB51";
"DDR3_CS<5>_N":   PN = "EB49"  !CDS_PN = "EB49";
"DDR3_CS<6>_N":   PN = "DV45"  !CDS_PN = "DV45";
"DDR3_CS<7>_N":   PN = "EB45"  !CDS_PN = "EB45";
"DDR3_DQ<0>":   PN = "CN84"  !CDS_PN = "CN84";
"DDR3_DQ<1>":   PN = "CN86"  !CDS_PN = "CN86";
"DDR3_DQ<2>":   PN = "DA86"  !CDS_PN = "DA86";
"DDR3_DQ<3>":   PN = "DA84"  !CDS_PN = "DA84";
"DDR3_DQ<4>":   PN = "CL84"  !CDS_PN = "CL84";
"DDR3_DQ<5>":   PN = "CL86"  !CDS_PN = "CL86";
"DDR3_DQ<6>":   PN = "CW86"  !CDS_PN = "CW86";
"DDR3_DQ<7>":   PN = "CW84"  !CDS_PN = "CW84";
"DDR3_DQ<8>":   PN = "DG84"  !CDS_PN = "DG84";
"DDR3_DQ<9>":   PN = "DH85"  !CDS_PN = "DH85";
"DDR3_DQ<10>":   PN = "DV83"  !CDS_PN = "DV83";
"DDR3_DQ<11>":   PN = "DY83"  !CDS_PN = "DY83";
"DDR3_DQ<12>":   PN = "DD85"  !CDS_PN = "DD85";
"DDR3_DQ<13>":   PN = "DE84"  !CDS_PN = "DE84";
"DDR3_DQ<14>":   PN = "DR84"  !CDS_PN = "DR84";
"DDR3_DQ<15>":   PN = "DV85"  !CDS_PN = "DV85";
"DDR3_DQ<16>":   PN = "DM79"  !CDS_PN = "DM79";
"DDR3_DQ<17>":   PN = "DK81"  !CDS_PN = "DK81";
"DDR3_DQ<18>":   PN = "DT81"  !CDS_PN = "DT81";
"DDR3_DQ<19>":   PN = "DR82"  !CDS_PN = "DR82";
"DDR3_DQ<20>":   PN = "DK79"  !CDS_PN = "DK79";
"DDR3_DQ<21>":   PN = "DJ80"  !CDS_PN = "DJ80";
"DDR3_DQ<22>":   PN = "DR80"  !CDS_PN = "DR80";
"DDR3_DQ<23>":   PN = "DN82"  !CDS_PN = "DN82";
"DDR3_DQ<24>":   PN = "DN76"  !CDS_PN = "DN76";
"DDR3_DQ<25>":   PN = "DU76"  !CDS_PN = "DU76";
"DDR3_DQ<26>":   PN = "DP73"  !CDS_PN = "DP73";
"DDR3_DQ<27>":   PN = "DT73"  !CDS_PN = "DT73";
"DDR3_DQ<28>":   PN = "DP77"  !CDS_PN = "DP77";
"DDR3_DQ<29>":   PN = "DT77"  !CDS_PN = "DT77";
"DDR3_DQ<30>":   PN = "DN74"  !CDS_PN = "DN74";
"DDR3_DQ<31>":   PN = "DU74"  !CDS_PN = "DU74";
"DDR3_DQ<32>":   PN = "EC40"  !CDS_PN = "EC40";
"DDR3_DQ<33>":   PN = "ED39"  !CDS_PN = "ED39";
"DDR3_DQ<34>":   PN = "EA36"  !CDS_PN = "EA36";
"DDR3_DQ<35>":   PN = "EC36"  !CDS_PN = "EC36";
"DDR3_DQ<36>":   PN = "DY39"  !CDS_PN = "DY39";
"DDR3_DQ<37>":   PN = "EA40"  !CDS_PN = "EA40";
"DDR3_DQ<38>":   PN = "DY37"  !CDS_PN = "DY37";
"DDR3_DQ<39>":   PN = "ED37"  !CDS_PN = "ED37";
"DDR3_DQ<40>":   PN = "DN36"  !CDS_PN = "DN36";
"DDR3_DQ<41>":   PN = "DU36"  !CDS_PN = "DU36";
"DDR3_DQ<42>":   PN = "DP33"  !CDS_PN = "DP33";
"DDR3_DQ<43>":   PN = "DT33"  !CDS_PN = "DT33";
"DDR3_DQ<44>":   PN = "DP37"  !CDS_PN = "DP37";
"DDR3_DQ<45>":   PN = "DT37"  !CDS_PN = "DT37";
"DDR3_DQ<46>":   PN = "DN34"  !CDS_PN = "DN34";
"DDR3_DQ<47>":   PN = "DU34"  !CDS_PN = "DU34";
"DDR3_DQ<48>":   PN = "DN30"  !CDS_PN = "DN30";
"DDR3_DQ<49>":   PN = "DU30"  !CDS_PN = "DU30";
"DDR3_DQ<50>":   PN = "DP27"  !CDS_PN = "DP27";
"DDR3_DQ<51>":   PN = "DT27"  !CDS_PN = "DT27";
"DDR3_DQ<52>":   PN = "DP31"  !CDS_PN = "DP31";
"DDR3_DQ<53>":   PN = "DT31"  !CDS_PN = "DT31";
"DDR3_DQ<54>":   PN = "DN28"  !CDS_PN = "DN28";
"DDR3_DQ<55>":   PN = "DU28"  !CDS_PN = "DU28";
"DDR3_DQ<56>":   PN = "DN24"  !CDS_PN = "DN24";
"DDR3_DQ<57>":   PN = "DU24"  !CDS_PN = "DU24";
"DDR3_DQ<58>":   PN = "DY21"  !CDS_PN = "DY21";
"DDR3_DQ<59>":   PN = "EB21"  !CDS_PN = "EB21";
"DDR3_DQ<60>":   PN = "DP25"  !CDS_PN = "DP25";
"DDR3_DQ<61>":   PN = "DT25"  !CDS_PN = "DT25";
"DDR3_DQ<62>":   PN = "EC22"  !CDS_PN = "EC22";
"DDR3_DQ<63>":   PN = "DW22"  !CDS_PN = "DW22";
"DDR3_DQS_DN<0>":   PN = "CU84"  !CDS_PN = "CU84";
"DDR3_DQS_DN<1>":   PN = "DN84"  !CDS_PN = "DN84";
"DDR3_DQS_DN<2>":   PN = "DL82"  !CDS_PN = "DL82";
"DDR3_DQS_DN<3>":   PN = "DV75"  !CDS_PN = "DV75";
"DDR3_DQS_DN<4>":   PN = "EE38"  !CDS_PN = "EE38";
"DDR3_DQS_DN<5>":   PN = "DV35"  !CDS_PN = "DV35";
"DDR3_DQS_DN<6>":   PN = "DV29"  !CDS_PN = "DV29";
"DDR3_DQS_DN<7>":   PN = "DV23"  !CDS_PN = "DV23";
"DDR3_DQS_DN<8>":   PN = "DF67"  !CDS_PN = "DF67";
"DDR3_DQS_DN<9>":   PN = "CR84"  !CDS_PN = "CR84";
"DDR3_DQS_DN<10>":   PN = "DM85"  !CDS_PN = "DM85";
"DDR3_DQS_DN<11>":   PN = "DN80"  !CDS_PN = "DN80";
"DDR3_DQS_DN<12>":   PN = "DP75"  !CDS_PN = "DP75";
"DDR3_DQS_DN<13>":   PN = "EA38"  !CDS_PN = "EA38";
"DDR3_DQS_DN<14>":   PN = "DP35"  !CDS_PN = "DP35";
"DDR3_DQS_DN<15>":   PN = "DM29"  !CDS_PN = "DM29";
"DDR3_DQS_DN<16>":   PN = "DM23"  !CDS_PN = "DM23";
"DDR3_DQS_DN<17>":   PN = "DB67"  !CDS_PN = "DB67";
"DDR3_DQS_DP<0>":   PN = "CV85"  !CDS_PN = "CV85";
"DDR3_DQS_DP<1>":   PN = "DP85"  !CDS_PN = "DP85";
"DDR3_DQS_DP<2>":   PN = "DM81"  !CDS_PN = "DM81";
"DDR3_DQS_DP<3>":   PN = "DT75"  !CDS_PN = "DT75";
"DDR3_DQS_DP<4>":   PN = "EC38"  !CDS_PN = "EC38";
"DDR3_DQS_DP<5>":   PN = "DT35"  !CDS_PN = "DT35";
"DDR3_DQS_DP<6>":   PN = "DT29"  !CDS_PN = "DT29";
"DDR3_DQS_DP<7>":   PN = "DT23"  !CDS_PN = "DT23";
"DDR3_DQS_DP<8>":   PN = "DD67"  !CDS_PN = "DD67";
"DDR3_DQS_DP<9>":   PN = "CP85"  !CDS_PN = "CP85";
"DDR3_DQS_DP<10>":   PN = "DL84"  !CDS_PN = "DL84";
"DDR3_DQS_DP<11>":   PN = "DP79"  !CDS_PN = "DP79";
"DDR3_DQS_DP<12>":   PN = "DM75"  !CDS_PN = "DM75";
"DDR3_DQS_DP<13>":   PN = "DW38"  !CDS_PN = "DW38";
"DDR3_DQS_DP<14>":   PN = "DM35"  !CDS_PN = "DM35";
"DDR3_DQS_DP<15>":   PN = "DP29"  !CDS_PN = "DP29";
"DDR3_DQS_DP<16>":   PN = "DP23"  !CDS_PN = "DP23";
"DDR3_DQS_DP<17>":   PN = "CY67"  !CDS_PN = "CY67";
"DDR3_ECC<0>":   PN = "DA68"  !CDS_PN = "DA68";
"DDR3_ECC<1>":   PN = "DE68"  !CDS_PN = "DE68";
"DDR3_ECC<2>":   PN = "DB65"  !CDS_PN = "DB65";
"DDR3_ECC<3>":   PN = "DD65"  !CDS_PN = "DD65";
"DDR3_ECC<4>":   PN = "DB69"  !CDS_PN = "DB69";
"DDR3_ECC<5>":   PN = "DD69"  !CDS_PN = "DD69";
"DDR3_ECC<6>":   PN = "DA66"  !CDS_PN = "DA66";
"DDR3_ECC<7>":   PN = "DE66"  !CDS_PN = "DE66";
"DDR3_MA<0>":   PN = "EB53"  !CDS_PN = "EB53";
"DDR3_MA<1>":   PN = "ED57"  !CDS_PN = "ED57";
"DDR3_MA<2>":   PN = "EE58"  !CDS_PN = "EE58";
"DDR3_MA<3>":   PN = "EB57"  !CDS_PN = "EB57";
"DDR3_MA<4>":   PN = "ED59"  !CDS_PN = "ED59";
"DDR3_MA<5>":   PN = "EA58"  !CDS_PN = "EA58";
"DDR3_MA<6>":   PN = "EE60"  !CDS_PN = "EE60";
"DDR3_MA<7>":   PN = "EA60"  !CDS_PN = "EA60";
"DDR3_MA<8>":   PN = "EB59"  !CDS_PN = "EB59";
"DDR3_MA<9>":   PN = "EF61"  !CDS_PN = "EF61";
"DDR3_MA<10>":   PN = "DW54"  !CDS_PN = "DW54";
"DDR3_MA<11>":   PN = "EB61"  !CDS_PN = "EB61";
"DDR3_MA<12>":   PN = "DT63"  !CDS_PN = "DT63";
"DDR3_MA<13>":   PN = "DW48"  !CDS_PN = "DW48";
"DDR3_MA<14>":   PN = "ED51"  !CDS_PN = "ED51";
"DDR3_MA<15>":   PN = "DV49"  !CDS_PN = "DV49";
"DDR3_MA<16>":   PN = "EA52"  !CDS_PN = "EA52";
"DDR3_MA<17>":   PN = "EA46"  !CDS_PN = "EA46";
"DDR3_ODT<0>":   PN = "EE50"  !CDS_PN = "EE50";
"DDR3_ODT<1>":   PN = "EE48"  !CDS_PN = "EE48";
"DDR3_ODT<2>":   PN = "EA50"  !CDS_PN = "EA50";
"DDR3_ODT<3>":   PN = "EA48"  !CDS_PN = "EA48";
"DDR3_PAR":   PN = "ED53"  !CDS_PN = "ED53";
DRAWING = "@baseboard_fab2_lib.baseboard_fab2(sch_1):page61";
BODY = "SKX_EXT_B","I172": #LOCATION = "U2D1" !CDS_LOCATION = "U2D1" #SEC = "7" !CDS_SEC = "7";
"DDR4_ACT_N":   PN = "DR62"  !CDS_PN = "DR62";
"DDR4_ALERT_N":   PN = "DT61"  !CDS_PN = "DT61";
"DDR4_BA<0>":   PN = "DM53"  !CDS_PN = "DM53";
"DDR4_BA<1>":   PN = "DV55"  !CDS_PN = "DV55";
"DDR4_BG<0>":   PN = "DJ62"  !CDS_PN = "DJ62";
"DDR4_BG<1>":   PN = "DM61"  !CDS_PN = "DM61";
"DDR4_CID<2>":   PN = "DT47"  !CDS_PN = "DT47";
"DDR4_CKE<0>":   PN = "DM63"  !CDS_PN = "DM63";
"DDR4_CKE<1>":   PN = "DN64"  !CDS_PN = "DN64";
"DDR4_CKE<2>":   PN = "DL64"  !CDS_PN = "DL64";
"DDR4_CKE<3>":   PN = "DR64"  !CDS_PN = "DR64";
"DDR4_CLK_DN<0>":   PN = "DM55"  !CDS_PN = "DM55";
"DDR4_CLK_DN<1>":   PN = "DR54"  !CDS_PN = "DR54";
"DDR4_CLK_DN<2>":   PN = "DM57"  !CDS_PN = "DM57";
"DDR4_CLK_DN<3>":   PN = "DT57"  !CDS_PN = "DT57";
"DDR4_CLK_DP<0>":   PN = "DN54"  !CDS_PN = "DN54";
"DDR4_CLK_DP<1>":   PN = "DT53"  !CDS_PN = "DT53";
"DDR4_CLK_DP<2>":   PN = "DN56"  !CDS_PN = "DN56";
"DDR4_CLK_DP<3>":   PN = "DR56"  !CDS_PN = "DR56";
"DDR4_CS<0>_N":   PN = "DV51"  !CDS_PN = "DV51";
"DDR4_CS<1>_N":   PN = "DN50"  !CDS_PN = "DN50";
"DDR4_CS<2>_N":   PN = "DR46"  !CDS_PN = "DR46";
"DDR4_CS<3>_N":   PN = "DK47"  !CDS_PN = "DK47";
"DDR4_CS<4>_N":   PN = "DW50"  !CDS_PN = "DW50";
"DDR4_CS<5>_N":   PN = "DM49"  !CDS_PN = "DM49";
"DDR4_CS<6>_N":   PN = "DT45"  !CDS_PN = "DT45";
"DDR4_CS<7>_N":   PN = "DN46"  !CDS_PN = "DN46";
"DDR4_DQ<0>":   PN = "CM79"  !CDS_PN = "CM79";
"DDR4_DQ<1>":   PN = "CK81"  !CDS_PN = "CK81";
"DDR4_DQ<2>":   PN = "CT81"  !CDS_PN = "CT81";
"DDR4_DQ<3>":   PN = "CR82"  !CDS_PN = "CR82";
"DDR4_DQ<4>":   PN = "CK79"  !CDS_PN = "CK79";
"DDR4_DQ<5>":   PN = "CJ80"  !CDS_PN = "CJ80";
"DDR4_DQ<6>":   PN = "CR80"  !CDS_PN = "CR80";
"DDR4_DQ<7>":   PN = "CN82"  !CDS_PN = "CN82";
"DDR4_DQ<8>":   PN = "DB79"  !CDS_PN = "DB79";
"DDR4_DQ<9>":   PN = "CY81"  !CDS_PN = "CY81";
"DDR4_DQ<10>":   PN = "DE80"  !CDS_PN = "DE80";
"DDR4_DQ<11>":   PN = "DF81"  !CDS_PN = "DF81";
"DDR4_DQ<12>":   PN = "CY79"  !CDS_PN = "CY79";
"DDR4_DQ<13>":   PN = "CW80"  !CDS_PN = "CW80";
"DDR4_DQ<14>":   PN = "DC82"  !CDS_PN = "DC82";
"DDR4_DQ<15>":   PN = "DE82"  !CDS_PN = "DE82";
"DDR4_DQ<16>":   PN = "DW80"  !CDS_PN = "DW80";
"DDR4_DQ<17>":   PN = "EC80"  !CDS_PN = "EC80";
"DDR4_DQ<18>":   PN = "DY77"  !CDS_PN = "DY77";
"DDR4_DQ<19>":   PN = "EB77"  !CDS_PN = "EB77";
"DDR4_DQ<20>":   PN = "DY81"  !CDS_PN = "DY81";
"DDR4_DQ<21>":   PN = "EB81"  !CDS_PN = "EB81";
"DDR4_DQ<22>":   PN = "DW78"  !CDS_PN = "DW78";
"DDR4_DQ<23>":   PN = "EC78"  !CDS_PN = "EC78";
"DDR4_DQ<24>":   PN = "ED75"  !CDS_PN = "ED75";
"DDR4_DQ<25>":   PN = "EE74"  !CDS_PN = "EE74";
"DDR4_DQ<26>":   PN = "EB71"  !CDS_PN = "EB71";
"DDR4_DQ<27>":   PN = "ED71"  !CDS_PN = "ED71";
"DDR4_DQ<28>":   PN = "EA74"  !CDS_PN = "EA74";
"DDR4_DQ<29>":   PN = "EB75"  !CDS_PN = "EB75";
"DDR4_DQ<30>":   PN = "EA72"  !CDS_PN = "EA72";
"DDR4_DQ<31>":   PN = "EE72"  !CDS_PN = "EE72";
"DDR4_DQ<32>":   PN = "DU42"  !CDS_PN = "DU42";
"DDR4_DQ<33>":   PN = "DW42"  !CDS_PN = "DW42";
"DDR4_DQ<34>":   PN = "DP39"  !CDS_PN = "DP39";
"DDR4_DQ<35>":   PN = "DT39"  !CDS_PN = "DT39";
"DDR4_DQ<36>":   PN = "DL42"  !CDS_PN = "DL42";
"DDR4_DQ<37>":   PN = "DN42"  !CDS_PN = "DN42";
"DDR4_DQ<38>":   PN = "DN40"  !CDS_PN = "DN40";
"DDR4_DQ<39>":   PN = "DU40"  !CDS_PN = "DU40";
"DDR4_DQ<40>":   PN = "EC34"  !CDS_PN = "EC34";
"DDR4_DQ<41>":   PN = "ED33"  !CDS_PN = "ED33";
"DDR4_DQ<42>":   PN = "EA30"  !CDS_PN = "EA30";
"DDR4_DQ<43>":   PN = "EC30"  !CDS_PN = "EC30";
"DDR4_DQ<44>":   PN = "DY33"  !CDS_PN = "DY33";
"DDR4_DQ<45>":   PN = "EA34"  !CDS_PN = "EA34";
"DDR4_DQ<46>":   PN = "DY31"  !CDS_PN = "DY31";
"DDR4_DQ<47>":   PN = "ED31"  !CDS_PN = "ED31";
"DDR4_DQ<48>":   PN = "EC28"  !CDS_PN = "EC28";
"DDR4_DQ<49>":   PN = "ED27"  !CDS_PN = "ED27";
"DDR4_DQ<50>":   PN = "EA24"  !CDS_PN = "EA24";
"DDR4_DQ<51>":   PN = "EC24"  !CDS_PN = "EC24";
"DDR4_DQ<52>":   PN = "DY27"  !CDS_PN = "DY27";
"DDR4_DQ<53>":   PN = "EA28"  !CDS_PN = "EA28";
"DDR4_DQ<54>":   PN = "DY25"  !CDS_PN = "DY25";
"DDR4_DQ<55>":   PN = "ED25"  !CDS_PN = "ED25";
"DDR4_DQ<56>":   PN = "DF27"  !CDS_PN = "DF27";
"DDR4_DQ<57>":   PN = "DK27"  !CDS_PN = "DK27";
"DDR4_DQ<58>":   PN = "DD25"  !CDS_PN = "DD25";
"DDR4_DQ<59>":   PN = "DJ24"  !CDS_PN = "DJ24";
"DDR4_DQ<60>":   PN = "DG28"  !CDS_PN = "DG28";
"DDR4_DQ<61>":   PN = "DJ28"  !CDS_PN = "DJ28";
"DDR4_DQ<62>":   PN = "DF25"  !CDS_PN = "DF25";
"DDR4_DQ<63>":   PN = "DK25"  !CDS_PN = "DK25";
"DDR4_DQS_DN<0>":   PN = "CL82"  !CDS_PN = "CL82";
"DDR4_DQS_DN<1>":   PN = "DA82"  !CDS_PN = "DA82";
"DDR4_DQS_DN<2>":   PN = "ED79"  !CDS_PN = "ED79";
"DDR4_DQS_DN<3>":   PN = "EF73"  !CDS_PN = "EF73";
"DDR4_DQS_DN<4>":   PN = "DV41"  !CDS_PN = "DV41";
"DDR4_DQS_DN<5>":   PN = "EE32"  !CDS_PN = "EE32";
"DDR4_DQS_DN<6>":   PN = "EE26"  !CDS_PN = "EE26";
"DDR4_DQS_DN<7>":   PN = "DL26"  !CDS_PN = "DL26";
"DDR4_DQS_DN<8>":   PN = "EB67"  !CDS_PN = "EB67";
"DDR4_DQS_DN<9>":   PN = "CN80"  !CDS_PN = "CN80";
"DDR4_DQS_DN<10>":   PN = "DC80"  !CDS_PN = "DC80";
"DDR4_DQS_DN<11>":   PN = "DY79"  !CDS_PN = "DY79";
"DDR4_DQS_DN<12>":   PN = "EB73"  !CDS_PN = "EB73";
"DDR4_DQS_DN<13>":   PN = "DP41"  !CDS_PN = "DP41";
"DDR4_DQS_DN<14>":   PN = "EA32"  !CDS_PN = "EA32";
"DDR4_DQS_DN<15>":   PN = "EA26"  !CDS_PN = "EA26";
"DDR4_DQS_DN<16>":   PN = "DG26"  !CDS_PN = "DG26";
"DDR4_DQS_DN<17>":   PN = "DV67"  !CDS_PN = "DV67";
"DDR4_DQS_DP<0>":   PN = "CM81"  !CDS_PN = "CM81";
"DDR4_DQS_DP<1>":   PN = "DB81"  !CDS_PN = "DB81";
"DDR4_DQS_DP<2>":   PN = "EB79"  !CDS_PN = "EB79";
"DDR4_DQS_DP<3>":   PN = "ED73"  !CDS_PN = "ED73";
"DDR4_DQS_DP<4>":   PN = "DT41"  !CDS_PN = "DT41";
"DDR4_DQS_DP<5>":   PN = "EC32"  !CDS_PN = "EC32";
"DDR4_DQS_DP<6>":   PN = "EC26"  !CDS_PN = "EC26";
"DDR4_DQS_DP<7>":   PN = "DJ26"  !CDS_PN = "DJ26";
"DDR4_DQS_DP<8>":   PN = "DY67"  !CDS_PN = "DY67";
"DDR4_DQS_DP<9>":   PN = "CP79"  !CDS_PN = "CP79";
"DDR4_DQS_DP<10>":   PN = "DD79"  !CDS_PN = "DD79";
"DDR4_DQS_DP<11>":   PN = "DV79"  !CDS_PN = "DV79";
"DDR4_DQS_DP<12>":   PN = "DY73"  !CDS_PN = "DY73";
"DDR4_DQS_DP<13>":   PN = "DM41"  !CDS_PN = "DM41";
"DDR4_DQS_DP<14>":   PN = "DW32"  !CDS_PN = "DW32";
"DDR4_DQS_DP<15>":   PN = "DW26"  !CDS_PN = "DW26";
"DDR4_DQS_DP<16>":   PN = "DE26"  !CDS_PN = "DE26";
"DDR4_DQS_DP<17>":   PN = "DT67"  !CDS_PN = "DT67";
"DDR4_ECC<0>":   PN = "DY69"  !CDS_PN = "DY69";
"DDR4_ECC<1>":   PN = "EA68"  !CDS_PN = "EA68";
"DDR4_ECC<2>":   PN = "DV65"  !CDS_PN = "DV65";
"DDR4_ECC<3>":   PN = "DY65"  !CDS_PN = "DY65";
"DDR4_ECC<4>":   PN = "DU68"  !CDS_PN = "DU68";
"DDR4_ECC<5>":   PN = "DV69"  !CDS_PN = "DV69";
"DDR4_ECC<6>":   PN = "DU66"  !CDS_PN = "DU66";
"DDR4_ECC<7>":   PN = "EA66"  !CDS_PN = "EA66";
"DDR4_MA<0>":   PN = "DW52"  !CDS_PN = "DW52";
"DDR4_MA<1>":   PN = "DW58"  !CDS_PN = "DW58";
"DDR4_MA<2>":   PN = "DV57"  !CDS_PN = "DV57";
"DDR4_MA<3>":   PN = "DR58"  !CDS_PN = "DR58";
"DDR4_MA<4>":   PN = "DT59"  !CDS_PN = "DT59";
"DDR4_MA<5>":   PN = "DN58"  !CDS_PN = "DN58";
"DDR4_MA<6>":   PN = "DM59"  !CDS_PN = "DM59";
"DDR4_MA<7>":   PN = "DK61"  !CDS_PN = "DK61";
"DDR4_MA<8>":   PN = "DJ60"  !CDS_PN = "DJ60";
"DDR4_MA<9>":   PN = "DV59"  !CDS_PN = "DV59";
"DDR4_MA<10>":   PN = "DT55"  !CDS_PN = "DT55";
"DDR4_MA<11>":   PN = "DR60"  !CDS_PN = "DR60";
"DDR4_MA<12>":   PN = "DN60"  !CDS_PN = "DN60";
"DDR4_MA<13>":   PN = "DT51"  !CDS_PN = "DT51";
"DDR4_MA<14>":   PN = "DM51"  !CDS_PN = "DM51";
"DDR4_MA<15>":   PN = "DR52"  !CDS_PN = "DR52";
"DDR4_MA<16>":   PN = "DN52"  !CDS_PN = "DN52";
"DDR4_MA<17>":   PN = "DR48"  !CDS_PN = "DR48";
"DDR4_ODT<0>":   PN = "DR50"  !CDS_PN = "DR50";
"DDR4_ODT<1>":   PN = "DN48"  !CDS_PN = "DN48";
"DDR4_ODT<2>":   PN = "DT49"  !CDS_PN = "DT49";
"DDR4_ODT<3>":   PN = "DM47"  !CDS_PN = "DM47";
"DDR4_PAR":   PN = "DV53"  !CDS_PN = "DV53";
DRAWING = "@baseboard_fab2_lib.baseboard_fab2(sch_1):page62";
BODY = "SKX_EXT_B","I172": #LOCATION = "U2D1" !CDS_LOCATION = "U2D1" #SEC = "8" !CDS_SEC = "8";
"DDR5_ACT_N":   PN = "DC62"  !CDS_PN = "DC62";
"DDR5_ALERT_N":   PN = "DD61"  !CDS_PN = "DD61";
"DDR5_BA<0>":   PN = "DJ52"  !CDS_PN = "DJ52";
"DDR5_BA<1>":   PN = "DC56"  !CDS_PN = "DC56";
"DDR5_BG<0>":   PN = "DA62"  !CDS_PN = "DA62";
"DDR5_BG<1>":   PN = "DF61"  !CDS_PN = "DF61";
"DDR5_CID<2>":   PN = "DF45"  !CDS_PN = "DF45";
"DDR5_CKE<0>":   PN = "DG62"  !CDS_PN = "DG62";
"DDR5_CKE<1>":   PN = "DD63"  !CDS_PN = "DD63";
"DDR5_CKE<2>":   PN = "DK63"  !CDS_PN = "DK63";
"DDR5_CKE<3>":   PN = "DF63"  !CDS_PN = "DF63";
"DDR5_CLK_DN<0>":   PN = "DK55"  !CDS_PN = "DK55";
"DDR5_CLK_DN<1>":   PN = "DF55"  !CDS_PN = "DF55";
"DDR5_CLK_DN<2>":   PN = "DK57"  !CDS_PN = "DK57";
"DDR5_CLK_DN<3>":   PN = "DF57"  !CDS_PN = "DF57";
"DDR5_CLK_DP<0>":   PN = "DJ54"  !CDS_PN = "DJ54";
"DDR5_CLK_DP<1>":   PN = "DG54"  !CDS_PN = "DG54";
"DDR5_CLK_DP<2>":   PN = "DJ56"  !CDS_PN = "DJ56";
"DDR5_CLK_DP<3>":   PN = "DG56"  !CDS_PN = "DG56";
"DDR5_CS<0>_N":   PN = "DK51"  !CDS_PN = "DK51";
"DDR5_CS<1>_N":   PN = "DF49"  !CDS_PN = "DF49";
"DDR5_CS<2>_N":   PN = "DJ46"  !CDS_PN = "DJ46";
"DDR5_CS<3>_N":   PN = "DG46"  !CDS_PN = "DG46";
"DDR5_CS<4>_N":   PN = "DF51"  !CDS_PN = "DF51";
"DDR5_CS<5>_N":   PN = "DJ48"  !CDS_PN = "DJ48";
"DDR5_CS<6>_N":   PN = "DM45"  !CDS_PN = "DM45";
"DDR5_CS<7>_N":   PN = "DK45"  !CDS_PN = "DK45";
"DDR5_DQ<0>":   PN = "CR74"  !CDS_PN = "CR74";
"DDR5_DQ<1>":   PN = "CN76"  !CDS_PN = "CN76";
"DDR5_DQ<2>":   PN = "CW76"  !CDS_PN = "CW76";
"DDR5_DQ<3>":   PN = "CV77"  !CDS_PN = "CV77";
"DDR5_DQ<4>":   PN = "CN74"  !CDS_PN = "CN74";
"DDR5_DQ<5>":   PN = "CM75"  !CDS_PN = "CM75";
"DDR5_DQ<6>":   PN = "CV75"  !CDS_PN = "CV75";
"DDR5_DQ<7>":   PN = "CT77"  !CDS_PN = "CT77";
"DDR5_DQ<8>":   PN = "DE74"  !CDS_PN = "DE74";
"DDR5_DQ<9>":   PN = "DC76"  !CDS_PN = "DC76";
"DDR5_DQ<10>":   PN = "DH75"  !CDS_PN = "DH75";
"DDR5_DQ<11>":   PN = "DJ76"  !CDS_PN = "DJ76";
"DDR5_DQ<12>":   PN = "DC74"  !CDS_PN = "DC74";
"DDR5_DQ<13>":   PN = "DB75"  !CDS_PN = "DB75";
"DDR5_DQ<14>":   PN = "DF77"  !CDS_PN = "DF77";
"DDR5_DQ<15>":   PN = "DH77"  !CDS_PN = "DH77";
"DDR5_DQ<16>":   PN = "DG70"  !CDS_PN = "DG70";
"DDR5_DQ<17>":   PN = "DJ72"  !CDS_PN = "DJ72";
"DDR5_DQ<18>":   PN = "DM69"  !CDS_PN = "DM69";
"DDR5_DQ<19>":   PN = "DN70"  !CDS_PN = "DN70";
"DDR5_DQ<20>":   PN = "DF71"  !CDS_PN = "DF71";
"DDR5_DQ<21>":   PN = "DG72"  !CDS_PN = "DG72";
"DDR5_DQ<22>":   PN = "DK69"  !CDS_PN = "DK69";
"DDR5_DQ<23>":   PN = "DM71"  !CDS_PN = "DM71";
"DDR5_DQ<24>":   PN = "CN66"  !CDS_PN = "CN66";
"DDR5_DQ<25>":   PN = "CU66"  !CDS_PN = "CU66";
"DDR5_DQ<26>":   PN = "CP63"  !CDS_PN = "CP63";
"DDR5_DQ<27>":   PN = "CT63"  !CDS_PN = "CT63";
"DDR5_DQ<28>":   PN = "CP67"  !CDS_PN = "CP67";
"DDR5_DQ<29>":   PN = "CT67"  !CDS_PN = "CT67";
"DDR5_DQ<30>":   PN = "CN64"  !CDS_PN = "CN64";
"DDR5_DQ<31>":   PN = "CU64"  !CDS_PN = "CU64";
"DDR5_DQ<32>":   PN = "DD41"  !CDS_PN = "DD41";
"DDR5_DQ<33>":   PN = "DG42"  !CDS_PN = "DG42";
"DDR5_DQ<34>":   PN = "DE38"  !CDS_PN = "DE38";
"DDR5_DQ<35>":   PN = "DG38"  !CDS_PN = "DG38";
"DDR5_DQ<36>":   PN = "DA42"  !CDS_PN = "DA42";
"DDR5_DQ<37>":   PN = "DE42"  !CDS_PN = "DE42";
"DDR5_DQ<38>":   PN = "DD39"  !CDS_PN = "DD39";
"DDR5_DQ<39>":   PN = "DH39"  !CDS_PN = "DH39";
"DDR5_DQ<40>":   PN = "DF33"  !CDS_PN = "DF33";
"DDR5_DQ<41>":   PN = "DK33"  !CDS_PN = "DK33";
"DDR5_DQ<42>":   PN = "DG30"  !CDS_PN = "DG30";
"DDR5_DQ<43>":   PN = "DJ30"  !CDS_PN = "DJ30";
"DDR5_DQ<44>":   PN = "DG34"  !CDS_PN = "DG34";
"DDR5_DQ<45>":   PN = "DJ34"  !CDS_PN = "DJ34";
"DDR5_DQ<46>":   PN = "DF31"  !CDS_PN = "DF31";
"DDR5_DQ<47>":   PN = "DK31"  !CDS_PN = "DK31";
"DDR5_DQ<48>":   PN = "CW36"  !CDS_PN = "CW36";
"DDR5_DQ<49>":   PN = "DC36"  !CDS_PN = "DC36";
"DDR5_DQ<50>":   PN = "CY33"  !CDS_PN = "CY33";
"DDR5_DQ<51>":   PN = "DB33"  !CDS_PN = "DB33";
"DDR5_DQ<52>":   PN = "CY37"  !CDS_PN = "CY37";
"DDR5_DQ<53>":   PN = "DB37"  !CDS_PN = "DB37";
"DDR5_DQ<54>":   PN = "CW34"  !CDS_PN = "CW34";
"DDR5_DQ<55>":   PN = "DC34"  !CDS_PN = "DC34";
"DDR5_DQ<56>":   PN = "CW30"  !CDS_PN = "CW30";
"DDR5_DQ<57>":   PN = "DC30"  !CDS_PN = "DC30";
"DDR5_DQ<58>":   PN = "CY27"  !CDS_PN = "CY27";
"DDR5_DQ<59>":   PN = "DB27"  !CDS_PN = "DB27";
"DDR5_DQ<60>":   PN = "CY31"  !CDS_PN = "CY31";
"DDR5_DQ<61>":   PN = "DB31"  !CDS_PN = "DB31";
"DDR5_DQ<62>":   PN = "CW28"  !CDS_PN = "CW28";
"DDR5_DQ<63>":   PN = "DC28"  !CDS_PN = "DC28";
"DDR5_DQS_DN<0>":   PN = "CP77"  !CDS_PN = "CP77";
"DDR5_DQS_DN<1>":   PN = "DD77"  !CDS_PN = "DD77";
"DDR5_DQS_DN<2>":   PN = "DL72"  !CDS_PN = "DL72";
"DDR5_DQS_DN<3>":   PN = "CV65"  !CDS_PN = "CV65";
"DDR5_DQS_DN<4>":   PN = "DG40"  !CDS_PN = "DG40";
"DDR5_DQS_DN<5>":   PN = "DL32"  !CDS_PN = "DL32";
"DDR5_DQS_DN<6>":   PN = "DD35"  !CDS_PN = "DD35";
"DDR5_DQS_DN<7>":   PN = "DD29"  !CDS_PN = "DD29";
"DDR5_DQS_DN<8>":   PN = "CN70"  !CDS_PN = "CN70";
"DDR5_DQS_DN<9>":   PN = "CT75"  !CDS_PN = "CT75";
"DDR5_DQS_DN<10>":   PN = "DF75"  !CDS_PN = "DF75";
"DDR5_DQS_DN<11>":   PN = "DJ70"  !CDS_PN = "DJ70";
"DDR5_DQS_DN<12>":   PN = "CP65"  !CDS_PN = "CP65";
"DDR5_DQS_DN<13>":   PN = "DE40"  !CDS_PN = "DE40";
"DDR5_DQS_DN<14>":   PN = "DG32"  !CDS_PN = "DG32";
"DDR5_DQS_DN<15>":   PN = "CY35"  !CDS_PN = "CY35";
"DDR5_DQS_DN<16>":   PN = "CY29"  !CDS_PN = "CY29";
"DDR5_DQS_DN<17>":   PN = "CJ70"  !CDS_PN = "CJ70";
"DDR5_DQS_DP<0>":   PN = "CR76"  !CDS_PN = "CR76";
"DDR5_DQS_DP<1>":   PN = "DE76"  !CDS_PN = "DE76";
"DDR5_DQS_DP<2>":   PN = "DK71"  !CDS_PN = "DK71";
"DDR5_DQS_DP<3>":   PN = "CT65"  !CDS_PN = "CT65";
"DDR5_DQS_DP<4>":   PN = "DJ40"  !CDS_PN = "DJ40";
"DDR5_DQS_DP<5>":   PN = "DJ32"  !CDS_PN = "DJ32";
"DDR5_DQS_DP<6>":   PN = "DB35"  !CDS_PN = "DB35";
"DDR5_DQS_DP<7>":   PN = "DB29"  !CDS_PN = "DB29";
"DDR5_DQS_DP<8>":   PN = "CL70"  !CDS_PN = "CL70";
"DDR5_DQS_DP<9>":   PN = "CU74"  !CDS_PN = "CU74";
"DDR5_DQS_DP<10>":   PN = "DG74"  !CDS_PN = "DG74";
"DDR5_DQS_DP<11>":   PN = "DH69"  !CDS_PN = "DH69";
"DDR5_DQS_DP<12>":   PN = "CM65"  !CDS_PN = "CM65";
"DDR5_DQS_DP<13>":   PN = "DC40"  !CDS_PN = "DC40";
"DDR5_DQS_DP<14>":   PN = "DE32"  !CDS_PN = "DE32";
"DDR5_DQS_DP<15>":   PN = "CV35"  !CDS_PN = "CV35";
"DDR5_DQS_DP<16>":   PN = "CV29"  !CDS_PN = "CV29";
"DDR5_DQS_DP<17>":   PN = "CG70"  !CDS_PN = "CG70";
"DDR5_ECC<0>":   PN = "CH71"  !CDS_PN = "CH71";
"DDR5_ECC<1>":   PN = "CM71"  !CDS_PN = "CM71";
"DDR5_ECC<2>":   PN = "CJ68"  !CDS_PN = "CJ68";
"DDR5_ECC<3>":   PN = "CL68"  !CDS_PN = "CL68";
"DDR5_ECC<4>":   PN = "CJ72"  !CDS_PN = "CJ72";
"DDR5_ECC<5>":   PN = "CL72"  !CDS_PN = "CL72";
"DDR5_ECC<6>":   PN = "CH69"  !CDS_PN = "CH69";
"DDR5_ECC<7>":   PN = "CM69"  !CDS_PN = "CM69";
"DDR5_MA<0>":   PN = "DF53"  !CDS_PN = "DF53";
"DDR5_MA<1>":   PN = "DC58"  !CDS_PN = "DC58";
"DDR5_MA<2>":   PN = "DD57"  !CDS_PN = "DD57";
"DDR5_MA<3>":   PN = "DG58"  !CDS_PN = "DG58";
"DDR5_MA<4>":   PN = "DJ58"  !CDS_PN = "DJ58";
"DDR5_MA<5>":   PN = "DF59"  !CDS_PN = "DF59";
"DDR5_MA<6>":   PN = "DK59"  !CDS_PN = "DK59";
"DDR5_MA<7>":   PN = "DC60"  !CDS_PN = "DC60";
"DDR5_MA<8>":   PN = "DD59"  !CDS_PN = "DD59";
"DDR5_MA<9>":   PN = "DA58"  !CDS_PN = "DA58";
"DDR5_MA<10>":   PN = "DD55"  !CDS_PN = "DD55";
"DDR5_MA<11>":   PN = "DA60"  !CDS_PN = "DA60";
"DDR5_MA<12>":   PN = "DG60"  !CDS_PN = "DG60";
"DDR5_MA<13>":   PN = "DD53"  !CDS_PN = "DD53";
"DDR5_MA<14>":   PN = "DJ50"  !CDS_PN = "DJ50";
"DDR5_MA<15>":   PN = "DC54"  !CDS_PN = "DC54";
"DDR5_MA<16>":   PN = "DG52"  !CDS_PN = "DG52";
"DDR5_MA<17>":   PN = "DE46"  !CDS_PN = "DE46";
"DDR5_ODT<0>":   PN = "DG50"  !CDS_PN = "DG50";
"DDR5_ODT<1>":   PN = "DG48"  !CDS_PN = "DG48";
"DDR5_ODT<2>":   PN = "DK49"  !CDS_PN = "DK49";
"DDR5_ODT<3>":   PN = "DF47"  !CDS_PN = "DF47";
"DDR5_PAR":   PN = "DK53"  !CDS_PN = "DK53";
DRAWING = "@baseboard_fab2_lib.baseboard_fab2(sch_1):page63";
BODY = "SKX_EXT_B","I23": #LOCATION = "U2D1" !CDS_LOCATION = "U2D1" #SEC = "9" !CDS_SEC = "9";
"CD_HFI0_I2CCLK":   PN = "BN22"  !CDS_PN = "BN22";
"CD_HFI0_I2CDAT":   PN = "BP23"  !CDS_PN = "BP23";
"CD_HFI0_INT_N":   PN = "BP19"  !CDS_PN = "BP19";
"CD_HFI0_LED_N":   PN = "BK21"  !CDS_PN = "BK21";
"CD_HFI0_MODPRST_N":   PN = "BR20"  !CDS_PN = "BR20";
"CD_HFI0_RESET_N":   PN = "BN24"  !CDS_PN = "BN24";
"CD_HFI1_I2CCLK":   PN = "BJ22"  !CDS_PN = "BJ22";
"CD_HFI1_I2CDAT":   PN = "BH23"  !CDS_PN = "BH23";
"CD_HFI1_INT_N":   PN = "BM21"  !CDS_PN = "BM21";
"CD_HFI1_LED_N":   PN = "BM23"  !CDS_PN = "BM23";
"CD_HFI1_MODPRST_N":   PN = "BT19"  !CDS_PN = "BT19";
"CD_HFI1_RESET_N":   PN = "BK23"  !CDS_PN = "BK23";
"CD_HFI_REFCLK_DN":   PN = "BE16"  !CDS_PN = "BE16";
"CD_HFI_REFCLK_DP":   PN = "BG16"  !CDS_PN = "BG16";
"CD_PE_REFCLK_DN":   PN = "BU24"  !CDS_PN = "BU24";
"CD_PE_REFCLK_DP":   PN = "BW24"  !CDS_PN = "BW24";
"CD_POR_N":   PN = "CF25"  !CDS_PN = "CF25";
"CD_TCLK":   PN = "CB23"  !CDS_PN = "CB23";
"CD_TDI":   PN = "BY21"  !CDS_PN = "BY21";
"CD_TDO":   PN = "CC22"  !CDS_PN = "CC22";
"CD_TMS":   PN = "CE24"  !CDS_PN = "CE24";
"CD_TRST_N":   PN = "CD23"  !CDS_PN = "CD23";
"DMI_RX_DN<0>":   PN = "CK9"  !CDS_PN = "CK9";
"DMI_RX_DN<1>":   PN = "CM11"  !CDS_PN = "CM11";
"DMI_RX_DN<2>":   PN = "CR12"  !CDS_PN = "CR12";
"DMI_RX_DN<3>":   PN = "CT11"  !CDS_PN = "CT11";
"DMI_RX_DP<0>":   PN = "CL10"  !CDS_PN = "CL10";
"DMI_RX_DP<1>":   PN = "CN10"  !CDS_PN = "CN10";
"DMI_RX_DP<2>":   PN = "CP11"  !CDS_PN = "CP11";
"DMI_RX_DP<3>":   PN = "CV11"  !CDS_PN = "CV11";
"DMI_TX_DN<0>":   PN = "CG4"  !CDS_PN = "CG4";
"DMI_TX_DN<1>":   PN = "CJ4"  !CDS_PN = "CJ4";
"DMI_TX_DN<2>":   PN = "CN4"  !CDS_PN = "CN4";
"DMI_TX_DN<3>":   PN = "CP5"  !CDS_PN = "CP5";
"DMI_TX_DP<0>":   PN = "CH5"  !CDS_PN = "CH5";
"DMI_TX_DP<1>":   PN = "CL4"  !CDS_PN = "CL4";
"DMI_TX_DP<2>":   PN = "CM3"  !CDS_PN = "CM3";
"DMI_TX_DP<3>":   PN = "CR4"  !CDS_PN = "CR4";
"RSVD<172>":   PN = "BA76"  !CDS_PN = "BA76";
"RSVD<173>":   PN = "BA66"  !CDS_PN = "BA66";
"RSVD<174>":   PN = "BA64"  !CDS_PN = "BA64";
"RSVD<175>":   PN = "BA22"  !CDS_PN = "BA22";
"RSVD<176>":   PN = "BA18"  !CDS_PN = "BA18";
"RSVD<177>":   PN = "BA16"  !CDS_PN = "BA16";
"RSVD<178>":   PN = "BA14"  !CDS_PN = "BA14";
"RSVD<179>":   PN = "AY77"  !CDS_PN = "AY77";
"RSVD<180>":   PN = "AY75"  !CDS_PN = "AY75";
"RSVD<181>":   PN = "AY67"  !CDS_PN = "AY67";
"RSVD<182>":   PN = "AY65"  !CDS_PN = "AY65";
"RSVD<183>":   PN = "AW76"  !CDS_PN = "AW76";
"RSVD<184>":   PN = "AW64"  !CDS_PN = "AW64";
"RSVD<186>":   PN = "AV77"  !CDS_PN = "AV77";
"RSVD<187>":   PN = "AT25"  !CDS_PN = "AT25";
"RSVD<188>":   PN = "AT23"  !CDS_PN = "AT23";
"RSVD<189>":   PN = "AT13"  !CDS_PN = "AT13";
"RSVD<190>":   PN = "AR62"  !CDS_PN = "AR62";
"RSVD<191>":   PN = "AR26"  !CDS_PN = "AR26";
"RSVD<192>":   PN = "AR22"  !CDS_PN = "AR22";
"RSVD<193>":   PN = "AR20"  !CDS_PN = "AR20";
DRAWING = "@baseboard_fab2_lib.baseboard_fab2(sch_1):page64";
BODY = "SKX_EXT_B","I68": #LOCATION = "U2D1" !CDS_LOCATION = "U2D1" #SEC = "10" !CDS_SEC = "10";
"PE1_RX_DN<0>":   PN = "CW8"  !CDS_PN = "CW8";
"PE1_RX_DN<1>":   PN = "DA8"  !CDS_PN = "DA8";
"PE1_RX_DN<2>":   PN = "DC8"  !CDS_PN = "DC8";
"PE1_RX_DN<3>":   PN = "DC10"  !CDS_PN = "DC10";
"PE1_RX_DN<4>":   PN = "DE10"  !CDS_PN = "DE10";
"PE1_RX_DN<5>":   PN = "DH9"  !CDS_PN = "DH9";
"PE1_RX_DN<6>":   PN = "DK9"  !CDS_PN = "DK9";
"PE1_RX_DN<7>":   PN = "DM9"  !CDS_PN = "DM9";
"PE1_RX_DN<8>":   PN = "DM11"  !CDS_PN = "DM11";
"PE1_RX_DN<9>":   PN = "DP11"  !CDS_PN = "DP11";
"PE1_RX_DN<10>":   PN = "DT11"  !CDS_PN = "DT11";
"PE1_RX_DN<11>":   PN = "DT13"  !CDS_PN = "DT13";
"PE1_RX_DN<12>":   PN = "DV13"  !CDS_PN = "DV13";
"PE1_RX_DN<13>":   PN = "DW14"  !CDS_PN = "DW14";
"PE1_RX_DN<14>":   PN = "DY15"  !CDS_PN = "DY15";
"PE1_RX_DN<15>":   PN = "DU16"  !CDS_PN = "DU16";
"PE1_RX_DP<0>":   PN = "CU8"  !CDS_PN = "CU8";
"PE1_RX_DP<1>":   PN = "CY7"  !CDS_PN = "CY7";
"PE1_RX_DP<2>":   PN = "DB9"  !CDS_PN = "DB9";
"PE1_RX_DP<3>":   PN = "DA10"  !CDS_PN = "DA10";
"PE1_RX_DP<4>":   PN = "DD9"  !CDS_PN = "DD9";
"PE1_RX_DP<5>":   PN = "DF9"  !CDS_PN = "DF9";
"PE1_RX_DP<6>":   PN = "DJ8"  !CDS_PN = "DJ8";
"PE1_RX_DP<7>":   PN = "DL10"  !CDS_PN = "DL10";
"PE1_RX_DP<8>":   PN = "DK11"  !CDS_PN = "DK11";
"PE1_RX_DP<9>":   PN = "DN10"  !CDS_PN = "DN10";
"PE1_RX_DP<10>":   PN = "DR12"  !CDS_PN = "DR12";
"PE1_RX_DP<11>":   PN = "DP13"  !CDS_PN = "DP13";
"PE1_RX_DP<12>":   PN = "DU12"  !CDS_PN = "DU12";
"PE1_RX_DP<13>":   PN = "DY13"  !CDS_PN = "DY13";
"PE1_RX_DP<14>":   PN = "DV15"  !CDS_PN = "DV15";
"PE1_RX_DP<15>":   PN = "DT15"  !CDS_PN = "DT15";
"PE1_TX_DN<0>":   PN = "DA2"  !CDS_PN = "DA2";
"PE1_TX_DN<1>":   PN = "DC2"  !CDS_PN = "DC2";
"PE1_TX_DN<2>":   PN = "DE2"  !CDS_PN = "DE2";
"PE1_TX_DN<3>":   PN = "DE4"  !CDS_PN = "DE4";
"PE1_TX_DN<4>":   PN = "DG4"  !CDS_PN = "DG4";
"PE1_TX_DN<5>":   PN = "DK3"  !CDS_PN = "DK3";
"PE1_TX_DN<6>":   PN = "DM3"  !CDS_PN = "DM3";
"PE1_TX_DN<7>":   PN = "DN4"  !CDS_PN = "DN4";
"PE1_TX_DN<8>":   PN = "DT5"  !CDS_PN = "DT5";
"PE1_TX_DN<9>":   PN = "DV3"  !CDS_PN = "DV3";
"PE1_TX_DN<10>":   PN = "DW4"  !CDS_PN = "DW4";
"PE1_TX_DN<11>":   PN = "DU6"  !CDS_PN = "DU6";
"PE1_TX_DN<12>":   PN = "DV7"  !CDS_PN = "DV7";
"PE1_TX_DN<13>":   PN = "DY7"  !CDS_PN = "DY7";
"PE1_TX_DN<14>":   PN = "EA8"  !CDS_PN = "EA8";
"PE1_TX_DN<15>":   PN = "ED9"  !CDS_PN = "ED9";
"PE1_TX_DP<0>":   PN = "CW2"  !CDS_PN = "CW2";
"PE1_TX_DP<1>":   PN = "DB1"  !CDS_PN = "DB1";
"PE1_TX_DP<2>":   PN = "DD3"  !CDS_PN = "DD3";
"PE1_TX_DP<3>":   PN = "DC4"  !CDS_PN = "DC4";
"PE1_TX_DP<4>":   PN = "DF3"  !CDS_PN = "DF3";
"PE1_TX_DP<5>":   PN = "DH3"  !CDS_PN = "DH3";
"PE1_TX_DP<6>":   PN = "DL2"  !CDS_PN = "DL2";
"PE1_TX_DP<7>":   PN = "DP3"  !CDS_PN = "DP3";
"PE1_TX_DP<8>":   PN = "DR4"  !CDS_PN = "DR4";
"PE1_TX_DP<9>":   PN = "DU2"  !CDS_PN = "DU2";
"PE1_TX_DP<10>":   PN = "DU4"  !CDS_PN = "DU4";
"PE1_TX_DP<11>":   PN = "DV5"  !CDS_PN = "DV5";
"PE1_TX_DP<12>":   PN = "DT7"  !CDS_PN = "DT7";
"PE1_TX_DP<13>":   PN = "DW6"  !CDS_PN = "DW6";
"PE1_TX_DP<14>":   PN = "EB7"  !CDS_PN = "EB7";
"PE1_TX_DP<15>":   PN = "EC8"  !CDS_PN = "EC8";
DRAWING = "@baseboard_fab2_lib.baseboard_fab2(sch_1):page65";
BODY = "SKX_EXT_B","I68": #LOCATION = "U2D1" !CDS_LOCATION = "U2D1" #SEC = "11" !CDS_SEC = "11";
"PE2_RX_DN<0>":   PN = "CT9"  !CDS_PN = "CT9";
"PE2_RX_DN<1>":   PN = "CP9"  !CDS_PN = "CP9";
"PE2_RX_DN<2>":   PN = "CP7"  !CDS_PN = "CP7";
"PE2_RX_DN<3>":   PN = "CM7"  !CDS_PN = "CM7";
"PE2_RX_DN<4>":   PN = "CK7"  !CDS_PN = "CK7";
"PE2_RX_DN<5>":   PN = "CG8"  !CDS_PN = "CG8";
"PE2_RX_DN<6>":   PN = "CE6"  !CDS_PN = "CE6";
"PE2_RX_DN<7>":   PN = "CE8"  !CDS_PN = "CE8";
"PE2_RX_DN<8>":   PN = "BY9"  !CDS_PN = "BY9";
"PE2_RX_DN<9>":   PN = "BY7"  !CDS_PN = "BY7";
"PE2_RX_DN<10>":   PN = "BV7"  !CDS_PN = "BV7";
"PE2_RX_DN<11>":   PN = "BT7"  !CDS_PN = "BT7";
"PE2_RX_DN<12>":   PN = "BR8"  !CDS_PN = "BR8";
"PE2_RX_DN<13>":   PN = "BN8"  !CDS_PN = "BN8";
"PE2_RX_DN<14>":   PN = "BL8"  !CDS_PN = "BL8";
"PE2_RX_DN<15>":   PN = "BK9"  !CDS_PN = "BK9";
"PE2_RX_DP<0>":   PN = "CR8"  !CDS_PN = "CR8";
"PE2_RX_DP<1>":   PN = "CM9"  !CDS_PN = "CM9";
"PE2_RX_DP<2>":   PN = "CN8"  !CDS_PN = "CN8";
"PE2_RX_DP<3>":   PN = "CL6"  !CDS_PN = "CL6";
"PE2_RX_DP<4>":   PN = "CH7"  !CDS_PN = "CH7";
"PE2_RX_DP<5>":   PN = "CF7"  !CDS_PN = "CF7";
"PE2_RX_DP<6>":   PN = "CD7"  !CDS_PN = "CD7";
"PE2_RX_DP<7>":   PN = "CC8"  !CDS_PN = "CC8";
"PE2_RX_DP<8>":   PN = "BV9"  !CDS_PN = "BV9";
"PE2_RX_DP<9>":   PN = "BW8"  !CDS_PN = "BW8";
"PE2_RX_DP<10>":   PN = "BU6"  !CDS_PN = "BU6";
"PE2_RX_DP<11>":   PN = "BP7"  !CDS_PN = "BP7";
"PE2_RX_DP<12>":   PN = "BP9"  !CDS_PN = "BP9";
"PE2_RX_DP<13>":   PN = "BM7"  !CDS_PN = "BM7";
"PE2_RX_DP<14>":   PN = "BJ8"  !CDS_PN = "BJ8";
"PE2_RX_DP<15>":   PN = "BJ10"  !CDS_PN = "BJ10";
"PE2_TX_DN<0>":   PN = "CY3"  !CDS_PN = "CY3";
"PE2_TX_DN<1>":   PN = "CV3"  !CDS_PN = "CV3";
"PE2_TX_DN<2>":   PN = "CT1"  !CDS_PN = "CT1";
"PE2_TX_DN<3>":   PN = "CT3"  !CDS_PN = "CT3";
"PE2_TX_DN<4>":   PN = "CM1"  !CDS_PN = "CM1";
"PE2_TX_DN<5>":   PN = "CL2"  !CDS_PN = "CL2";
"PE2_TX_DN<6>":   PN = "CG2"  !CDS_PN = "CG2";
"PE2_TX_DN<7>":   PN = "CF3"  !CDS_PN = "CF3";
"PE2_TX_DN<8>":   PN = "CC2"  !CDS_PN = "CC2";
"PE2_TX_DN<9>":   PN = "CB3"  !CDS_PN = "CB3";
"PE2_TX_DN<10>":   PN = "CA4"  !CDS_PN = "CA4";
"PE2_TX_DN<11>":   PN = "BW4"  !CDS_PN = "BW4";
"PE2_TX_DN<12>":   PN = "BU4"  !CDS_PN = "BU4";
"PE2_TX_DN<13>":   PN = "BP5"  !CDS_PN = "BP5";
"PE2_TX_DN<14>":   PN = "BL4"  !CDS_PN = "BL4";
"PE2_TX_DN<15>":   PN = "BM5"  !CDS_PN = "BM5";
"PE2_TX_DP<0>":   PN = "CW4"  !CDS_PN = "CW4";
"PE2_TX_DP<1>":   PN = "CU2"  !CDS_PN = "CU2";
"PE2_TX_DP<2>":   PN = "CR2"  !CDS_PN = "CR2";
"PE2_TX_DP<3>":   PN = "CP3"  !CDS_PN = "CP3";
"PE2_TX_DP<4>":   PN = "CK1"  !CDS_PN = "CK1";
"PE2_TX_DP<5>":   PN = "CK3"  !CDS_PN = "CK3";
"PE2_TX_DP<6>":   PN = "CE2"  !CDS_PN = "CE2";
"PE2_TX_DP<7>":   PN = "CE4"  !CDS_PN = "CE4";
"PE2_TX_DP<8>":   PN = "CD3"  !CDS_PN = "CD3";
"PE2_TX_DP<9>":   PN = "BY3"  !CDS_PN = "BY3";
"PE2_TX_DP<10>":   PN = "BY5"  !CDS_PN = "BY5";
"PE2_TX_DP<11>":   PN = "BV3"  !CDS_PN = "BV3";
"PE2_TX_DP<12>":   PN = "BR4"  !CDS_PN = "BR4";
"PE2_TX_DP<13>":   PN = "BN4"  !CDS_PN = "BN4";
"PE2_TX_DP<14>":   PN = "BM3"  !CDS_PN = "BM3";
"PE2_TX_DP<15>":   PN = "BK5"  !CDS_PN = "BK5";
DRAWING = "@baseboard_fab2_lib.baseboard_fab2(sch_1):page66";
BODY = "SKX_EXT_B","I84": #LOCATION = "U2D1" !CDS_LOCATION = "U2D1" #SEC = "12" !CDS_SEC = "12";
"PE3_RX_DN<0>":   PN = "EA18"  !CDS_PN = "EA18";
"PE3_RX_DN<1>":   PN = "DW18"  !CDS_PN = "DW18";
"PE3_RX_DN<2>":   PN = "DW16"  !CDS_PN = "DW16";
"PE3_RX_DN<3>":   PN = "DT19"  !CDS_PN = "DT19";
"PE3_RX_DN<4>":   PN = "DR16"  !CDS_PN = "DR16";
"PE3_RX_DN<5>":   PN = "DR14"  !CDS_PN = "DR14";
"PE3_RX_DN<6>":   PN = "DN14"  !CDS_PN = "DN14";
"PE3_RX_DN<7>":   PN = "DL14"  !CDS_PN = "DL14";
"PE3_RX_DN<8>":   PN = "DL12"  !CDS_PN = "DL12";
"PE3_RX_DN<9>":   PN = "DJ12"  !CDS_PN = "DJ12";
"PE3_RX_DN<10>":   PN = "DG12"  !CDS_PN = "DG12";
"PE3_RX_DN<11>":   PN = "DG10"  !CDS_PN = "DG10";
"PE3_RX_DN<12>":   PN = "DD13"  !CDS_PN = "DD13";
"PE3_RX_DN<13>":   PN = "DB11"  !CDS_PN = "DB11";
"PE3_RX_DN<14>":   PN = "CY11"  !CDS_PN = "CY11";
"PE3_RX_DN<15>":   PN = "CV9"  !CDS_PN = "CV9";
"PE3_RX_DP<0>":   PN = "DY17"  !CDS_PN = "DY17";
"PE3_RX_DP<1>":   PN = "DU18"  !CDS_PN = "DU18";
"PE3_RX_DP<2>":   PN = "DV17"  !CDS_PN = "DV17";
"PE3_RX_DP<3>":   PN = "DR18"  !CDS_PN = "DR18";
"PE3_RX_DP<4>":   PN = "DN16"  !CDS_PN = "DN16";
"PE3_RX_DP<5>":   PN = "DP15"  !CDS_PN = "DP15";
"PE3_RX_DP<6>":   PN = "DM13"  !CDS_PN = "DM13";
"PE3_RX_DP<7>":   PN = "DJ14"  !CDS_PN = "DJ14";
"PE3_RX_DP<8>":   PN = "DK13"  !CDS_PN = "DK13";
"PE3_RX_DP<9>":   PN = "DH11"  !CDS_PN = "DH11";
"PE3_RX_DP<10>":   PN = "DE12"  !CDS_PN = "DE12";
"PE3_RX_DP<11>":   PN = "DF11"  !CDS_PN = "DF11";
"PE3_RX_DP<12>":   PN = "DC12"  !CDS_PN = "DC12";
"PE3_RX_DP<13>":   PN = "DA12"  !CDS_PN = "DA12";
"PE3_RX_DP<14>":   PN = "CW10"  !CDS_PN = "CW10";
"PE3_RX_DP<15>":   PN = "CU10"  !CDS_PN = "CU10";
"PE3_TX_DN<0>":   PN = "EE14"  !CDS_PN = "EE14";
"PE3_TX_DN<1>":   PN = "EE12"  !CDS_PN = "EE12";
"PE3_TX_DN<2>":   PN = "EC12"  !CDS_PN = "EC12";
"PE3_TX_DN<3>":   PN = "DY11"  !CDS_PN = "DY11";
"PE3_TX_DN<4>":   PN = "EB9"  !CDS_PN = "EB9";
"PE3_TX_DN<5>":   PN = "DW10"  !CDS_PN = "DW10";
"PE3_TX_DN<6>":   PN = "DU8"  !CDS_PN = "DU8";
"PE3_TX_DN<7>":   PN = "DR8"  !CDS_PN = "DR8";
"PE3_TX_DN<8>":   PN = "DM7"  !CDS_PN = "DM7";
"PE3_TX_DN<9>":   PN = "DP5"  !CDS_PN = "DP5";
"PE3_TX_DN<10>":   PN = "DL6"  !CDS_PN = "DL6";
"PE3_TX_DN<11>":   PN = "DJ4"  !CDS_PN = "DJ4";
"PE3_TX_DN<12>":   PN = "DJ6"  !CDS_PN = "DJ6";
"PE3_TX_DN<13>":   PN = "DD5"  !CDS_PN = "DD5";
"PE3_TX_DN<14>":   PN = "DB5"  !CDS_PN = "DB5";
"PE3_TX_DN<15>":   PN = "CY5"  !CDS_PN = "CY5";
"PE3_TX_DP<0>":   PN = "EC14"  !CDS_PN = "EC14";
"PE3_TX_DP<1>":   PN = "ED13"  !CDS_PN = "ED13";
"PE3_TX_DP<2>":   PN = "EB11"  !CDS_PN = "EB11";
"PE3_TX_DP<3>":   PN = "EA10"  !CDS_PN = "EA10";
"PE3_TX_DP<4>":   PN = "DY9"  !CDS_PN = "DY9";
"PE3_TX_DP<5>":   PN = "DV9"  !CDS_PN = "DV9";
"PE3_TX_DP<6>":   PN = "DT9"  !CDS_PN = "DT9";
"PE3_TX_DP<7>":   PN = "DP7"  !CDS_PN = "DP7";
"PE3_TX_DP<8>":   PN = "DN6"  !CDS_PN = "DN6";
"PE3_TX_DP<9>":   PN = "DM5"  !CDS_PN = "DM5";
"PE3_TX_DP<10>":   PN = "DK5"  !CDS_PN = "DK5";
"PE3_TX_DP<11>":   PN = "DH5"  !CDS_PN = "DH5";
"PE3_TX_DP<12>":   PN = "DG6"  !CDS_PN = "DG6";
"PE3_TX_DP<13>":   PN = "DC6"  !CDS_PN = "DC6";
"PE3_TX_DP<14>":   PN = "DA4"  !CDS_PN = "DA4";
"PE3_TX_DP<15>":   PN = "CV5"  !CDS_PN = "CV5";
DRAWING = "@baseboard_fab2_lib.baseboard_fab2(sch_1):page67";
BODY = "SKX_EXT_B","I132": #LOCATION = "U2D1" !CDS_LOCATION = "U2D1" #SEC = "13" !CDS_SEC = "13";
"UPI0_RX_DN<0>":   PN = "AC10"  !CDS_PN = "AC10";
"UPI0_RX_DN<1>":   PN = "AA8"  !CDS_PN = "AA8";
"UPI0_RX_DN<2>":   PN = "AB7"  !CDS_PN = "AB7";
"UPI0_RX_DN<3>":   PN = "AD5"  !CDS_PN = "AD5";
"UPI0_RX_DN<4>":   PN = "AE6"  !CDS_PN = "AE6";
"UPI0_RX_DN<5>":   PN = "AG8"  !CDS_PN = "AG8";
"UPI0_RX_DN<6>":   PN = "AJ6"  !CDS_PN = "AJ6";
"UPI0_RX_DN<7>":   PN = "AL6"  !CDS_PN = "AL6";
"UPI0_RX_DN<8>":   PN = "AK7"  !CDS_PN = "AK7";
"UPI0_RX_DN<9>":   PN = "AM9"  !CDS_PN = "AM9";
"UPI0_RX_DN<10>":   PN = "AP7"  !CDS_PN = "AP7";
"UPI0_RX_DN<11>":   PN = "AR8"  !CDS_PN = "AR8";
"UPI0_RX_DN<12>":   PN = "AU10"  !CDS_PN = "AU10";
"UPI0_RX_DN<13>":   PN = "BA8"  !CDS_PN = "BA8";
"UPI0_RX_DN<14>":   PN = "BC6"  !CDS_PN = "BC6";
"UPI0_RX_DN<15>":   PN = "BD7"  !CDS_PN = "BD7";
"UPI0_RX_DN<16>":   PN = "AW8"  !CDS_PN = "AW8";
"UPI0_RX_DN<17>":   PN = "AY9"  !CDS_PN = "AY9";
"UPI0_RX_DN<18>":   PN = "BD9"  !CDS_PN = "BD9";
"UPI0_RX_DN<19>":   PN = "BB11"  !CDS_PN = "BB11";
"UPI0_RX_DP<0>":   PN = "AB9"  !CDS_PN = "AB9";
"UPI0_RX_DP<1>":   PN = "AC8"  !CDS_PN = "AC8";
"UPI0_RX_DP<2>":   PN = "AA6"  !CDS_PN = "AA6";
"UPI0_RX_DP<3>":   PN = "AC6"  !CDS_PN = "AC6";
"UPI0_RX_DP<4>":   PN = "AG6"  !CDS_PN = "AG6";
"UPI0_RX_DP<5>":   PN = "AF7"  !CDS_PN = "AF7";
"UPI0_RX_DP<6>":   PN = "AH7"  !CDS_PN = "AH7";
"UPI0_RX_DP<7>":   PN = "AK5"  !CDS_PN = "AK5";
"UPI0_RX_DP<8>":   PN = "AM7"  !CDS_PN = "AM7";
"UPI0_RX_DP<9>":   PN = "AL8"  !CDS_PN = "AL8";
"UPI0_RX_DP<10>":   PN = "AN8"  !CDS_PN = "AN8";
"UPI0_RX_DP<11>":   PN = "AU8"  !CDS_PN = "AU8";
"UPI0_RX_DP<12>":   PN = "AT9"  !CDS_PN = "AT9";
"UPI0_RX_DP<13>":   PN = "AY7"  !CDS_PN = "AY7";
"UPI0_RX_DP<14>":   PN = "BB7"  !CDS_PN = "BB7";
"UPI0_RX_DP<15>":   PN = "BF7"  !CDS_PN = "BF7";
"UPI0_RX_DP<16>":   PN = "AV9"  !CDS_PN = "AV9";
"UPI0_RX_DP<17>":   PN = "BB9"  !CDS_PN = "BB9";
"UPI0_RX_DP<18>":   PN = "BC10"  !CDS_PN = "BC10";
"UPI0_RX_DP<19>":   PN = "BA10"  !CDS_PN = "BA10";
"UPI0_TX_DN<0>":   PN = "N2"  !CDS_PN = "N2";
"UPI0_TX_DN<1>":   PN = "P1"  !CDS_PN = "P1";
"UPI0_TX_DN<2>":   PN = "V3"  !CDS_PN = "V3";
"UPI0_TX_DN<3>":   PN = "Y1"  !CDS_PN = "Y1";
"UPI0_TX_DN<4>":   PN = "AB3"  !CDS_PN = "AB3";
"UPI0_TX_DN<5>":   PN = "AC2"  !CDS_PN = "AC2";
"UPI0_TX_DN<6>":   PN = "AG4"  !CDS_PN = "AG4";
"UPI0_TX_DN<7>":   PN = "AE2"  !CDS_PN = "AE2";
"UPI0_TX_DN<8>":   PN = "AH3"  !CDS_PN = "AH3";
"UPI0_TX_DN<9>":   PN = "AL2"  !CDS_PN = "AL2";
"UPI0_TX_DN<10>":   PN = "AM3"  !CDS_PN = "AM3";
"UPI0_TX_DN<11>":   PN = "AN4"  !CDS_PN = "AN4";
"UPI0_TX_DN<12>":   PN = "AT1"  !CDS_PN = "AT1";
"UPI0_TX_DN<13>":   PN = "AT3"  !CDS_PN = "AT3";
"UPI0_TX_DN<14>":   PN = "AU4"  !CDS_PN = "AU4";
"UPI0_TX_DN<15>":   PN = "AV5"  !CDS_PN = "AV5";
"UPI0_TX_DN<16>":   PN = "BA4"  !CDS_PN = "BA4";
"UPI0_TX_DN<17>":   PN = "BB3"  !CDS_PN = "BB3";
"UPI0_TX_DN<18>":   PN = "BF3"  !CDS_PN = "BF3";
"UPI0_TX_DN<19>":   PN = "BG4"  !CDS_PN = "BG4";
"UPI0_TX_DP<0>":   PN = "M1"  !CDS_PN = "M1";
"UPI0_TX_DP<1>":   PN = "T1"  !CDS_PN = "T1";
"UPI0_TX_DP<2>":   PN = "Y3"  !CDS_PN = "Y3";
"UPI0_TX_DP<3>":   PN = "W2"  !CDS_PN = "W2";
"UPI0_TX_DP<4>":   PN = "AA2"  !CDS_PN = "AA2";
"UPI0_TX_DP<5>":   PN = "AD1"  !CDS_PN = "AD1";
"UPI0_TX_DP<6>":   PN = "AF3"  !CDS_PN = "AF3";
"UPI0_TX_DP<7>":   PN = "AG2"  !CDS_PN = "AG2";
"UPI0_TX_DP<8>":   PN = "AJ2"  !CDS_PN = "AJ2";
"UPI0_TX_DP<9>":   PN = "AK1"  !CDS_PN = "AK1";
"UPI0_TX_DP<10>":   PN = "AK3"  !CDS_PN = "AK3";
"UPI0_TX_DP<11>":   PN = "AP3"  !CDS_PN = "AP3";
"UPI0_TX_DP<12>":   PN = "AP1"  !CDS_PN = "AP1";
"UPI0_TX_DP<13>":   PN = "AR2"  !CDS_PN = "AR2";
"UPI0_TX_DP<14>":   PN = "AR4"  !CDS_PN = "AR4";
"UPI0_TX_DP<15>":   PN = "AW4"  !CDS_PN = "AW4";
"UPI0_TX_DP<16>":   PN = "AY3"  !CDS_PN = "AY3";
"UPI0_TX_DP<17>":   PN = "BC2"  !CDS_PN = "BC2";
"UPI0_TX_DP<18>":   PN = "BD3"  !CDS_PN = "BD3";
"UPI0_TX_DP<19>":   PN = "BH3"  !CDS_PN = "BH3";
DRAWING = "@baseboard_fab2_lib.baseboard_fab2(sch_1):page68";
BODY = "SKX_EXT_B","I125": #LOCATION = "U2D1" !CDS_LOCATION = "U2D1" #SEC = "14" !CDS_SEC = "14";
"UPI1_RX_DN<0>":   PN = "T5"  !CDS_PN = "T5";
"UPI1_RX_DN<1>":   PN = "P7"  !CDS_PN = "P7";
"UPI1_RX_DN<2>":   PN = "V7"  !CDS_PN = "V7";
"UPI1_RX_DN<3>":   PN = "T9"  !CDS_PN = "T9";
"UPI1_RX_DN<4>":   PN = "P9"  !CDS_PN = "P9";
"UPI1_RX_DN<5>":   PN = "R10"  !CDS_PN = "R10";
"UPI1_RX_DN<6>":   PN = "U12"  !CDS_PN = "U12";
"UPI1_RX_DN<7>":   PN = "L12"  !CDS_PN = "L12";
"UPI1_RX_DN<8>":   PN = "N14"  !CDS_PN = "N14";
"UPI1_RX_DN<9>":   PN = "R12"  !CDS_PN = "R12";
"UPI1_RX_DN<10>":   PN = "R16"  !CDS_PN = "R16";
"UPI1_RX_DN<11>":   PN = "P17"  !CDS_PN = "P17";
"UPI1_RX_DN<12>":   PN = "U16"  !CDS_PN = "U16";
"UPI1_RX_DN<13>":   PN = "W18"  !CDS_PN = "W18";
"UPI1_RX_DN<14>":   PN = "R20"  !CDS_PN = "R20";
"UPI1_RX_DN<15>":   PN = "U18"  !CDS_PN = "U18";
"UPI1_RX_DN<16>":   PN = "P21"  !CDS_PN = "P21";
"UPI1_RX_DN<17>":   PN = "V19"  !CDS_PN = "V19";
"UPI1_RX_DN<18>":   PN = "Y21"  !CDS_PN = "Y21";
"UPI1_RX_DN<19>":   PN = "AB19"  !CDS_PN = "AB19";
"UPI1_RX_DP<0>":   PN = "R6"  !CDS_PN = "R6";
"UPI1_RX_DP<1>":   PN = "T7"  !CDS_PN = "T7";
"UPI1_RX_DP<2>":   PN = "U8"  !CDS_PN = "U8";
"UPI1_RX_DP<3>":   PN = "R8"  !CDS_PN = "R8";
"UPI1_RX_DP<4>":   PN = "N10"  !CDS_PN = "N10";
"UPI1_RX_DP<5>":   PN = "U10"  !CDS_PN = "U10";
"UPI1_RX_DP<6>":   PN = "T11"  !CDS_PN = "T11";
"UPI1_RX_DP<7>":   PN = "N12"  !CDS_PN = "N12";
"UPI1_RX_DP<8>":   PN = "M13"  !CDS_PN = "M13";
"UPI1_RX_DP<9>":   PN = "P13"  !CDS_PN = "P13";
"UPI1_RX_DP<10>":   PN = "T15"  !CDS_PN = "T15";
"UPI1_RX_DP<11>":   PN = "N16"  !CDS_PN = "N16";
"UPI1_RX_DP<12>":   PN = "W16"  !CDS_PN = "W16";
"UPI1_RX_DP<13>":   PN = "V17"  !CDS_PN = "V17";
"UPI1_RX_DP<14>":   PN = "P19"  !CDS_PN = "P19";
"UPI1_RX_DP<15>":   PN = "T19"  !CDS_PN = "T19";
"UPI1_RX_DP<16>":   PN = "T21"  !CDS_PN = "T21";
"UPI1_RX_DP<17>":   PN = "Y19"  !CDS_PN = "Y19";
"UPI1_RX_DP<18>":   PN = "W20"  !CDS_PN = "W20";
"UPI1_RX_DP<19>":   PN = "AA20"  !CDS_PN = "AA20";
"UPI1_TX_DN<0>":   PN = "M3"  !CDS_PN = "M3";
"UPI1_TX_DN<1>":   PN = "L4"  !CDS_PN = "L4";
"UPI1_TX_DN<2>":   PN = "K5"  !CDS_PN = "K5";
"UPI1_TX_DN<3>":   PN = "J6"  !CDS_PN = "J6";
"UPI1_TX_DN<4>":   PN = "G6"  !CDS_PN = "G6";
"UPI1_TX_DN<5>":   PN = "H7"  !CDS_PN = "H7";
"UPI1_TX_DN<6>":   PN = "K9"  !CDS_PN = "K9";
"UPI1_TX_DN<7>":   PN = "D9"  !CDS_PN = "D9";
"UPI1_TX_DN<8>":   PN = "F11"  !CDS_PN = "F11";
"UPI1_TX_DN<9>":   PN = "G10"  !CDS_PN = "G10";
"UPI1_TX_DN<10>":   PN = "E12"  !CDS_PN = "E12";
"UPI1_TX_DN<11>":   PN = "G14"  !CDS_PN = "G14";
"UPI1_TX_DN<12>":   PN = "D15"  !CDS_PN = "D15";
"UPI1_TX_DN<13>":   PN = "F15"  !CDS_PN = "F15";
"UPI1_TX_DN<14>":   PN = "H17"  !CDS_PN = "H17";
"UPI1_TX_DN<15>":   PN = "K19"  !CDS_PN = "K19";
"UPI1_TX_DN<16>":   PN = "G18"  !CDS_PN = "G18";
"UPI1_TX_DN<17>":   PN = "J20"  !CDS_PN = "J20";
"UPI1_TX_DN<18>":   PN = "F21"  !CDS_PN = "F21";
"UPI1_TX_DN<19>":   PN = "H21"  !CDS_PN = "H21";
"UPI1_TX_DP<0>":   PN = "P3"  !CDS_PN = "P3";
"UPI1_TX_DP<1>":   PN = "K3"  !CDS_PN = "K3";
"UPI1_TX_DP<2>":   PN = "M5"  !CDS_PN = "M5";
"UPI1_TX_DP<3>":   PN = "H5"  !CDS_PN = "H5";
"UPI1_TX_DP<4>":   PN = "F7"  !CDS_PN = "F7";
"UPI1_TX_DP<5>":   PN = "K7"  !CDS_PN = "K7";
"UPI1_TX_DP<6>":   PN = "J8"  !CDS_PN = "J8";
"UPI1_TX_DP<7>":   PN = "F9"  !CDS_PN = "F9";
"UPI1_TX_DP<8>":   PN = "E10"  !CDS_PN = "E10";
"UPI1_TX_DP<9>":   PN = "H9"  !CDS_PN = "H9";
"UPI1_TX_DP<10>":   PN = "G12"  !CDS_PN = "G12";
"UPI1_TX_DP<11>":   PN = "F13"  !CDS_PN = "F13";
"UPI1_TX_DP<12>":   PN = "E14"  !CDS_PN = "E14";
"UPI1_TX_DP<13>":   PN = "H15"  !CDS_PN = "H15";
"UPI1_TX_DP<14>":   PN = "G16"  !CDS_PN = "G16";
"UPI1_TX_DP<15>":   PN = "L18"  !CDS_PN = "L18";
"UPI1_TX_DP<16>":   PN = "J18"  !CDS_PN = "J18";
"UPI1_TX_DP<17>":   PN = "H19"  !CDS_PN = "H19";
"UPI1_TX_DP<18>":   PN = "G20"  !CDS_PN = "G20";
"UPI1_TX_DP<19>":   PN = "K21"  !CDS_PN = "K21";
DRAWING = "@baseboard_fab2_lib.baseboard_fab2(sch_1):page69";
BODY = "SKX_EXT_B","I1": #LOCATION = "U2D1" !CDS_LOCATION = "U2D1" #SEC = "15" !CDS_SEC = "15";
"UPI2_RX_DN<0>":   PN = "DF23"  !CDS_PN = "DF23";
"UPI2_RX_DN<1>":   PN = "DE22"  !CDS_PN = "DE22";
"UPI2_RX_DN<2>":   PN = "DC22"  !CDS_PN = "DC22";
"UPI2_RX_DN<3>":   PN = "DB21"  !CDS_PN = "DB21";
"UPI2_RX_DN<4>":   PN = "DD19"  !CDS_PN = "DD19";
"UPI2_RX_DN<5>":   PN = "DA20"  !CDS_PN = "DA20";
"UPI2_RX_DN<6>":   PN = "CW20"  !CDS_PN = "CW20";
"UPI2_RX_DN<7>":   PN = "CV19"  !CDS_PN = "CV19";
"UPI2_RX_DN<8>":   PN = "CT21"  !CDS_PN = "CT21";
"UPI2_RX_DN<9>":   PN = "CR18"  !CDS_PN = "CR18";
"UPI2_RX_DN<10>":   PN = "CN20"  !CDS_PN = "CN20";
"UPI2_RX_DN<11>":   PN = "CP21"  !CDS_PN = "CP21";
"UPI2_RX_DN<12>":   PN = "CL16"  !CDS_PN = "CL16";
"UPI2_RX_DN<13>":   PN = "CJ18"  !CDS_PN = "CJ18";
"UPI2_RX_DN<14>":   PN = "CH17"  !CDS_PN = "CH17";
"UPI2_RX_DN<15>":   PN = "CE16"  !CDS_PN = "CE16";
"UPI2_RX_DN<16>":   PN = "CD15"  !CDS_PN = "CD15";
"UPI2_RX_DN<17>":   PN = "CF17"  !CDS_PN = "CF17";
"UPI2_RX_DN<18>":   PN = "CB15"  !CDS_PN = "CB15";
"UPI2_RX_DN<19>":   PN = "BY17"  !CDS_PN = "BY17";
"UPI2_RX_DP<0>":   PN = "DG22"  !CDS_PN = "DG22";
"UPI2_RX_DP<1>":   PN = "DD21"  !CDS_PN = "DD21";
"UPI2_RX_DP<2>":   PN = "DA22"  !CDS_PN = "DA22";
"UPI2_RX_DP<3>":   PN = "DC20"  !CDS_PN = "DC20";
"UPI2_RX_DP<4>":   PN = "DB19"  !CDS_PN = "DB19";
"UPI2_RX_DP<5>":   PN = "CY19"  !CDS_PN = "CY19";
"UPI2_RX_DP<6>":   PN = "CU20"  !CDS_PN = "CU20";
"UPI2_RX_DP<7>":   PN = "CW18"  !CDS_PN = "CW18";
"UPI2_RX_DP<8>":   PN = "CR20"  !CDS_PN = "CR20";
"UPI2_RX_DP<9>":   PN = "CN18"  !CDS_PN = "CN18";
"UPI2_RX_DP<10>":   PN = "CP19"  !CDS_PN = "CP19";
"UPI2_RX_DP<11>":   PN = "CM21"  !CDS_PN = "CM21";
"UPI2_RX_DP<12>":   PN = "CJ16"  !CDS_PN = "CJ16";
"UPI2_RX_DP<13>":   PN = "CK17"  !CDS_PN = "CK17";
"UPI2_RX_DP<14>":   PN = "CG16"  !CDS_PN = "CG16";
"UPI2_RX_DP<15>":   PN = "CF15"  !CDS_PN = "CF15";
"UPI2_RX_DP<16>":   PN = "CC14"  !CDS_PN = "CC14";
"UPI2_RX_DP<17>":   PN = "CD17"  !CDS_PN = "CD17";
"UPI2_RX_DP<18>":   PN = "BY15"  !CDS_PN = "BY15";
"UPI2_RX_DP<19>":   PN = "CA16"  !CDS_PN = "CA16";
"UPI2_TX_DN<0>":   PN = "DT21"  !CDS_PN = "DT21";
"UPI2_TX_DN<1>":   PN = "DM21"  !CDS_PN = "DM21";
"UPI2_TX_DN<2>":   PN = "DL20"  !CDS_PN = "DL20";
"UPI2_TX_DN<3>":   PN = "DG20"  !CDS_PN = "DG20";
"UPI2_TX_DN<4>":   PN = "DH19"  !CDS_PN = "DH19";
"UPI2_TX_DN<5>":   PN = "DK17"  !CDS_PN = "DK17";
"UPI2_TX_DN<6>":   PN = "DG18"  !CDS_PN = "DG18";
"UPI2_TX_DN<7>":   PN = "DD17"  !CDS_PN = "DD17";
"UPI2_TX_DN<8>":   PN = "DF15"  !CDS_PN = "DF15";
"UPI2_TX_DN<9>":   PN = "DC16"  !CDS_PN = "DC16";
"UPI2_TX_DN<10>":   PN = "DA16"  !CDS_PN = "DA16";
"UPI2_TX_DN<11>":   PN = "CW14"  !CDS_PN = "CW14";
"UPI2_TX_DN<12>":   PN = "CU14"  !CDS_PN = "CU14";
"UPI2_TX_DN<13>":   PN = "CM13"  !CDS_PN = "CM13";
"UPI2_TX_DN<14>":   PN = "CJ14"  !CDS_PN = "CJ14";
"UPI2_TX_DN<15>":   PN = "CF13"  !CDS_PN = "CF13";
"UPI2_TX_DN<16>":   PN = "CH11"  !CDS_PN = "CH11";
"UPI2_TX_DN<17>":   PN = "CE12"  !CDS_PN = "CE12";
"UPI2_TX_DN<18>":   PN = "CC10"  !CDS_PN = "CC10";
"UPI2_TX_DN<19>":   PN = "CC12"  !CDS_PN = "CC12";
"UPI2_TX_DP<0>":   PN = "DP21"  !CDS_PN = "DP21";
"UPI2_TX_DP<1>":   PN = "DN20"  !CDS_PN = "DN20";
"UPI2_TX_DP<2>":   PN = "DK19"  !CDS_PN = "DK19";
"UPI2_TX_DP<3>":   PN = "DJ20"  !CDS_PN = "DJ20";
"UPI2_TX_DP<4>":   PN = "DJ18"  !CDS_PN = "DJ18";
"UPI2_TX_DP<5>":   PN = "DH17"  !CDS_PN = "DH17";
"UPI2_TX_DP<6>":   PN = "DF17"  !CDS_PN = "DF17";
"UPI2_TX_DP<7>":   PN = "DE16"  !CDS_PN = "DE16";
"UPI2_TX_DP<8>":   PN = "DD15"  !CDS_PN = "DD15";
"UPI2_TX_DP<9>":   PN = "DB15"  !CDS_PN = "DB15";
"UPI2_TX_DP<10>":   PN = "CW16"  !CDS_PN = "CW16";
"UPI2_TX_DP<11>":   PN = "CV13"  !CDS_PN = "CV13";
"UPI2_TX_DP<12>":   PN = "CR14"  !CDS_PN = "CR14";
"UPI2_TX_DP<13>":   PN = "CK13"  !CDS_PN = "CK13";
"UPI2_TX_DP<14>":   PN = "CH13"  !CDS_PN = "CH13";
"UPI2_TX_DP<15>":   PN = "CG12"  !CDS_PN = "CG12";
"UPI2_TX_DP<16>":   PN = "CF11"  !CDS_PN = "CF11";
"UPI2_TX_DP<17>":   PN = "CD11"  !CDS_PN = "CD11";
"UPI2_TX_DP<18>":   PN = "CB11"  !CDS_PN = "CB11";
"UPI2_TX_DP<19>":   PN = "CA12"  !CDS_PN = "CA12";
DRAWING = "@baseboard_fab2_lib.baseboard_fab2(sch_1):page70";
BODY = "SKX_EXT_B","I9": #LOCATION = "U2D1" !CDS_LOCATION = "U2D1" #SEC = "16" !CDS_SEC = "16";
"RSVD<92>":   PN = "CH23"  !CDS_PN = "CH23";
"RSVD<93>":   PN = "CH21"  !CDS_PN = "CH21";
"RSVD<94>":   PN = "CG82"  !CDS_PN = "CG82";
"RSVD<95>":   PN = "CG78"  !CDS_PN = "CG78";
"RSVD<96>":   PN = "CG26"  !CDS_PN = "CG26";
"RSVD<97>":   PN = "CG24"  !CDS_PN = "CG24";
"RSVD<98>":   PN = "CG20"  !CDS_PN = "CG20";
"RSVD<99>":   PN = "CG10"  !CDS_PN = "CG10";
"RSVD<100>":   PN = "CF81"  !CDS_PN = "CF81";
"RSVD<101>":   PN = "CF79"  !CDS_PN = "CF79";
"RSVD<102>":   PN = "CF23"  !CDS_PN = "CF23";
"RSVD<103>":   PN = "CF21"  !CDS_PN = "CF21";
"RSVD<104>":   PN = "CF19"  !CDS_PN = "CF19";
"RSVD<105>":   PN = "CE80"  !CDS_PN = "CE80";
"RSVD<106>":   PN = "CE78"  !CDS_PN = "CE78";
"RSVD<107>":   PN = "CE22"  !CDS_PN = "CE22";
"RSVD<108>":   PN = "CD25"  !CDS_PN = "CD25";
"RSVD<109>":   PN = "CD21"  !CDS_PN = "CD21";
"RSVD<110>":   PN = "CD19"  !CDS_PN = "CD19";
"RSVD<111>":   PN = "CC6"  !CDS_PN = "CC6";
"RSVD<112>":   PN = "CC20"  !CDS_PN = "CC20";
"RSVD<113>":   PN = "CB5"  !CDS_PN = "CB5";
"RSVD<114>":   PN = "CB25"  !CDS_PN = "CB25";
"RSVD<115>":   PN = "CB21"  !CDS_PN = "CB21";
"RSVD<116>":   PN = "CB19"  !CDS_PN = "CB19";
"RSVD<117>":   PN = "CA24"  !CDS_PN = "CA24";
"RSVD<118>":   PN = "CA22"  !CDS_PN = "CA22";
"RSVD<119>":   PN = "BY25"  !CDS_PN = "BY25";
"RSVD<120>":   PN = "BY19"  !CDS_PN = "BY19";
"RSVD<121>":   PN = "BW22"  !CDS_PN = "BW22";
"RSVD<122>":   PN = "BW20"  !CDS_PN = "BW20";
"RSVD<123>":   PN = "BW10"  !CDS_PN = "BW10";
"RSVD<124>":   PN = "BV23"  !CDS_PN = "BV23";
"RSVD<125>":   PN = "BV21"  !CDS_PN = "BV21";
"RSVD<126>":   PN = "BV19"  !CDS_PN = "BV19";
"RSVD<127>":   PN = "BU22"  !CDS_PN = "BU22";
"RSVD<128>":   PN = "BU20"  !CDS_PN = "BU20";
"RSVD<129>":   PN = "BU18"  !CDS_PN = "BU18";
"RSVD<130>":   PN = "BR24"  !CDS_PN = "BR24";
"RSVD<131>":   PN = "BR22"  !CDS_PN = "BR22";
"RSVD<132>":   PN = "BP21"  !CDS_PN = "BP21";
"RSVD<133>":   PN = "BP17"  !CDS_PN = "BP17";
"RSVD<134>":   PN = "BN18"  !CDS_PN = "BN18";
"RSVD<135>":   PN = "BM19"  !CDS_PN = "BM19";
"RSVD<136>":   PN = "BM17"  !CDS_PN = "BM17";
"RSVD<137>":   PN = "BL20"  !CDS_PN = "BL20";
"RSVD<138>":   PN = "BL18"  !CDS_PN = "BL18";
"RSVD<139>":   PN = "BK17"  !CDS_PN = "BK17";
"RSVD<140>":   PN = "BJ20"  !CDS_PN = "BJ20";
"RSVD<141>":   PN = "BJ18"  !CDS_PN = "BJ18";
"RSVD<142>":   PN = "BJ16"  !CDS_PN = "BJ16";
"RSVD<143>":   PN = "BH19"  !CDS_PN = "BH19";
"RSVD<144>":   PN = "BG20"  !CDS_PN = "BG20";
"RSVD<145>":   PN = "BG18"  !CDS_PN = "BG18";
"RSVD<146>":   PN = "BF21"  !CDS_PN = "BF21";
"RSVD<147>":   PN = "BE22"  !CDS_PN = "BE22";
"RSVD<148>":   PN = "BE20"  !CDS_PN = "BE20";
"RSVD<149>":   PN = "BE18"  !CDS_PN = "BE18";
"RSVD<150>":   PN = "BD69"  !CDS_PN = "BD69";
"RSVD<151>":   PN = "BD67"  !CDS_PN = "BD67";
"RSVD<152>":   PN = "BD65"  !CDS_PN = "BD65";
"RSVD<153>":   PN = "BD25"  !CDS_PN = "BD25";
"RSVD<154>":   PN = "BD19"  !CDS_PN = "BD19";
"RSVD<155>":   PN = "BD17"  !CDS_PN = "BD17";
"RSVD<156>":   PN = "BC68"  !CDS_PN = "BC68";
"RSVD<157>":   PN = "BC66"  !CDS_PN = "BC66";
"RSVD<158>":   PN = "BC64"  !CDS_PN = "BC64";
"RSVD<159>":   PN = "BC22"  !CDS_PN = "BC22";
"RSVD<160>":   PN = "BC20"  !CDS_PN = "BC20";
"RSVD<161>":   PN = "BC18"  !CDS_PN = "BC18";
"RSVD<162>":   PN = "BC14"  !CDS_PN = "BC14";
"RSVD<163>":   PN = "BB67"  !CDS_PN = "BB67";
"RSVD<164>":   PN = "BB65"  !CDS_PN = "BB65";
"RSVD<165>":   PN = "BB25"  !CDS_PN = "BB25";
"RSVD<166>":   PN = "BB21"  !CDS_PN = "BB21";
"RSVD<167>":   PN = "BB17"  !CDS_PN = "BB17";
"RSVD<168>":   PN = "BB15"  !CDS_PN = "BB15";
"RSVD<169>":   PN = "BB13"  !CDS_PN = "BB13";
"RSVD<170>":   PN = "BA82"  !CDS_PN = "BA82";
"RSVD<171>":   PN = "BA78"  !CDS_PN = "BA78";
"RSVD<255>":   PN = "AY83"  !CDS_PN = "AY83";
BODY = "SKX_EXT_B","I10": #LOCATION = "U2D1" !CDS_LOCATION = "U2D1" #SEC = "17" !CDS_SEC = "17";
"RSVD<81>":   PN = "CL24"  !CDS_PN = "CL24";
"RSVD<82>":   PN = "CK77"  !CDS_PN = "CK77";
"RSVD<83>":   PN = "CK25"  !CDS_PN = "CK25";
"RSVD<84>":   PN = "CK23"  !CDS_PN = "CK23";
"RSVD<85>":   PN = "CK19"  !CDS_PN = "CK19";
"RSVD<86>":   PN = "CJ26"  !CDS_PN = "CJ26";
"RSVD<87>":   PN = "CJ24"  !CDS_PN = "CJ24";
"RSVD<88>":   PN = "CJ22"  !CDS_PN = "CJ22";
"RSVD<89>":   PN = "CJ20"  !CDS_PN = "CJ20";
"RSVD<90>":   PN = "CH77"  !CDS_PN = "CH77";
"RSVD<91>":   PN = "CH25"  !CDS_PN = "CH25";
"TEST_6":   PN = "AR16"  !CDS_PN = "AR16";
"TEST_7":   PN = "AU18"  !CDS_PN = "AU18";
"TEST_8":   PN = "AW16"  !CDS_PN = "AW16";
"TEST_9":   PN = "AW20"  !CDS_PN = "AW20";
"TEST_10":   PN = "AW22"  !CDS_PN = "AW22";
DRAWING = "@baseboard_fab2_lib.baseboard_fab2(sch_1):page71";
BODY = "RES","I43": #LOCATION = "R3D27" !CDS_LOCATION = "R3D27" #SEC = "1" !CDS_SEC = "1";
"A":   PN = "1"  !CDS_PN = "1";
"B":   PN = "2"  !CDS_PN = "2";
BODY = "RES","I49": #LOCATION = "RT8P1" !CDS_LOCATION = "RT8P1" #SEC = "1" !CDS_SEC = "1";
"A":   PN = "1"  !CDS_PN = "1";
"B":   PN = "2"  !CDS_PN = "2";
BODY = "SKX_EXT_B","I50": #LOCATION = "U2D1" !CDS_LOCATION = "U2D1" #SEC = "18" !CDS_SEC = "18";
"VCCIN<130>":   PN = "BN78"  !CDS_PN = "BN78";
"VCCIN<131>":   PN = "BN76"  !CDS_PN = "BN76";
"VCCIN<132>":   PN = "BN74"  !CDS_PN = "BN74";
"VCCIN<133>":   PN = "BN72"  !CDS_PN = "BN72";
"VCCIN<134>":   PN = "BN70"  !CDS_PN = "BN70";
"VCCIN<135>":   PN = "BN68"  !CDS_PN = "BN68";
"VCCIN<136>":   PN = "BN66"  !CDS_PN = "BN66";
"VCCIN<137>":   PN = "BN64"  !CDS_PN = "BN64";
"VCCIN<138>":   PN = "BN62"  !CDS_PN = "BN62";
"VCCIN<139>":   PN = "BN60"  !CDS_PN = "BN60";
"VCCIN<140>":   PN = "BM83"  !CDS_PN = "BM83";
"VCCIN<141>":   PN = "BM81"  !CDS_PN = "BM81";
"VCCIN<142>":   PN = "BM79"  !CDS_PN = "BM79";
"VCCIN<143>":   PN = "BM77"  !CDS_PN = "BM77";
"VCCIN<144>":   PN = "BM75"  !CDS_PN = "BM75";
"VCCIN<145>":   PN = "BM73"  !CDS_PN = "BM73";
"VCCIN<146>":   PN = "BM71"  !CDS_PN = "BM71";
"VCCIN<147>":   PN = "BM69"  !CDS_PN = "BM69";
"VCCIN<148>":   PN = "BM67"  !CDS_PN = "BM67";
"VCCIN<149>":   PN = "BM65"  !CDS_PN = "BM65";
"VCCIN<150>":   PN = "BM63"  !CDS_PN = "BM63";
"VCCIN<151>":   PN = "BM61"  !CDS_PN = "BM61";
"VCCIN<152>":   PN = "BL84"  !CDS_PN = "BL84";
"VCCIN<153>":   PN = "BL62"  !CDS_PN = "BL62";
"VCCIN<154>":   PN = "BL60"  !CDS_PN = "BL60";
"VCCIN<155>":   PN = "BK83"  !CDS_PN = "BK83";
"VCCIN<156>":   PN = "BK81"  !CDS_PN = "BK81";
"VCCIN<157>":   PN = "BK79"  !CDS_PN = "BK79";
"VCCIN<158>":   PN = "BK77"  !CDS_PN = "BK77";
"VCCIN<159>":   PN = "BK75"  !CDS_PN = "BK75";
"VCCIN<160>":   PN = "BK73"  !CDS_PN = "BK73";
"VCCIN<161>":   PN = "BK71"  !CDS_PN = "BK71";
"VCCIN<162>":   PN = "BK69"  !CDS_PN = "BK69";
"VCCIN<163>":   PN = "BK67"  !CDS_PN = "BK67";
"VCCIN<164>":   PN = "BK65"  !CDS_PN = "BK65";
"VCCIN<165>":   PN = "BK63"  !CDS_PN = "BK63";
"VCCIN<166>":   PN = "BK61"  !CDS_PN = "BK61";
"VCCIN<167>":   PN = "BJ84"  !CDS_PN = "BJ84";
"VCCIN<168>":   PN = "BJ82"  !CDS_PN = "BJ82";
"VCCIN<169>":   PN = "BJ80"  !CDS_PN = "BJ80";
"VCCIN<170>":   PN = "BJ78"  !CDS_PN = "BJ78";
"VCCIN<171>":   PN = "BJ76"  !CDS_PN = "BJ76";
"VCCIN<172>":   PN = "BJ74"  !CDS_PN = "BJ74";
"VCCIN<173>":   PN = "BJ72"  !CDS_PN = "BJ72";
"VCCIN<174>":   PN = "BJ70"  !CDS_PN = "BJ70";
"VCCIN<175>":   PN = "BJ68"  !CDS_PN = "BJ68";
"VCCIN<176>":   PN = "BJ66"  !CDS_PN = "BJ66";
"VCCIN<177>":   PN = "BJ64"  !CDS_PN = "BJ64";
"VCCIN<178>":   PN = "BJ62"  !CDS_PN = "BJ62";
"VCCIN<179>":   PN = "BJ60"  !CDS_PN = "BJ60";
"VCCIN<180>":   PN = "BH83"  !CDS_PN = "BH83";
"VCCIN<181>":   PN = "BH81"  !CDS_PN = "BH81";
"VCCIN<182>":   PN = "BH79"  !CDS_PN = "BH79";
"VCCIN<183>":   PN = "BH77"  !CDS_PN = "BH77";
"VCCIN<184>":   PN = "BH75"  !CDS_PN = "BH75";
"VCCIN<185>":   PN = "BH73"  !CDS_PN = "BH73";
"VCCIN<186>":   PN = "BH71"  !CDS_PN = "BH71";
"VCCIN<187>":   PN = "BH69"  !CDS_PN = "BH69";
"VCCIN<188>":   PN = "BH67"  !CDS_PN = "BH67";
"VCCIN<189>":   PN = "BH65"  !CDS_PN = "BH65";
"VCCIN<190>":   PN = "BH63"  !CDS_PN = "BH63";
"VCCIN<191>":   PN = "BH61"  !CDS_PN = "BH61";
"VCCIN<192>":   PN = "BG84"  !CDS_PN = "BG84";
"VCCIN<193>":   PN = "BG70"  !CDS_PN = "BG70";
"VCCIN<194>":   PN = "BG68"  !CDS_PN = "BG68";
"VCCIN<195>":   PN = "BG66"  !CDS_PN = "BG66";
"VCCIN<196>":   PN = "BG64"  !CDS_PN = "BG64";
"VCCIN<197>":   PN = "BG62"  !CDS_PN = "BG62";
"VCCIN<198>":   PN = "BG60"  !CDS_PN = "BG60";
"VCCIN<199>":   PN = "BF85"  !CDS_PN = "BF85";
"VCCIN<200>":   PN = "BF83"  !CDS_PN = "BF83";
"VCCIN<201>":   PN = "BF81"  !CDS_PN = "BF81";
"VCCIN<202>":   PN = "BF79"  !CDS_PN = "BF79";
"VCCIN<203>":   PN = "BF77"  !CDS_PN = "BF77";
"VCCIN<204>":   PN = "BF75"  !CDS_PN = "BF75";
"VCCIN<205>":   PN = "BF73"  !CDS_PN = "BF73";
"VCCIN<206>":   PN = "BF61"  !CDS_PN = "BF61";
"VCCIN<207>":   PN = "BE84"  !CDS_PN = "BE84";
"VCCIN<208>":   PN = "BE82"  !CDS_PN = "BE82";
"VCCIN<209>":   PN = "BE80"  !CDS_PN = "BE80";
"VCCIN<210>":   PN = "BE78"  !CDS_PN = "BE78";
"VCCIN<211>":   PN = "BE76"  !CDS_PN = "BE76";
"VCCIN<212>":   PN = "BE74"  !CDS_PN = "BE74";
"VCCIN<213>":   PN = "BE72"  !CDS_PN = "BE72";
"VCCIN<214>":   PN = "BE62"  !CDS_PN = "BE62";
"VCCIN<215>":   PN = "BE60"  !CDS_PN = "BE60";
"VCCIN<216>":   PN = "BD85"  !CDS_PN = "BD85";
"VCCIN<217>":   PN = "BD83"  !CDS_PN = "BD83";
"VCCIN<218>":   PN = "BD81"  !CDS_PN = "BD81";
"VCCIN<219>":   PN = "BD79"  !CDS_PN = "BD79";
"VCCIN<220>":   PN = "BD77"  !CDS_PN = "BD77";
"VCCIN<221>":   PN = "BD75"  !CDS_PN = "BD75";
"VCCIN<222>":   PN = "BD73"  !CDS_PN = "BD73";
"VCCIN<223>":   PN = "BD61"  !CDS_PN = "BD61";
"VCCIN<224>":   PN = "BC84"  !CDS_PN = "BC84";
"VCCIN<225>":   PN = "BC62"  !CDS_PN = "BC62";
"VCCIN<226>":   PN = "BC60"  !CDS_PN = "BC60";
"VCCIN<227>":   PN = "BB85"  !CDS_PN = "BB85";
"VCCIN<228>":   PN = "BB61"  !CDS_PN = "BB61";
"VCCIN<229>":   PN = "BA60"  !CDS_PN = "BA60";
"VCCIN<230>":   PN = "AY61"  !CDS_PN = "AY61";
"VCCIN<231>":   PN = "AW60"  !CDS_PN = "AW60";
"VCCIN<232>":   PN = "AV61"  !CDS_PN = "AV61";
"VCCIN<233>":   PN = "AV59"  !CDS_PN = "AV59";
"VCCIN<234>":   PN = "AU60"  !CDS_PN = "AU60";
"VCCIN<235>":   PN = "AU58"  !CDS_PN = "AU58";
"VCCIN<236>":   PN = "AT59"  !CDS_PN = "AT59";
"VCCIN<237>":   PN = "AT57"  !CDS_PN = "AT57";
"VCCIN<238>":   PN = "AR58"  !CDS_PN = "AR58";
"VCCIN<239>":   PN = "AR56"  !CDS_PN = "AR56";
"VCCIN<240>":   PN = "AP57"  !CDS_PN = "AP57";
"VCCIN<241>":   PN = "AP55"  !CDS_PN = "AP55";
"VCCIN<242>":   PN = "AN56"  !CDS_PN = "AN56";
"VCCIN<243>":   PN = "AN54"  !CDS_PN = "AN54";
"VCCIN<244>":   PN = "AN32"  !CDS_PN = "AN32";
"VCCIN<245>":   PN = "AM55"  !CDS_PN = "AM55";
"VCCIN<246>":   PN = "AM53"  !CDS_PN = "AM53";
"VCCIN<247>":   PN = "AM33"  !CDS_PN = "AM33";
"VCCIN<248>":   PN = "AL54"  !CDS_PN = "AL54";
"VCCIN<249>":   PN = "AL52"  !CDS_PN = "AL52";
"VCCIN<250>":   PN = "AL50"  !CDS_PN = "AL50";
"VCCIN<251>":   PN = "AL48"  !CDS_PN = "AL48";
"VCCIN<252>":   PN = "AL46"  !CDS_PN = "AL46";
"VCCIN<253>":   PN = "AL34"  !CDS_PN = "AL34";
"VCCIN<254>":   PN = "AK53"  !CDS_PN = "AK53";
"VCCIN<255>":   PN = "AK51"  !CDS_PN = "AK51";
"VCCIN<256>":   PN = "AK49"  !CDS_PN = "AK49";
"VCCIN<257>":   PN = "AK47"  !CDS_PN = "AK47";
"VCCIN<258>":   PN = "AK45"  !CDS_PN = "AK45";
"VCCIN<259>":   PN = "AK35"  !CDS_PN = "AK35";
"VCCIN<260>":   PN = "AJ36"  !CDS_PN = "AJ36";
"VCCIN<261>":   PN = "AH41"  !CDS_PN = "AH41";
"VCCIN<262>":   PN = "AH39"  !CDS_PN = "AH39";
"VCCIN<263>":   PN = "AH37"  !CDS_PN = "AH37";
"VCCIN<264>":   PN = "AG42"  !CDS_PN = "AG42";
"VCCIN<265>":   PN = "AG40"  !CDS_PN = "AG40";
"VCCIN<266>":   PN = "AG38"  !CDS_PN = "AG38";
"VCCIN<267>":   PN = "AF43"  !CDS_PN = "AF43";
BODY = "SKX_EXT_B","I51": #LOCATION = "U2D1" !CDS_LOCATION = "U2D1" #SEC = "19" !CDS_SEC = "19";
"VCCIN<0>":   PN = "CY49"  !CDS_PN = "CY49";
"VCCIN<1>":   PN = "CY47"  !CDS_PN = "CY47";
"VCCIN<2>":   PN = "CW50"  !CDS_PN = "CW50";
"VCCIN<3>":   PN = "CW48"  !CDS_PN = "CW48";
"VCCIN<4>":   PN = "CW46"  !CDS_PN = "CW46";
"VCCIN<5>":   PN = "CV51"  !CDS_PN = "CV51";
"VCCIN<6>":   PN = "CU54"  !CDS_PN = "CU54";
"VCCIN<7>":   PN = "CU52"  !CDS_PN = "CU52";
"VCCIN<8>":   PN = "CU42"  !CDS_PN = "CU42";
"VCCIN<9>":   PN = "CU40"  !CDS_PN = "CU40";
"VCCIN<10>":   PN = "CU38"  !CDS_PN = "CU38";
"VCCIN<11>":   PN = "CT55"  !CDS_PN = "CT55";
"VCCIN<12>":   PN = "CT53"  !CDS_PN = "CT53";
"VCCIN<13>":   PN = "CT41"  !CDS_PN = "CT41";
"VCCIN<14>":   PN = "CT39"  !CDS_PN = "CT39";
"VCCIN<15>":   PN = "CT37"  !CDS_PN = "CT37";
"VCCIN<16>":   PN = "CR56"  !CDS_PN = "CR56";
"VCCIN<17>":   PN = "CR54"  !CDS_PN = "CR54";
"VCCIN<18>":   PN = "CR34"  !CDS_PN = "CR34";
"VCCIN<19>":   PN = "CP57"  !CDS_PN = "CP57";
"VCCIN<20>":   PN = "CP55"  !CDS_PN = "CP55";
"VCCIN<21>":   PN = "CP33"  !CDS_PN = "CP33";
"VCCIN<22>":   PN = "CN58"  !CDS_PN = "CN58";
"VCCIN<23>":   PN = "CN56"  !CDS_PN = "CN56";
"VCCIN<24>":   PN = "CM59"  !CDS_PN = "CM59";
"VCCIN<25>":   PN = "CM57"  !CDS_PN = "CM57";
"VCCIN<26>":   PN = "CL60"  !CDS_PN = "CL60";
"VCCIN<27>":   PN = "CL58"  !CDS_PN = "CL58";
"VCCIN<28>":   PN = "CK61"  !CDS_PN = "CK61";
"VCCIN<29>":   PN = "CK59"  !CDS_PN = "CK59";
"VCCIN<30>":   PN = "CJ60"  !CDS_PN = "CJ60";
"VCCIN<31>":   PN = "CH85"  !CDS_PN = "CH85";
"VCCIN<32>":   PN = "CH61"  !CDS_PN = "CH61";
"VCCIN<33>":   PN = "CG84"  !CDS_PN = "CG84";
"VCCIN<34>":   PN = "CG60"  !CDS_PN = "CG60";
"VCCIN<35>":   PN = "CF85"  !CDS_PN = "CF85";
"VCCIN<36>":   PN = "CF61"  !CDS_PN = "CF61";
"VCCIN<37>":   PN = "CE84"  !CDS_PN = "CE84";
"VCCIN<38>":   PN = "CE60"  !CDS_PN = "CE60";
"VCCIN<39>":   PN = "CD85"  !CDS_PN = "CD85";
"VCCIN<40>":   PN = "CD83"  !CDS_PN = "CD83";
"VCCIN<41>":   PN = "CD61"  !CDS_PN = "CD61";
"VCCIN<42>":   PN = "CC84"  !CDS_PN = "CC84";
"VCCIN<43>":   PN = "CC62"  !CDS_PN = "CC62";
"VCCIN<44>":   PN = "CC60"  !CDS_PN = "CC60";
"VCCIN<45>":   PN = "CB83"  !CDS_PN = "CB83";
"VCCIN<46>":   PN = "CB81"  !CDS_PN = "CB81";
"VCCIN<47>":   PN = "CB79"  !CDS_PN = "CB79";
"VCCIN<48>":   PN = "CB77"  !CDS_PN = "CB77";
"VCCIN<49>":   PN = "CB75"  !CDS_PN = "CB75";
"VCCIN<50>":   PN = "CB73"  !CDS_PN = "CB73";
"VCCIN<51>":   PN = "CB61"  !CDS_PN = "CB61";
"VCCIN<52>":   PN = "CA84"  !CDS_PN = "CA84";
"VCCIN<53>":   PN = "CA82"  !CDS_PN = "CA82";
"VCCIN<54>":   PN = "CA80"  !CDS_PN = "CA80";
"VCCIN<55>":   PN = "CA78"  !CDS_PN = "CA78";
"VCCIN<56>":   PN = "CA76"  !CDS_PN = "CA76";
"VCCIN<57>":   PN = "CA74"  !CDS_PN = "CA74";
"VCCIN<58>":   PN = "CA72"  !CDS_PN = "CA72";
"VCCIN<59>":   PN = "CA62"  !CDS_PN = "CA62";
"VCCIN<60>":   PN = "CA60"  !CDS_PN = "CA60";
"VCCIN<61>":   PN = "BY83"  !CDS_PN = "BY83";
"VCCIN<62>":   PN = "BY81"  !CDS_PN = "BY81";
"VCCIN<63>":   PN = "BY79"  !CDS_PN = "BY79";
"VCCIN<64>":   PN = "BY77"  !CDS_PN = "BY77";
"VCCIN<65>":   PN = "BY75"  !CDS_PN = "BY75";
"VCCIN<66>":   PN = "BY73"  !CDS_PN = "BY73";
"VCCIN<67>":   PN = "BY61"  !CDS_PN = "BY61";
"VCCIN<68>":   PN = "BW84"  !CDS_PN = "BW84";
"VCCIN<69>":   PN = "BW70"  !CDS_PN = "BW70";
"VCCIN<70>":   PN = "BW68"  !CDS_PN = "BW68";
"VCCIN<71>":   PN = "BW66"  !CDS_PN = "BW66";
"VCCIN<72>":   PN = "BW64"  !CDS_PN = "BW64";
"VCCIN<73>":   PN = "BW62"  !CDS_PN = "BW62";
"VCCIN<74>":   PN = "BW60"  !CDS_PN = "BW60";
"VCCIN<75>":   PN = "BV83"  !CDS_PN = "BV83";
"VCCIN<76>":   PN = "BV81"  !CDS_PN = "BV81";
"VCCIN<77>":   PN = "BV79"  !CDS_PN = "BV79";
"VCCIN<78>":   PN = "BV77"  !CDS_PN = "BV77";
"VCCIN<79>":   PN = "BV75"  !CDS_PN = "BV75";
"VCCIN<80>":   PN = "BV73"  !CDS_PN = "BV73";
"VCCIN<81>":   PN = "BV71"  !CDS_PN = "BV71";
"VCCIN<82>":   PN = "BV69"  !CDS_PN = "BV69";
"VCCIN<83>":   PN = "BV67"  !CDS_PN = "BV67";
"VCCIN<84>":   PN = "BV65"  !CDS_PN = "BV65";
"VCCIN<85>":   PN = "BV63"  !CDS_PN = "BV63";
"VCCIN<86>":   PN = "BV61"  !CDS_PN = "BV61";
"VCCIN<87>":   PN = "BU84"  !CDS_PN = "BU84";
"VCCIN<88>":   PN = "BU82"  !CDS_PN = "BU82";
"VCCIN<89>":   PN = "BU80"  !CDS_PN = "BU80";
"VCCIN<90>":   PN = "BU78"  !CDS_PN = "BU78";
"VCCIN<91>":   PN = "BU76"  !CDS_PN = "BU76";
"VCCIN<92>":   PN = "BU74"  !CDS_PN = "BU74";
"VCCIN<93>":   PN = "BU72"  !CDS_PN = "BU72";
"VCCIN<94>":   PN = "BU70"  !CDS_PN = "BU70";
"VCCIN<95>":   PN = "BU68"  !CDS_PN = "BU68";
"VCCIN<96>":   PN = "BU66"  !CDS_PN = "BU66";
"VCCIN<97>":   PN = "BU64"  !CDS_PN = "BU64";
"VCCIN<98>":   PN = "BU62"  !CDS_PN = "BU62";
"VCCIN<99>":   PN = "BU60"  !CDS_PN = "BU60";
"VCCIN<100>":   PN = "BT83"  !CDS_PN = "BT83";
"VCCIN<101>":   PN = "BT81"  !CDS_PN = "BT81";
"VCCIN<102>":   PN = "BT79"  !CDS_PN = "BT79";
"VCCIN<103>":   PN = "BT77"  !CDS_PN = "BT77";
"VCCIN<104>":   PN = "BT75"  !CDS_PN = "BT75";
"VCCIN<105>":   PN = "BT73"  !CDS_PN = "BT73";
"VCCIN<106>":   PN = "BT71"  !CDS_PN = "BT71";
"VCCIN<107>":   PN = "BT69"  !CDS_PN = "BT69";
"VCCIN<108>":   PN = "BT67"  !CDS_PN = "BT67";
"VCCIN<109>":   PN = "BT65"  !CDS_PN = "BT65";
"VCCIN<110>":   PN = "BT63"  !CDS_PN = "BT63";
"VCCIN<111>":   PN = "BT61"  !CDS_PN = "BT61";
"VCCIN<112>":   PN = "BR84"  !CDS_PN = "BR84";
"VCCIN<113>":   PN = "BR62"  !CDS_PN = "BR62";
"VCCIN<114>":   PN = "BR60"  !CDS_PN = "BR60";
"VCCIN<115>":   PN = "BP83"  !CDS_PN = "BP83";
"VCCIN<116>":   PN = "BP81"  !CDS_PN = "BP81";
"VCCIN<117>":   PN = "BP79"  !CDS_PN = "BP79";
"VCCIN<118>":   PN = "BP77"  !CDS_PN = "BP77";
"VCCIN<119>":   PN = "BP75"  !CDS_PN = "BP75";
"VCCIN<120>":   PN = "BP73"  !CDS_PN = "BP73";
"VCCIN<121>":   PN = "BP71"  !CDS_PN = "BP71";
"VCCIN<122>":   PN = "BP69"  !CDS_PN = "BP69";
"VCCIN<123>":   PN = "BP67"  !CDS_PN = "BP67";
"VCCIN<124>":   PN = "BP65"  !CDS_PN = "BP65";
"VCCIN<125>":   PN = "BP63"  !CDS_PN = "BP63";
"VCCIN<126>":   PN = "BP61"  !CDS_PN = "BP61";
"VCCIN<127>":   PN = "BN84"  !CDS_PN = "BN84";
"VCCIN<128>":   PN = "BN82"  !CDS_PN = "BN82";
"VCCIN<129>":   PN = "BN80"  !CDS_PN = "BN80";
"VCCIN_SENSE":   PN = "BA86"  !CDS_PN = "BA86";
"VCCINPMAX<0>":   PN = "AW86"  !CDS_PN = "AW86";
"VCCINPMAX<1>":   PN = "AV85"  !CDS_PN = "AV85";
"VSENSEPMAX":   PN = "AD41"  !CDS_PN = "AD41";
"VSS_VCCIN_SENSE":   PN = "AY85"  !CDS_PN = "AY85";
BODY = "RES","I53": #LOCATION = "R3D32" !CDS_LOCATION = "R3D32" #SEC = "1" !CDS_SEC = "1";
"A":   PN = "1"  !CDS_PN = "1";
"B":   PN = "2"  !CDS_PN = "2";
DRAWING = "@baseboard_fab2_lib.baseboard_fab2(sch_1):page72";
BODY = "CAP","I25": #LOCATION = "C3D3" !CDS_LOCATION = "C3D3" &SEC = "1" #&CDS_SEC = "1";
"A":   PN = "1"  !CDS_PN = "1";
"B":   PN = "2"  !CDS_PN = "2";
BODY = "SKX_EXT_B","I32": #LOCATION = "U2D1" !CDS_LOCATION = "U2D1" #SEC = "20" !CDS_SEC = "20";
"VCCD012<0>":   PN = "B49"  !CDS_PN = "B49";
"VCCD012<1>":   PN = "B53"  !CDS_PN = "B53";
"VCCD012<2>":   PN = "B59"  !CDS_PN = "B59";
"VCCD012<3>":   PN = "E46"  !CDS_PN = "E46";
"VCCD012<4>":   PN = "E48"  !CDS_PN = "E48";
"VCCD012<5>":   PN = "E50"  !CDS_PN = "E50";
"VCCD012<6>":   PN = "E52"  !CDS_PN = "E52";
"VCCD012<7>":   PN = "E54"  !CDS_PN = "E54";
"VCCD012<8>":   PN = "E56"  !CDS_PN = "E56";
"VCCD012<9>":   PN = "E58"  !CDS_PN = "E58";
"VCCD012<10>":   PN = "E60"  !CDS_PN = "E60";
"VCCD012<11>":   PN = "E62"  !CDS_PN = "E62";
"VCCD012<12>":   PN = "E64"  !CDS_PN = "E64";
"VCCD012<13>":   PN = "L46"  !CDS_PN = "L46";
"VCCD012<14>":   PN = "L48"  !CDS_PN = "L48";
"VCCD012<15>":   PN = "L50"  !CDS_PN = "L50";
"VCCD012<16>":   PN = "L52"  !CDS_PN = "L52";
"VCCD012<17>":   PN = "L54"  !CDS_PN = "L54";
"VCCD012<18>":   PN = "L56"  !CDS_PN = "L56";
"VCCD012<19>":   PN = "L58"  !CDS_PN = "L58";
"VCCD012<20>":   PN = "L60"  !CDS_PN = "L60";
"VCCD012<21>":   PN = "L62"  !CDS_PN = "L62";
"VCCD012<22>":   PN = "N64"  !CDS_PN = "N64";
"VCCD012<23>":   PN = "U46"  !CDS_PN = "U46";
"VCCD012<24>":   PN = "U48"  !CDS_PN = "U48";
"VCCD012<25>":   PN = "U50"  !CDS_PN = "U50";
"VCCD012<26>":   PN = "U52"  !CDS_PN = "U52";
"VCCD012<27>":   PN = "U54"  !CDS_PN = "U54";
"VCCD012<28>":   PN = "U56"  !CDS_PN = "U56";
"VCCD012<29>":   PN = "U58"  !CDS_PN = "U58";
"VCCD012<30>":   PN = "U60"  !CDS_PN = "U60";
"VCCD012<31>":   PN = "U62"  !CDS_PN = "U62";
"VCCD012<32>":   PN = "W64"  !CDS_PN = "W64";
"VCCD012<33>":   PN = "Y45"  !CDS_PN = "Y45";
"VCCD012<34>":   PN = "Y47"  !CDS_PN = "Y47";
"VCCD012<35>":   PN = "Y49"  !CDS_PN = "Y49";
"VCCD012<36>":   PN = "Y51"  !CDS_PN = "Y51";
"VCCD012<37>":   PN = "Y53"  !CDS_PN = "Y53";
"VCCD012<38>":   PN = "Y55"  !CDS_PN = "Y55";
"VCCD012<39>":   PN = "Y57"  !CDS_PN = "Y57";
"VCCD012<40>":   PN = "Y59"  !CDS_PN = "Y59";
"VCCD012<41>":   PN = "Y61"  !CDS_PN = "Y61";
"VCCD012<42>":   PN = "Y63"  !CDS_PN = "Y63";
"VCCD012<43>":   PN = "AD45"  !CDS_PN = "AD45";
"VCCD012<44>":   PN = "AF55"  !CDS_PN = "AF55";
"VCCD012<45>":   PN = "AF57"  !CDS_PN = "AF57";
"VCCD012<46>":   PN = "AF59"  !CDS_PN = "AF59";
"VCCD012<47>":   PN = "AF61"  !CDS_PN = "AF61";
"VCCD012<48>":   PN = "AF63"  !CDS_PN = "AF63";
"VCCD012<49>":   PN = "D45"  !CDS_PN = "D45";
"VCCD012<50>":   PN = "C46"  !CDS_PN = "C46";
"VCCD012<51>":   PN = "B47"  !CDS_PN = "B47";
"VCCD345<0>":   PN = "EF59"  !CDS_PN = "EF59";
"VCCD345<1>":   PN = "EF53"  !CDS_PN = "EF53";
"VCCD345<2>":   PN = "EF49"  !CDS_PN = "EF49";
"VCCD345<3>":   PN = "EC62"  !CDS_PN = "EC62";
"VCCD345<4>":   PN = "EC60"  !CDS_PN = "EC60";
"VCCD345<5>":   PN = "EC58"  !CDS_PN = "EC58";
"VCCD345<6>":   PN = "EC56"  !CDS_PN = "EC56";
"VCCD345<7>":   PN = "EC54"  !CDS_PN = "EC54";
"VCCD345<8>":   PN = "EC52"  !CDS_PN = "EC52";
"VCCD345<9>":   PN = "EC50"  !CDS_PN = "EC50";
"VCCD345<10>":   PN = "EC48"  !CDS_PN = "EC48";
"VCCD345<11>":   PN = "EC46"  !CDS_PN = "EC46";
"VCCD345<12>":   PN = "DU64"  !CDS_PN = "DU64";
"VCCD345<13>":   PN = "DU62"  !CDS_PN = "DU62";
"VCCD345<14>":   PN = "DU60"  !CDS_PN = "DU60";
"VCCD345<15>":   PN = "DU58"  !CDS_PN = "DU58";
"VCCD345<16>":   PN = "DU56"  !CDS_PN = "DU56";
"VCCD345<17>":   PN = "DU54"  !CDS_PN = "DU54";
"VCCD345<18>":   PN = "DU52"  !CDS_PN = "DU52";
"VCCD345<19>":   PN = "DU50"  !CDS_PN = "DU50";
"VCCD345<20>":   PN = "DU48"  !CDS_PN = "DU48";
"VCCD345<21>":   PN = "DU46"  !CDS_PN = "DU46";
"VCCD345<22>":   PN = "DL62"  !CDS_PN = "DL62";
"VCCD345<23>":   PN = "DL60"  !CDS_PN = "DL60";
"VCCD345<24>":   PN = "DL58"  !CDS_PN = "DL58";
"VCCD345<25>":   PN = "DL56"  !CDS_PN = "DL56";
"VCCD345<26>":   PN = "DL54"  !CDS_PN = "DL54";
"VCCD345<27>":   PN = "DL52"  !CDS_PN = "DL52";
"VCCD345<28>":   PN = "DL50"  !CDS_PN = "DL50";
"VCCD345<29>":   PN = "DL48"  !CDS_PN = "DL48";
"VCCD345<30>":   PN = "DL46"  !CDS_PN = "DL46";
"VCCD345<31>":   PN = "DJ64"  !CDS_PN = "DJ64";
"VCCD345<32>":   PN = "DH63"  !CDS_PN = "DH63";
"VCCD345<33>":   PN = "DH61"  !CDS_PN = "DH61";
"VCCD345<34>":   PN = "DH59"  !CDS_PN = "DH59";
"VCCD345<35>":   PN = "DH57"  !CDS_PN = "DH57";
"VCCD345<36>":   PN = "DH55"  !CDS_PN = "DH55";
"VCCD345<37>":   PN = "DH53"  !CDS_PN = "DH53";
"VCCD345<38>":   PN = "DH51"  !CDS_PN = "DH51";
"VCCD345<39>":   PN = "DH49"  !CDS_PN = "DH49";
"VCCD345<40>":   PN = "DH47"  !CDS_PN = "DH47";
"VCCD345<41>":   PN = "DH45"  !CDS_PN = "DH45";
"VCCD345<42>":   PN = "DD45"  !CDS_PN = "DD45";
"VCCD345<43>":   PN = "DB63"  !CDS_PN = "DB63";
"VCCD345<44>":   PN = "DB61"  !CDS_PN = "DB61";
"VCCD345<45>":   PN = "DB59"  !CDS_PN = "DB59";
"VCCD345<46>":   PN = "DB57"  !CDS_PN = "DB57";
"VCCD345<47>":   PN = "DB55"  !CDS_PN = "DB55";
"VCCD345<48>":   PN = "DB53"  !CDS_PN = "DB53";
"VCCD345<49>":   PN = "EF45"  !CDS_PN = "EF45";
"VCCD345<50>":   PN = "EE44"  !CDS_PN = "EE44";
BODY = "SKX_EXT_B","I33": #LOCATION = "U2D1" !CDS_LOCATION = "U2D1" #SEC = "21" !CDS_SEC = "21";
"CD_VCC_CORE<0>":   PN = "BL14"  !CDS_PN = "BL14";
"CD_VCC_CORE<1>":   PN = "BK15"  !CDS_PN = "BK15";
"CD_VCC_CORE<2>":   PN = "BK13"  !CDS_PN = "BK13";
"CD_VCC_CORE<3>":   PN = "BJ14"  !CDS_PN = "BJ14";
"CD_VCC_CORE<4>":   PN = "BJ12"  !CDS_PN = "BJ12";
"CD_VCC_CORE<5>":   PN = "BH13"  !CDS_PN = "BH13";
"CD_VCC_CORE<6>":   PN = "BG14"  !CDS_PN = "BG14";
"CD_VCC_CORE<7>":   PN = "BG12"  !CDS_PN = "BG12";
"CD_VCC_CORE<8>":   PN = "BF13"  !CDS_PN = "BF13";
"CD_VCC_CORE<9>":   PN = "BF11"  !CDS_PN = "BF11";
"CD_VCC_CORE<10>":   PN = "BE14"  !CDS_PN = "BE14";
"CD_VCC_CORE<11>":   PN = "BE12"  !CDS_PN = "BE12";
"CD_VCC_CORE<12>":   PN = "BD13"  !CDS_PN = "BD13";
"CD_VCCIN<0>":   PN = "BT27"  !CDS_PN = "BT27";
"CD_VCCIN<1>":   PN = "BU26"  !CDS_PN = "BU26";
"CD_VCCIN<2>":   PN = "BV27"  !CDS_PN = "BV27";
"CD_VCCIN<3>":   PN = "BY27"  !CDS_PN = "BY27";
"CD_VCCP<0>":   PN = "BV15"  !CDS_PN = "BV15";
"CD_VCCP<1>":   PN = "BV13"  !CDS_PN = "BV13";
"CD_VCCP<2>":   PN = "BV11"  !CDS_PN = "BV11";
"CD_VCCP<3>":   PN = "BU14"  !CDS_PN = "BU14";
"CD_VCCP<4>":   PN = "BU12"  !CDS_PN = "BU12";
"CD_VCCP<5>":   PN = "BT15"  !CDS_PN = "BT15";
"CD_VCCP<6>":   PN = "BT13"  !CDS_PN = "BT13";
"CD_VCCP<7>":   PN = "BT11"  !CDS_PN = "BT11";
"CD_VCCP<8>":   PN = "BR14"  !CDS_PN = "BR14";
"CD_VCCP<9>":   PN = "BR12"  !CDS_PN = "BR12";
"CD_VCCP<10>":   PN = "BP15"  !CDS_PN = "BP15";
"CD_VCCP<11>":   PN = "BP13"  !CDS_PN = "BP13";
"CD_VCCP<12>":   PN = "BP11"  !CDS_PN = "BP11";
"CD_VCCP<13>":   PN = "BN14"  !CDS_PN = "BN14";
"CD_VCCP<14>":   PN = "BN12"  !CDS_PN = "BN12";
"CD_VCCP<15>":   PN = "BM11"  !CDS_PN = "BM11";
"CD_VPP<0>":   PN = "B11"  !CDS_PN = "B11";
"CD_VPP<1>":   PN = "A12"  !CDS_PN = "A12";
"CD_VPP<2>":   PN = "A10"  !CDS_PN = "A10";
"CD_VPP<3>":   PN = "A8"  !CDS_PN = "A8";
"VCC33":   PN = "CY55"  !CDS_PN = "CY55";
"VCCIO<20>":   PN = "CM15"  !CDS_PN = "CM15";
"VCCIO<21>":   PN = "CL12"  !CDS_PN = "CL12";
"VCCIO<22>":   PN = "CK5"  !CDS_PN = "CK5";
"VCCIO<23>":   PN = "CV7"  !CDS_PN = "CV7";
"VCCIO<24>":   PN = "CH9"  !CDS_PN = "CH9";
"VCCIO<25>":   PN = "D7"  !CDS_PN = "D7";
"VCCIO<26>":   PN = "CE18"  !CDS_PN = "CE18";
"VCCIO<27>":   PN = "CD9"  !CDS_PN = "CD9";
"VCCIO<28>":   PN = "CB17"  !CDS_PN = "CB17";
"VCCIO<29>":   PN = "CB13"  !CDS_PN = "CB13";
"VCCIO<30>":   PN = "BP25"  !CDS_PN = "BP25";
"VCCIO<31>":   PN = "BJ24"  !CDS_PN = "BJ24";
"VCCIO<32>":   PN = "BF23"  !CDS_PN = "BF23";
"VCCIO<33>":   PN = "DA14"  !CDS_PN = "DA14";
"VCCIO<34>":   PN = "BB5"  !CDS_PN = "BB5";
"VCCIO<35>":   PN = "BA24"  !CDS_PN = "BA24";
"VCCIO<36>":   PN = "AY11"  !CDS_PN = "AY11";
"VCCIO<37>":   PN = "AW6"  !CDS_PN = "AW6";
"VCCIO<38>":   PN = "AT11"  !CDS_PN = "AT11";
"VCCIO<39>":   PN = "DD7"  !CDS_PN = "DD7";
"VCCIO<40>":   PN = "AN10"  !CDS_PN = "AN10";
"VCCIO<41>":   PN = "DF13"  !CDS_PN = "DF13";
"VCCIO<42>":   PN = "AH9"  !CDS_PN = "AH9";
"VCCIO<43>":   PN = "AC4"  !CDS_PN = "AC4";
"VCCIO<44>":   PN = "AC20"  !CDS_PN = "AC20";
"VCCIO<45>":   PN = "AA10"  !CDS_PN = "AA10";
"VCCIO<46>":   PN = "W6"  !CDS_PN = "W6";
"VCCIO<47>":   PN = "W4"  !CDS_PN = "W4";
"VCCIO<48>":   PN = "DF21"  !CDS_PN = "DF21";
"VCCIO<49>":   PN = "U14"  !CDS_PN = "U14";
"VCCIO<50>":   PN = "T3"  !CDS_PN = "T3";
"VCCIO<51>":   PN = "P5"  !CDS_PN = "P5";
"VCCIO<52>":   PN = "M21"  !CDS_PN = "M21";
"VCCIO<53>":   PN = "M11"  !CDS_PN = "M11";
"VCCIO<54>":   PN = "DG8"  !CDS_PN = "DG8";
"VCCIO<55>":   PN = "DH7"  !CDS_PN = "DH7";
"VCCIO<56>":   PN = "L16"  !CDS_PN = "L16";
"VCCIO<57>":   PN = "L14"  !CDS_PN = "L14";
"VCCIO<58>":   PN = "J10"  !CDS_PN = "J10";
"VCCIO<59>":   PN = "H13"  !CDS_PN = "H13";
"VCCIO<60>":   PN = "DJ16"  !CDS_PN = "DJ16";
"VCCIO<61>":   PN = "DM17"  !CDS_PN = "DM17";
"VCCIO<62>":   PN = "DN8"  !CDS_PN = "DN8";
"VCCIO<63>":   PN = "DP19"  !CDS_PN = "DP19";
"VCCIO<64>":   PN = "DR10"  !CDS_PN = "DR10";
"VCCIO<65>":   PN = "DR2"  !CDS_PN = "DR2";
"VCCIO<66>":   PN = "DU20"  !CDS_PN = "DU20";
"VCCIO<67>":   PN = "EA12"  !CDS_PN = "EA12";
"VCCIO<68>":   PN = "EB15"  !CDS_PN = "EB15";
"VCCIO<69>":   PN = "J2"  !CDS_PN = "J2";
"VCCIO<70>":   PN = "K15"  !CDS_PN = "K15";
"VCCIO<71>":   PN = "M7"  !CDS_PN = "M7";
"VCCIO<72>":   PN = "M9"  !CDS_PN = "M9";
"VCCIO<73>":   PN = "N18"  !CDS_PN = "N18";
"VCCIO<74>":   PN = "W10"  !CDS_PN = "W10";
"VCCIO<75>":   PN = "BC26"  !CDS_PN = "BC26";
"VCCIO<76>":   PN = "BB27"  !CDS_PN = "BB27";
"VCCIO<77>":   PN = "BA26"  !CDS_PN = "BA26";
"VCCIO<78>":   PN = "AY27"  !CDS_PN = "AY27";
"VCCIO<79>":   PN = "AW26"  !CDS_PN = "AW26";
"VCCIO<80>":   PN = "AV27"  !CDS_PN = "AV27";
"VCCIO<81>":   PN = "CF27"  !CDS_PN = "CF27";
"VCCIO<82>":   PN = "CD27"  !CDS_PN = "CD27";
"VCCIO<83>":   PN = "CC26"  !CDS_PN = "CC26";
"VCCIO<84>":   PN = "CJ28"  !CDS_PN = "CJ28";
"VCCIO<85>":   PN = "CH27"  !CDS_PN = "CH27";
"VCCIO<86>":   PN = "BM27"  !CDS_PN = "BM27";
"VCCIO<87>":   PN = "BL26"  !CDS_PN = "BL26";
"VCCIO<88>":   PN = "BK27"  !CDS_PN = "BK27";
"VCCIO<89>":   PN = "BK25"  !CDS_PN = "BK25";
"VCCIO<90>":   PN = "BJ26"  !CDS_PN = "BJ26";
"VCCIO<91>":   PN = "BH27"  !CDS_PN = "BH27";
"VCCIO<92>":   PN = "BH25"  !CDS_PN = "BH25";
"VCCIO<93>":   PN = "BG26"  !CDS_PN = "BG26";
"VCCIO<94>":   PN = "BF27"  !CDS_PN = "BF27";
"VCCIO<95>":   PN = "AE36"  !CDS_PN = "AE36";
"VCCIO<96>":   PN = "AD37"  !CDS_PN = "AD37";
"VCCIO<97>":   PN = "AC36"  !CDS_PN = "AC36";
"VCCIO<98>":   PN = "AF35"  !CDS_PN = "AF35";
"VCCIO<99>":   PN = "AD35"  !CDS_PN = "AD35";
"VCCIO<100>":   PN = "AE34"  !CDS_PN = "AE34";
"VCCIO<101>":   PN = "AG34"  !CDS_PN = "AG34";
"VCCIO<102>":   PN = "AM29"  !CDS_PN = "AM29";
"VCCIO<103>":   PN = "AL28"  !CDS_PN = "AL28";
"VCCIO<104>":   PN = "AR28"  !CDS_PN = "AR28";
"VCCSA<0>":   PN = "CJ66"  !CDS_PN = "CJ66";
"VCCSA<1>":   PN = "CJ64"  !CDS_PN = "CJ64";
"VCCSA<2>":   PN = "CH75"  !CDS_PN = "CH75";
"VCCSA<3>":   PN = "CH65"  !CDS_PN = "CH65";
"VCCSA<4>":   PN = "CG74"  !CDS_PN = "CG74";
"VCCSA<5>":   PN = "CG66"  !CDS_PN = "CG66";
"VCCSA<6>":   PN = "CG64"  !CDS_PN = "CG64";
"VCCSA<7>":   PN = "CF75"  !CDS_PN = "CF75";
"VCCSA<8>":   PN = "CF73"  !CDS_PN = "CF73";
"VCCSA<9>":   PN = "CF67"  !CDS_PN = "CF67";
"VCCSA<10>":   PN = "CF65"  !CDS_PN = "CF65";
"VCCSA<11>":   PN = "CE74"  !CDS_PN = "CE74";
"VCCSA<12>":   PN = "CE72"  !CDS_PN = "CE72";
"VCCSA<13>":   PN = "CE68"  !CDS_PN = "CE68";
"VCCSA<14>":   PN = "CE66"  !CDS_PN = "CE66";
"VCCSA<15>":   PN = "CE64"  !CDS_PN = "CE64";
"VCCSA<16>":   PN = "CD71"  !CDS_PN = "CD71";
"VCCSA<17>":   PN = "CD69"  !CDS_PN = "CD69";
"VCCSA<18>":   PN = "CD67"  !CDS_PN = "CD67";
"VCCSA<19>":   PN = "CD65"  !CDS_PN = "CD65";
"VCCSA<20>":   PN = "CC70"  !CDS_PN = "CC70";
"VCCSA<21>":   PN = "CC68"  !CDS_PN = "CC68";
"VCCSA<22>":   PN = "CC66"  !CDS_PN = "CC66";
"VCCSA<23>":   PN = "CB69"  !CDS_PN = "CB69";
"VCCSA<24>":   PN = "CB67"  !CDS_PN = "CB67";
"VCCSA<25>":   PN = "CB65"  !CDS_PN = "CB65";
DRAWING = "@baseboard_fab2_lib.baseboard_fab2(sch_1):page73";
BODY = "SKX_EXT_B","I107": #LOCATION = "U2D1" !CDS_LOCATION = "U2D1" #SEC = "22" !CDS_SEC = "22";
"CD_VCC_CORE_SENSE":   PN = "BN16"  !CDS_PN = "BN16";
"CD_VCCP_SENSE<0>":   PN = "BU16"  !CDS_PN = "BU16";
"CD_VCCP_SENSE<1>":   PN = "BT17"  !CDS_PN = "BT17";
"CD_VSS_VCC_CORE_SENSE":   PN = "BL16"  !CDS_PN = "BL16";
"RSVD<0>":   PN = "EF83"  !CDS_PN = "EF83";
"RSVD<1>":   PN = "EF81"  !CDS_PN = "EF81";
"RSVD<2>":   PN = "EF77"  !CDS_PN = "EF77";
"RSVD<3>":   PN = "EF47"  !CDS_PN = "EF47";
"RSVD<4>":   PN = "EE84"  !CDS_PN = "EE84";
"RSVD<5>":   PN = "EE82"  !CDS_PN = "EE82";
"RSVD<6>":   PN = "EE6"  !CDS_PN = "EE6";
"RSVD<7>":   PN = "EE46"  !CDS_PN = "EE46";
"RSVD<8>":   PN = "EE16"  !CDS_PN = "EE16";
"RSVD<9>":   PN = "ED83"  !CDS_PN = "ED83";
"RSVD<10>":   PN = "ED5"  !CDS_PN = "ED5";
"RSVD<11>":   PN = "ED45"  !CDS_PN = "ED45";
"RSVD<12>":   PN = "EC84"  !CDS_PN = "EC84";
"RSVD<13>":   PN = "EC44"  !CDS_PN = "EC44";
"RSVD<14>":   PN = "EC4"  !CDS_PN = "EC4";
"RSVD<15>":   PN = "EC16"  !CDS_PN = "EC16";
"RSVD<16>":   PN = "EB85"  !CDS_PN = "EB85";
"RSVD<17>":   PN = "EB5"  !CDS_PN = "EB5";
"RSVD<18>":   PN = "EB3"  !CDS_PN = "EB3";
"RSVD<19>":   PN = "EA44"  !CDS_PN = "EA44";
"RSVD<20>":   PN = "EA4"  !CDS_PN = "EA4";
"RSVD<21>":   PN = "DY3"  !CDS_PN = "DY3";
"RSVD<22>":   PN = "DW46"  !CDS_PN = "DW46";
"RSVD<23>":   PN = "DW44"  !CDS_PN = "DW44";
"RSVD<24>":   PN = "DV71"  !CDS_PN = "DV71";
"RSVD<25>":   PN = "DV61"  !CDS_PN = "DV61";
"RSVD<26>":   PN = "DU44"  !CDS_PN = "DU44";
"RSVD<27>":   PN = "DT71"  !CDS_PN = "DT71";
"RSVD<28>":   PN = "DR44"  !CDS_PN = "DR44";
"RSVD<29>":   PN = "DP65"  !CDS_PN = "DP65";
"RSVD<30>":   PN = "DP17"  !CDS_PN = "DP17";
"RSVD<31>":   PN = "DN66"  !CDS_PN = "DN66";
"RSVD<32>":   PN = "DN62"  !CDS_PN = "DN62";
"RSVD<33>":   PN = "DM67"  !CDS_PN = "DM67";
"RSVD<34>":   PN = "DL66"  !CDS_PN = "DL66";
"RSVD<35>":   PN = "DL38"  !CDS_PN = "DL38";
"RSVD<36>":   PN = "DK67"  !CDS_PN = "DK67";
"RSVD<37>":   PN = "DK65"  !CDS_PN = "DK65";
"RSVD<38>":   PN = "DK37"  !CDS_PN = "DK37";
"RSVD<39>":   PN = "DK15"  !CDS_PN = "DK15";
"RSVD<40>":   PN = "DJ66"  !CDS_PN = "DJ66";
"RSVD<41>":   PN = "DJ36"  !CDS_PN = "DJ36";
"RSVD<42>":   PN = "DH65"  !CDS_PN = "DH65";
"RSVD<43>":   PN = "DG64"  !CDS_PN = "DG64";
"RSVD<44>":   PN = "DG36"  !CDS_PN = "DG36";
"RSVD<45>":   PN = "DD51"  !CDS_PN = "DD51";
"RSVD<46>":   PN = "DC52"  !CDS_PN = "DC52";
"RSVD<47>":   PN = "DC46"  !CDS_PN = "DC46";
"RSVD<48>":   PN = "DA56"  !CDS_PN = "DA56";
"RSVD<49>":   PN = "DA54"  !CDS_PN = "DA54";
"RSVD<50>":   PN = "DA52"  !CDS_PN = "DA52";
"RSVD<51>":   PN = "DA40"  !CDS_PN = "DA40";
"RSVD<52>":   PN = "DA24"  !CDS_PN = "DA24";
"RSVD<53>":   PN = "CY73"  !CDS_PN = "CY73";
"RSVD<54>":   PN = "CY63"  !CDS_PN = "CY63";
"RSVD<55>":   PN = "CY57"  !CDS_PN = "CY57";
"RSVD<56>":   PN = "CY53"  !CDS_PN = "CY53";
"RSVD<57>":   PN = "CY39"  !CDS_PN = "CY39";
"RSVD<58>":   PN = "CY25"  !CDS_PN = "CY25";
"RSVD<59>":   PN = "CY23"  !CDS_PN = "CY23";
"RSVD<60>":   PN = "CW62"  !CDS_PN = "CW62";
"RSVD<61>":   PN = "CW60"  !CDS_PN = "CW60";
"RSVD<62>":   PN = "CW24"  !CDS_PN = "CW24";
"RSVD<63>":   PN = "CW22"  !CDS_PN = "CW22";
"RSVD<64>":   PN = "CV69"  !CDS_PN = "CV69";
"RSVD<65>":   PN = "CV23"  !CDS_PN = "CV23";
"RSVD<66>":   PN = "CU60"  !CDS_PN = "CU60";
"RSVD<67>":   PN = "CU6"  !CDS_PN = "CU6";
"RSVD<68>":   PN = "CU24"  !CDS_PN = "CU24";
"RSVD<69>":   PN = "CT69"  !CDS_PN = "CT69";
"RSVD<70>":   PN = "CT5"  !CDS_PN = "CT5";
"RSVD<71>":   PN = "CT23"  !CDS_PN = "CT23";
"RSVD<72>":   PN = "CR60"  !CDS_PN = "CR60";
"RSVD<73>":   PN = "CP31"  !CDS_PN = "CP31";
"RSVD<74>":   PN = "CP23"  !CDS_PN = "CP23";
"RSVD<75>":   PN = "CN28"  !CDS_PN = "CN28";
"RSVD<76>":   PN = "CN24"  !CDS_PN = "CN24";
"RSVD<77>":   PN = "CN22"  !CDS_PN = "CN22";
"RSVD<78>":   PN = "CM25"  !CDS_PN = "CM25";
"RSVD<79>":   PN = "CM23"  !CDS_PN = "CM23";
"RSVD<80>":   PN = "CL26"  !CDS_PN = "CL26";
"VCCIO<0>":   PN = "EE10"  !CDS_PN = "EE10";
"VCCIO<1>":   PN = "AE10"  !CDS_PN = "AE10";
"VCCIO<2>":   PN = "AF5"  !CDS_PN = "AF5";
"VCCIO<3>":   PN = "DV11"  !CDS_PN = "DV11";
"VCCIO<4>":   PN = "AM5"  !CDS_PN = "AM5";
"VCCIO<5>":   PN = "AT5"  !CDS_PN = "AT5";
"VCCIO<6>":   PN = "AT7"  !CDS_PN = "AT7";
"VCCIO<7>":   PN = "BE24"  !CDS_PN = "BE24";
"VCCIO<8>":   PN = "DK21"  !CDS_PN = "DK21";
"VCCIO<9>":   PN = "CF5"  !CDS_PN = "CF5";
"VCCIO<10>":   PN = "CG14"  !CDS_PN = "CG14";
"VCCIO<11>":   PN = "CL20"  !CDS_PN = "CL20";
"VCCIO<12>":   PN = "CP13"  !CDS_PN = "CP13";
"VCCIO<13>":   PN = "DE14"  !CDS_PN = "DE14";
"VCCIO<14>":   PN = "DC18"  !CDS_PN = "DC18";
"VCCIO<15>":   PN = "CY17"  !CDS_PN = "CY17";
"VCCIO<16>":   PN = "CU18"  !CDS_PN = "CU18";
"VCCIO<17>":   PN = "CV21"  !CDS_PN = "CV21";
"VCCIO<18>":   PN = "CU12"  !CDS_PN = "CU12";
"VCCIO<19>":   PN = "CN6"  !CDS_PN = "CN6";
"VCCIO_SENSE":   PN = "BH5"  !CDS_PN = "BH5";
"VCCSA_SENSE":   PN = "CE76"  !CDS_PN = "CE76";
"VSS_VCCIO_SENSE":   PN = "BF5"  !CDS_PN = "BF5";
"VSS_VCCSA_SENSE":   PN = "CG76"  !CDS_PN = "CG76";
DRAWING = "@baseboard_fab2_lib.baseboard_fab2(sch_1):page74";
BODY = "SKX_EXT_B","I20": #LOCATION = "U2D1" !CDS_LOCATION = "U2D1" #SEC = "23" !CDS_SEC = "23";
"VSS<1094>":   PN = "J74"  !CDS_PN = "J74";
"VSS<1095>":   PN = "J72"  !CDS_PN = "J72";
"VSS<1096>":   PN = "J40"  !CDS_PN = "J40";
"VSS<1097>":   PN = "J38"  !CDS_PN = "J38";
"VSS<1098>":   PN = "J34"  !CDS_PN = "J34";
"VSS<1099>":   PN = "J32"  !CDS_PN = "J32";
"VSS<1100>":   PN = "J28"  !CDS_PN = "J28";
"VSS<1101>":   PN = "J26"  !CDS_PN = "J26";
"VSS<1102>":   PN = "J22"  !CDS_PN = "J22";
"VSS<1103>":   PN = "J14"  !CDS_PN = "J14";
"VSS<1104>":   PN = "J12"  !CDS_PN = "J12";
"VSS<1105>":   PN = "J4"  !CDS_PN = "J4";
"VSS<1106>":   PN = "DN44"  !CDS_PN = "DN44";
"VSS<1107>":   PN = "H75"  !CDS_PN = "H75";
"VSS<1108>":   PN = "H71"  !CDS_PN = "H71";
"VSS<1109>":   PN = "H65"  !CDS_PN = "H65";
"VSS<1110>":   PN = "H41"  !CDS_PN = "H41";
"VSS<1111>":   PN = "H39"  !CDS_PN = "H39";
"VSS<1112>":   PN = "H37"  !CDS_PN = "H37";
"VSS<1113>":   PN = "H35"  !CDS_PN = "H35";
"VSS<1114>":   PN = "H33"  !CDS_PN = "H33";
"VSS<1115>":   PN = "H31"  !CDS_PN = "H31";
"VSS<1116>":   PN = "H29"  !CDS_PN = "H29";
"VSS<1117>":   PN = "H27"  !CDS_PN = "H27";
"VSS<1118>":   PN = "H25"  !CDS_PN = "H25";
"VSS<1119>":   PN = "H11"  !CDS_PN = "H11";
"VSS<1120>":   PN = "H3"  !CDS_PN = "H3";
"VSS<1121>":   PN = "G82"  !CDS_PN = "G82";
"VSS<1122>":   PN = "G80"  !CDS_PN = "G80";
"VSS<1123>":   PN = "G78"  !CDS_PN = "G78";
"VSS<1124>":   PN = "G76"  !CDS_PN = "G76";
"VSS<1125>":   PN = "G70"  !CDS_PN = "G70";
"VSS<1126>":   PN = "G66"  !CDS_PN = "G66";
"VSS<1127>":   PN = "G42"  !CDS_PN = "G42";
"VSS<1128>":   PN = "G38"  !CDS_PN = "G38";
"VSS<1129>":   PN = "G36"  !CDS_PN = "G36";
"VSS<1130>":   PN = "G32"  !CDS_PN = "G32";
"VSS<1131>":   PN = "G30"  !CDS_PN = "G30";
"VSS<1132>":   PN = "G26"  !CDS_PN = "G26";
"VSS<1133>":   PN = "G24"  !CDS_PN = "G24";
"VSS<1134>":   PN = "G22"  !CDS_PN = "G22";
"VSS<1135>":   PN = "G8"  !CDS_PN = "G8";
"VSS<1136>":   PN = "G4"  !CDS_PN = "G4";
"VSS<1137>":   PN = "F69"  !CDS_PN = "F69";
"VSS<1138>":   PN = "F67"  !CDS_PN = "F67";
"VSS<1139>":   PN = "F43"  !CDS_PN = "F43";
"VSS<1140>":   PN = "F37"  !CDS_PN = "F37";
"VSS<1141>":   PN = "F31"  !CDS_PN = "F31";
"VSS<1142>":   PN = "F25"  !CDS_PN = "F25";
"VSS<1143>":   PN = "F19"  !CDS_PN = "F19";
"VSS<1144>":   PN = "F17"  !CDS_PN = "F17";
"VSS<1145>":   PN = "F5"  !CDS_PN = "F5";
"VSS<1146>":   PN = "E76"  !CDS_PN = "E76";
"VSS<1147>":   PN = "E74"  !CDS_PN = "E74";
"VSS<1148>":   PN = "E72"  !CDS_PN = "E72";
"VSS<1149>":   PN = "E22"  !CDS_PN = "E22";
"VSS<1150>":   PN = "E20"  !CDS_PN = "E20";
"VSS<1151>":   PN = "E18"  !CDS_PN = "E18";
"VSS<1152>":   PN = "E16"  !CDS_PN = "E16";
"VSS<1153>":   PN = "E8"  !CDS_PN = "E8";
"VSS<1154>":   PN = "E6"  !CDS_PN = "E6";
"VSS<1155>":   PN = "D77"  !CDS_PN = "D77";
"VSS<1156>":   PN = "D43"  !CDS_PN = "D43";
"VSS<1157>":   PN = "D41"  !CDS_PN = "D41";
"VSS<1158>":   PN = "D39"  !CDS_PN = "D39";
"VSS<1159>":   PN = "D37"  !CDS_PN = "D37";
"VSS<1160>":   PN = "D35"  !CDS_PN = "D35";
"VSS<1161>":   PN = "D33"  !CDS_PN = "D33";
"VSS<1162>":   PN = "D31"  !CDS_PN = "D31";
"VSS<1163>":   PN = "D29"  !CDS_PN = "D29";
"VSS<1164>":   PN = "D27"  !CDS_PN = "D27";
"VSS<1165>":   PN = "D25"  !CDS_PN = "D25";
"VSS<1166>":   PN = "D13"  !CDS_PN = "D13";
"VSS<1167>":   PN = "D11"  !CDS_PN = "D11";
"VSS<1168>":   PN = "CM27"  !CDS_PN = "CM27";
"VSS<1169>":   PN = "C78"  !CDS_PN = "C78";
"VSS<1170>":   PN = "C76"  !CDS_PN = "C76";
"VSS<1171>":   PN = "C16"  !CDS_PN = "C16";
"VSS<1172>":   PN = "C14"  !CDS_PN = "C14";
"VSS<1173>":   PN = "C12"  !CDS_PN = "C12";
"VSS<1174>":   PN = "C10"  !CDS_PN = "C10";
"VSS<1175>":   PN = "C8"  !CDS_PN = "C8";
"VSS<1176>":   PN = "B75"  !CDS_PN = "B75";
"VSS<1177>":   PN = "B71"  !CDS_PN = "B71";
"VSS<1178>":   PN = "B37"  !CDS_PN = "B37";
"VSS<1179>":   PN = "B31"  !CDS_PN = "B31";
"VSS<1180>":   PN = "B25"  !CDS_PN = "B25";
"VSS<1181>":   PN = "A38"  !CDS_PN = "A38";
"VSS<1182>":   PN = "A36"  !CDS_PN = "A36";
"VSS<1183>":   PN = "A32"  !CDS_PN = "A32";
"VSS<1184>":   PN = "A30"  !CDS_PN = "A30";
"VSS<1185>":   PN = "A26"  !CDS_PN = "A26";
"VSS<1186>":   PN = "AC58"  !CDS_PN = "AC58";
"VSS<1187>":   PN = "AC60"  !CDS_PN = "AC60";
"VSS<1188>":   PN = "AC62"  !CDS_PN = "AC62";
"VSS<1189>":   PN = "AJ4"  !CDS_PN = "AJ4";
"VSS<1190>":   PN = "AR6"  !CDS_PN = "AR6";
"VSS<1191>":   PN = "CG6"  !CDS_PN = "CG6";
"VSS<1192>":   PN = "CW6"  !CDS_PN = "CW6";
"VSS<1193>":   PN = "DE48"  !CDS_PN = "DE48";
"VSS<1194>":   PN = "DE50"  !CDS_PN = "DE50";
"VSS<1195>":   PN = "DE52"  !CDS_PN = "DE52";
"VSS<1196>":   PN = "DE54"  !CDS_PN = "DE54";
"VSS<1197>":   PN = "DE56"  !CDS_PN = "DE56";
"VSS<1198>":   PN = "DE58"  !CDS_PN = "DE58";
"VSS<1199>":   PN = "DE60"  !CDS_PN = "DE60";
"VSS<1200>":   PN = "DE62"  !CDS_PN = "DE62";
"VSS<1201>":   PN = "DL8"  !CDS_PN = "DL8";
"VSS<1202>":   PN = "DN18"  !CDS_PN = "DN18";
"VSS<1203>":   PN = "DP45"  !CDS_PN = "DP45";
"VSS<1204>":   PN = "DP47"  !CDS_PN = "DP47";
"VSS<1205>":   PN = "DP49"  !CDS_PN = "DP49";
"VSS<1206>":   PN = "DP51"  !CDS_PN = "DP51";
"VSS<1207>":   PN = "DP53"  !CDS_PN = "DP53";
"VSS<1208>":   PN = "DP55"  !CDS_PN = "DP55";
"VSS<1209>":   PN = "DP57"  !CDS_PN = "DP57";
"VSS<1210>":   PN = "DP59"  !CDS_PN = "DP59";
"VSS<1211>":   PN = "DP61"  !CDS_PN = "DP61";
"VSS<1212>":   PN = "DP63"  !CDS_PN = "DP63";
"VSS<1213>":   PN = "DP9"  !CDS_PN = "DP9";
"VSS<1214>":   PN = "DV19"  !CDS_PN = "DV19";
"VSS<1215>":   PN = "DY45"  !CDS_PN = "DY45";
"VSS<1216>":   PN = "DY47"  !CDS_PN = "DY47";
"VSS<1217>":   PN = "DY49"  !CDS_PN = "DY49";
"VSS<1218>":   PN = "DY51"  !CDS_PN = "DY51";
"VSS<1219>":   PN = "DY53"  !CDS_PN = "DY53";
"VSS<1220>":   PN = "DY55"  !CDS_PN = "DY55";
"VSS<1221>":   PN = "DY57"  !CDS_PN = "DY57";
"VSS<1222>":   PN = "DY59"  !CDS_PN = "DY59";
"VSS<1223>":   PN = "DY61"  !CDS_PN = "DY61";
"VSS<1224>":   PN = "DY63"  !CDS_PN = "DY63";
"VSS<1225>":   PN = "EA14"  !CDS_PN = "EA14";
"VSS<1226>":   PN = "L8"  !CDS_PN = "L8";
"VSS<1227>":   PN = "V11"  !CDS_PN = "V11";
"VSS<1228>":   PN = "E66"  !CDS_PN = "E66";
"VSS<1229>":   PN = "ED69"  !CDS_PN = "ED69";
"VSS<1230>":   PN = "EE80"  !CDS_PN = "EE80";
"VSS<1231>":   PN = "EE8"  !CDS_PN = "EE8";
"VSS<1232>":   PN = "EE40"  !CDS_PN = "EE40";
"VSS<1233>":   PN = "ED81"  !CDS_PN = "ED81";
"VSS<1234>":   PN = "ED7"  !CDS_PN = "ED7";
"VSS<1235>":   PN = "ED41"  !CDS_PN = "ED41";
"VSS<1236>":   PN = "EC82"  !CDS_PN = "EC82";
"VSS<1237>":   PN = "EC6"  !CDS_PN = "EC6";
"VSS<1238>":   PN = "EC42"  !CDS_PN = "EC42";
"VSS<1239>":   PN = "DW2"  !CDS_PN = "DW2";
"VSS<1240>":   PN = "EB83"  !CDS_PN = "EB83";
"VSS<1241>":   PN = "EA84"  !CDS_PN = "EA84";
"VSS<1242>":   PN = "DY85"  !CDS_PN = "DY85";
"VSS<1243>":   PN = "J86"  !CDS_PN = "J86";
"VSS<1244>":   PN = "E82"  !CDS_PN = "E82";
"VSS<1245>":   PN = "D81"  !CDS_PN = "D81";
"VSS<1246>":   PN = "D3"  !CDS_PN = "D3";
"VSS<1247>":   PN = "C80"  !CDS_PN = "C80";
"VSS<1248>":   PN = "C4"  !CDS_PN = "C4";
"VSS<1249>":   PN = "B79"  !CDS_PN = "B79";
"VSS<1250>":   PN = "B5"  !CDS_PN = "B5";
"VSS<1251>":   PN = "B43"  !CDS_PN = "B43";
"VSS<1252>":   PN = "A42"  !CDS_PN = "A42";
"VSS<1253>":   PN = "B9"  !CDS_PN = "B9";
BODY = "SKX_EXT_B","I21": #LOCATION = "U2D1" !CDS_LOCATION = "U2D1" #SEC = "24" !CDS_SEC = "24";
"VSS<934>":   PN = "AA16"  !CDS_PN = "AA16";
"VSS<935>":   PN = "AA4"  !CDS_PN = "AA4";
"VSS<936>":   PN = "Y85"  !CDS_PN = "Y85";
"VSS<937>":   PN = "Y83"  !CDS_PN = "Y83";
"VSS<938>":   PN = "Y81"  !CDS_PN = "Y81";
"VSS<939>":   PN = "Y79"  !CDS_PN = "Y79";
"VSS<940>":   PN = "Y73"  !CDS_PN = "Y73";
"VSS<941>":   PN = "Y71"  !CDS_PN = "Y71";
"VSS<942>":   PN = "Y9"  !CDS_PN = "Y9";
"VSS<943>":   PN = "Y7"  !CDS_PN = "Y7";
"VSS<944>":   PN = "Y67"  !CDS_PN = "Y67";
"VSS<945>":   PN = "Y5"  !CDS_PN = "Y5";
"VSS<946>":   PN = "Y17"  !CDS_PN = "Y17";
"VSS<947>":   PN = "Y15"  !CDS_PN = "Y15";
"VSS<948>":   PN = "W82"  !CDS_PN = "W82";
"VSS<949>":   PN = "W78"  !CDS_PN = "W78";
"VSS<950>":   PN = "W74"  !CDS_PN = "W74";
"VSS<951>":   PN = "W68"  !CDS_PN = "W68";
"VSS<952>":   PN = "W42"  !CDS_PN = "W42";
"VSS<953>":   PN = "W40"  !CDS_PN = "W40";
"VSS<954>":   PN = "W38"  !CDS_PN = "W38";
"VSS<955>":   PN = "W36"  !CDS_PN = "W36";
"VSS<956>":   PN = "W34"  !CDS_PN = "W34";
"VSS<957>":   PN = "W32"  !CDS_PN = "W32";
"VSS<958>":   PN = "W30"  !CDS_PN = "W30";
"VSS<959>":   PN = "W28"  !CDS_PN = "W28";
"VSS<960>":   PN = "W26"  !CDS_PN = "W26";
"VSS<961>":   PN = "W24"  !CDS_PN = "W24";
"VSS<962>":   PN = "W22"  !CDS_PN = "W22";
"VSS<963>":   PN = "W12"  !CDS_PN = "W12";
"VSS<964>":   PN = "AC56"  !CDS_PN = "AC56";
"VSS<965>":   PN = "W8"  !CDS_PN = "W8";
"VSS<966>":   PN = "V83"  !CDS_PN = "V83";
"VSS<967>":   PN = "V77"  !CDS_PN = "V77";
"VSS<968>":   PN = "V75"  !CDS_PN = "V75";
"VSS<969>":   PN = "V73"  !CDS_PN = "V73";
"VSS<970>":   PN = "V43"  !CDS_PN = "V43";
"VSS<971>":   PN = "V23"  !CDS_PN = "V23";
"VSS<972>":   PN = "V21"  !CDS_PN = "V21";
"VSS<973>":   PN = "V15"  !CDS_PN = "V15";
"VSS<974>":   PN = "V13"  !CDS_PN = "V13";
"VSS<975>":   PN = "V9"  !CDS_PN = "V9";
"VSS<976>":   PN = "V5"  !CDS_PN = "V5";
"VSS<977>":   PN = "V1"  !CDS_PN = "V1";
"VSS<978>":   PN = "U86"  !CDS_PN = "U86";
"VSS<979>":   PN = "U80"  !CDS_PN = "U80";
"VSS<980>":   PN = "U78"  !CDS_PN = "U78";
"VSS<981>":   PN = "U76"  !CDS_PN = "U76";
"VSS<982>":   PN = "U74"  !CDS_PN = "U74";
"VSS<983>":   PN = "U70"  !CDS_PN = "U70";
"VSS<984>":   PN = "U68"  !CDS_PN = "U68";
"VSS<985>":   PN = "U42"  !CDS_PN = "U42";
"VSS<986>":   PN = "U36"  !CDS_PN = "U36";
"VSS<987>":   PN = "U30"  !CDS_PN = "U30";
"VSS<988>":   PN = "U24"  !CDS_PN = "U24";
"VSS<989>":   PN = "U22"  !CDS_PN = "U22";
"VSS<990>":   PN = "U20"  !CDS_PN = "U20";
"VSS<991>":   PN = "U6"  !CDS_PN = "U6";
"VSS<992>":   PN = "U4"  !CDS_PN = "U4";
"VSS<993>":   PN = "U2"  !CDS_PN = "U2";
"VSS<994>":   PN = "T85"  !CDS_PN = "T85";
"VSS<995>":   PN = "T83"  !CDS_PN = "T83";
"VSS<996>":   PN = "T77"  !CDS_PN = "T77";
"VSS<997>":   PN = "T73"  !CDS_PN = "T73";
"VSS<998>":   PN = "T65"  !CDS_PN = "T65";
"VSS<999>":   PN = "T41"  !CDS_PN = "T41";
"VSS<1000>":   PN = "T37"  !CDS_PN = "T37";
"VSS<1001>":   PN = "T35"  !CDS_PN = "T35";
"VSS<1002>":   PN = "T31"  !CDS_PN = "T31";
"VSS<1003>":   PN = "T29"  !CDS_PN = "T29";
"VSS<1004>":   PN = "T25"  !CDS_PN = "T25";
"VSS<1005>":   PN = "T17"  !CDS_PN = "T17";
"VSS<1006>":   PN = "T13"  !CDS_PN = "T13";
"VSS<1007>":   PN = "R86"  !CDS_PN = "R86";
"VSS<1008>":   PN = "R78"  !CDS_PN = "R78";
"VSS<1009>":   PN = "R72"  !CDS_PN = "R72";
"VSS<1010>":   PN = "R68"  !CDS_PN = "R68";
"VSS<1011>":   PN = "R40"  !CDS_PN = "R40";
"VSS<1012>":   PN = "R38"  !CDS_PN = "R38";
"VSS<1013>":   PN = "R34"  !CDS_PN = "R34";
"VSS<1014>":   PN = "R32"  !CDS_PN = "R32";
"VSS<1015>":   PN = "R28"  !CDS_PN = "R28";
"VSS<1016>":   PN = "R26"  !CDS_PN = "R26";
"VSS<1017>":   PN = "R22"  !CDS_PN = "R22";
"VSS<1018>":   PN = "R4"  !CDS_PN = "R4";
"VSS<1019>":   PN = "R2"  !CDS_PN = "R2";
"VSS<1020>":   PN = "R18"  !CDS_PN = "R18";
"VSS<1021>":   PN = "R14"  !CDS_PN = "R14";
"VSS<1022>":   PN = "P83"  !CDS_PN = "P83";
"VSS<1023>":   PN = "P81"  !CDS_PN = "P81";
"VSS<1024>":   PN = "P71"  !CDS_PN = "P71";
"VSS<1025>":   PN = "P69"  !CDS_PN = "P69";
"VSS<1026>":   PN = "P67"  !CDS_PN = "P67";
"VSS<1027>":   PN = "P39"  !CDS_PN = "P39";
"VSS<1028>":   PN = "P33"  !CDS_PN = "P33";
"VSS<1029>":   PN = "P27"  !CDS_PN = "P27";
"VSS<1030>":   PN = "P15"  !CDS_PN = "P15";
"VSS<1031>":   PN = "P11"  !CDS_PN = "P11";
"VSS<1032>":   PN = "N8"  !CDS_PN = "N8";
"VSS<1033>":   PN = "N4"  !CDS_PN = "N4";
"VSS<1034>":   PN = "N78"  !CDS_PN = "N78";
"VSS<1035>":   PN = "N76"  !CDS_PN = "N76";
"VSS<1036>":   PN = "N74"  !CDS_PN = "N74";
"VSS<1037>":   PN = "N72"  !CDS_PN = "N72";
"VSS<1038>":   PN = "N70"  !CDS_PN = "N70";
"VSS<1039>":   PN = "N66"  !CDS_PN = "N66";
"VSS<1040>":   PN = "N6"  !CDS_PN = "N6";
"VSS<1041>":   PN = "N22"  !CDS_PN = "N22";
"VSS<1042>":   PN = "N20"  !CDS_PN = "N20";
"VSS<1043>":   PN = "DM19"  !CDS_PN = "DM19";
"VSS<1044>":   PN = "M85"  !CDS_PN = "M85";
"VSS<1045>":   PN = "M83"  !CDS_PN = "M83";
"VSS<1046>":   PN = "M79"  !CDS_PN = "M79";
"VSS<1047>":   PN = "M71"  !CDS_PN = "M71";
"VSS<1048>":   PN = "M65"  !CDS_PN = "M65";
"VSS<1049>":   PN = "M43"  !CDS_PN = "M43";
"VSS<1050>":   PN = "M41"  !CDS_PN = "M41";
"VSS<1051>":   PN = "M39"  !CDS_PN = "M39";
"VSS<1052>":   PN = "M37"  !CDS_PN = "M37";
"VSS<1053>":   PN = "M35"  !CDS_PN = "M35";
"VSS<1054>":   PN = "M33"  !CDS_PN = "M33";
"VSS<1055>":   PN = "M31"  !CDS_PN = "M31";
"VSS<1056>":   PN = "M29"  !CDS_PN = "M29";
"VSS<1057>":   PN = "M27"  !CDS_PN = "M27";
"VSS<1058>":   PN = "M25"  !CDS_PN = "M25";
"VSS<1059>":   PN = "M23"  !CDS_PN = "M23";
"VSS<1060>":   PN = "M19"  !CDS_PN = "M19";
"VSS<1061>":   PN = "M17"  !CDS_PN = "M17";
"VSS<1062>":   PN = "M15"  !CDS_PN = "M15";
"VSS<1063>":   PN = "CT7"  !CDS_PN = "CT7";
"VSS<1064>":   PN = "BT9"  !CDS_PN = "BT9";
"VSS<1065>":   PN = "L82"  !CDS_PN = "L82";
"VSS<1066>":   PN = "L80"  !CDS_PN = "L80";
"VSS<1067>":   PN = "L78"  !CDS_PN = "L78";
"VSS<1068>":   PN = "L72"  !CDS_PN = "L72";
"VSS<1069>":   PN = "L22"  !CDS_PN = "L22";
"VSS<1070>":   PN = "L20"  !CDS_PN = "L20";
"VSS<1071>":   PN = "L6"  !CDS_PN = "L6";
"VSS<1072>":   PN = "L2"  !CDS_PN = "L2";
"VSS<1073>":   PN = "L10"  !CDS_PN = "L10";
"VSS<1074>":   PN = "K85"  !CDS_PN = "K85";
"VSS<1075>":   PN = "K83"  !CDS_PN = "K83";
"VSS<1076>":   PN = "K81"  !CDS_PN = "K81";
"VSS<1077>":   PN = "K77"  !CDS_PN = "K77";
"VSS<1078>":   PN = "K73"  !CDS_PN = "K73";
"VSS<1079>":   PN = "K71"  !CDS_PN = "K71";
"VSS<1080>":   PN = "K69"  !CDS_PN = "K69";
"VSS<1081>":   PN = "K67"  !CDS_PN = "K67";
"VSS<1082>":   PN = "K65"  !CDS_PN = "K65";
"VSS<1083>":   PN = "K39"  !CDS_PN = "K39";
"VSS<1084>":   PN = "K33"  !CDS_PN = "K33";
"VSS<1085>":   PN = "K27"  !CDS_PN = "K27";
"VSS<1086>":   PN = "DB7"  !CDS_PN = "DB7";
"VSS<1087>":   PN = "K17"  !CDS_PN = "K17";
"VSS<1088>":   PN = "K13"  !CDS_PN = "K13";
"VSS<1089>":   PN = "K11"  !CDS_PN = "K11";
"VSS<1090>":   PN = "K1"  !CDS_PN = "K1";
"VSS<1091>":   PN = "J84"  !CDS_PN = "J84";
"VSS<1092>":   PN = "J82"  !CDS_PN = "J82";
"VSS<1093>":   PN = "J76"  !CDS_PN = "J76";
BODY = "SKX_EXT_B","I22": #LOCATION = "U2D1" !CDS_LOCATION = "U2D1" #SEC = "25" !CDS_SEC = "25";
"VSS<774>":   PN = "AL68"  !CDS_PN = "AL68";
"VSS<775>":   PN = "AL64"  !CDS_PN = "AL64";
"VSS<776>":   PN = "AL56"  !CDS_PN = "AL56";
"VSS<777>":   PN = "AL32"  !CDS_PN = "AL32";
"VSS<778>":   PN = "AL30"  !CDS_PN = "AL30";
"VSS<779>":   PN = "AL24"  !CDS_PN = "AL24";
"VSS<780>":   PN = "AL10"  !CDS_PN = "AL10";
"VSS<781>":   PN = "AL4"  !CDS_PN = "AL4";
"VSS<782>":   PN = "AK85"  !CDS_PN = "AK85";
"VSS<783>":   PN = "AK83"  !CDS_PN = "AK83";
"VSS<784>":   PN = "AK81"  !CDS_PN = "AK81";
"VSS<785>":   PN = "AK79"  !CDS_PN = "AK79";
"VSS<786>":   PN = "AK73"  !CDS_PN = "AK73";
"VSS<787>":   PN = "AK67"  !CDS_PN = "AK67";
"VSS<788>":   PN = "AK65"  !CDS_PN = "AK65";
"VSS<789>":   PN = "AK55"  !CDS_PN = "AK55";
"VSS<790>":   PN = "AK33"  !CDS_PN = "AK33";
"VSS<791>":   PN = "AK31"  !CDS_PN = "AK31";
"VSS<792>":   PN = "AK29"  !CDS_PN = "AK29";
"VSS<793>":   PN = "AK25"  !CDS_PN = "AK25";
"VSS<794>":   PN = "AK23"  !CDS_PN = "AK23";
"VSS<795>":   PN = "AK19"  !CDS_PN = "AK19";
"VSS<796>":   PN = "AK13"  !CDS_PN = "AK13";
"VSS<797>":   PN = "AK9"  !CDS_PN = "AK9";
"VSS<798>":   PN = "AJ86"  !CDS_PN = "AJ86";
"VSS<799>":   PN = "AJ82"  !CDS_PN = "AJ82";
"VSS<800>":   PN = "AJ78"  !CDS_PN = "AJ78";
"VSS<801>":   PN = "AJ74"  !CDS_PN = "AJ74";
"VSS<802>":   PN = "AJ68"  !CDS_PN = "AJ68";
"VSS<803>":   PN = "AJ66"  !CDS_PN = "AJ66";
"VSS<804>":   PN = "AJ54"  !CDS_PN = "AJ54";
"VSS<805>":   PN = "AJ52"  !CDS_PN = "AJ52";
"VSS<806>":   PN = "AJ50"  !CDS_PN = "AJ50";
"VSS<807>":   PN = "AJ48"  !CDS_PN = "AJ48";
"VSS<808>":   PN = "AJ46"  !CDS_PN = "AJ46";
"VSS<809>":   PN = "AJ34"  !CDS_PN = "AJ34";
"VSS<810>":   PN = "AJ32"  !CDS_PN = "AJ32";
"VSS<811>":   PN = "AJ28"  !CDS_PN = "AJ28";
"VSS<812>":   PN = "AJ26"  !CDS_PN = "AJ26";
"VSS<813>":   PN = "AJ22"  !CDS_PN = "AJ22";
"VSS<814>":   PN = "AJ8"  !CDS_PN = "AJ8";
"VSS<815>":   PN = "AH83"  !CDS_PN = "AH83";
"VSS<816>":   PN = "AH77"  !CDS_PN = "AH77";
"VSS<817>":   PN = "AH75"  !CDS_PN = "AH75";
"VSS<818>":   PN = "AH69"  !CDS_PN = "AH69";
"VSS<819>":   PN = "AH65"  !CDS_PN = "AH65";
"VSS<820>":   PN = "AH61"  !CDS_PN = "AH61";
"VSS<821>":   PN = "AH59"  !CDS_PN = "AH59";
"VSS<822>":   PN = "AH53"  !CDS_PN = "AH53";
"VSS<823>":   PN = "AH51"  !CDS_PN = "AH51";
"VSS<824>":   PN = "AH49"  !CDS_PN = "AH49";
"VSS<825>":   PN = "AH47"  !CDS_PN = "AH47";
"VSS<826>":   PN = "AH45"  !CDS_PN = "AH45";
"VSS<827>":   PN = "AH35"  !CDS_PN = "AH35";
"VSS<828>":   PN = "AH33"  !CDS_PN = "AH33";
"VSS<829>":   PN = "AH27"  !CDS_PN = "AH27";
"VSS<830>":   PN = "AH21"  !CDS_PN = "AH21";
"VSS<831>":   PN = "AH5"  !CDS_PN = "AH5";
"VSS<832>":   PN = "AH1"  !CDS_PN = "AH1";
"VSS<833>":   PN = "AG80"  !CDS_PN = "AG80";
"VSS<834>":   PN = "AG78"  !CDS_PN = "AG78";
"VSS<835>":   PN = "AG76"  !CDS_PN = "AG76";
"VSS<836>":   PN = "AG74"  !CDS_PN = "AG74";
"VSS<837>":   PN = "AG70"  !CDS_PN = "AG70";
"VSS<838>":   PN = "AG64"  !CDS_PN = "AG64";
"VSS<839>":   PN = "AG36"  !CDS_PN = "AG36";
"VSS<840>":   PN = "AG18"  !CDS_PN = "AG18";
"VSS<841>":   PN = "AG14"  !CDS_PN = "AG14";
"VSS<842>":   PN = "AG12"  !CDS_PN = "AG12";
"VSS<843>":   PN = "AF85"  !CDS_PN = "AF85";
"VSS<844>":   PN = "AF83"  !CDS_PN = "AF83";
"VSS<845>":   PN = "AF77"  !CDS_PN = "AF77";
"VSS<846>":   PN = "AF73"  !CDS_PN = "AF73";
"VSS<847>":   PN = "AF41"  !CDS_PN = "AF41";
"VSS<848>":   PN = "AF39"  !CDS_PN = "AF39";
"VSS<849>":   PN = "AF37"  !CDS_PN = "AF37";
"VSS<850>":   PN = "AF33"  !CDS_PN = "AF33";
"VSS<851>":   PN = "AF31"  !CDS_PN = "AF31";
"VSS<852>":   PN = "AF29"  !CDS_PN = "AF29";
"VSS<853>":   PN = "AF27"  !CDS_PN = "AF27";
"VSS<854>":   PN = "AF25"  !CDS_PN = "AF25";
"VSS<855>":   PN = "AF23"  !CDS_PN = "AF23";
"VSS<856>":   PN = "AF21"  !CDS_PN = "AF21";
"VSS<857>":   PN = "AF9"  !CDS_PN = "AF9";
"VSS<858>":   PN = "AC52"  !CDS_PN = "AC52";
"VSS<859>":   PN = "AF1"  !CDS_PN = "AF1";
"VSS<860>":   PN = "AE78"  !CDS_PN = "AE78";
"VSS<861>":   PN = "AE70"  !CDS_PN = "AE70";
"VSS<862>":   PN = "AE68"  !CDS_PN = "AE68";
"VSS<863>":   PN = "AE66"  !CDS_PN = "AE66";
"VSS<864>":   PN = "AE64"  !CDS_PN = "AE64";
"VSS<865>":   PN = "AE42"  !CDS_PN = "AE42";
"VSS<866>":   PN = "AE40"  !CDS_PN = "AE40";
"VSS<867>":   PN = "AE38"  !CDS_PN = "AE38";
"VSS<868>":   PN = "AE16"  !CDS_PN = "AE16";
"VSS<869>":   PN = "AC54"  !CDS_PN = "AC54";
"VSS<870>":   PN = "AE8"  !CDS_PN = "AE8";
"VSS<871>":   PN = "AE4"  !CDS_PN = "AE4";
"VSS<872>":   PN = "AD85"  !CDS_PN = "AD85";
"VSS<873>":   PN = "AD83"  !CDS_PN = "AD83";
"VSS<874>":   PN = "AD81"  !CDS_PN = "AD81";
"VSS<875>":   PN = "AD75"  !CDS_PN = "AD75";
"VSS<876>":   PN = "AD73"  !CDS_PN = "AD73";
"VSS<877>":   PN = "AD71"  !CDS_PN = "AD71";
"VSS<878>":   PN = "AD43"  !CDS_PN = "AD43";
"VSS<879>":   PN = "AD39"  !CDS_PN = "AD39";
"VSS<880>":   PN = "AD33"  !CDS_PN = "AD33";
"VSS<881>":   PN = "AD27"  !CDS_PN = "AD27";
"VSS<882>":   PN = "AD21"  !CDS_PN = "AD21";
"VSS<883>":   PN = "AD19"  !CDS_PN = "AD19";
"VSS<884>":   PN = "AD15"  !CDS_PN = "AD15";
"VSS<885>":   PN = "AD13"  !CDS_PN = "AD13";
"VSS<886>":   PN = "AD11"  !CDS_PN = "AD11";
"VSS<887>":   PN = "AD9"  !CDS_PN = "AD9";
"VSS<888>":   PN = "AD7"  !CDS_PN = "AD7";
"VSS<889>":   PN = "AD3"  !CDS_PN = "AD3";
"VSS<890>":   PN = "AC86"  !CDS_PN = "AC86";
"VSS<891>":   PN = "AC84"  !CDS_PN = "AC84";
"VSS<892>":   PN = "AC78"  !CDS_PN = "AC78";
"VSS<893>":   PN = "AC72"  !CDS_PN = "AC72";
"VSS<894>":   PN = "AC70"  !CDS_PN = "AC70";
"VSS<895>":   PN = "AC64"  !CDS_PN = "AC64";
"VSS<896>":   PN = "AC40"  !CDS_PN = "AC40";
"VSS<897>":   PN = "AC38"  !CDS_PN = "AC38";
"VSS<898>":   PN = "AC34"  !CDS_PN = "AC34";
"VSS<899>":   PN = "AC32"  !CDS_PN = "AC32";
"VSS<900>":   PN = "AC28"  !CDS_PN = "AC28";
"VSS<901>":   PN = "AC26"  !CDS_PN = "AC26";
"VSS<902>":   PN = "AC22"  !CDS_PN = "AC22";
"VSS<903>":   PN = "AC18"  !CDS_PN = "AC18";
"VSS<904>":   PN = "AB85"  !CDS_PN = "AB85";
"VSS<905>":   PN = "AB83"  !CDS_PN = "AB83";
"VSS<906>":   PN = "AB79"  !CDS_PN = "AB79";
"VSS<907>":   PN = "AB73"  !CDS_PN = "AB73";
"VSS<908>":   PN = "AB69"  !CDS_PN = "AB69";
"VSS<909>":   PN = "AB65"  !CDS_PN = "AB65";
"VSS<910>":   PN = "AB41"  !CDS_PN = "AB41";
"VSS<911>":   PN = "AB37"  !CDS_PN = "AB37";
"VSS<912>":   PN = "AB35"  !CDS_PN = "AB35";
"VSS<913>":   PN = "AB31"  !CDS_PN = "AB31";
"VSS<914>":   PN = "AB29"  !CDS_PN = "AB29";
"VSS<915>":   PN = "AB25"  !CDS_PN = "AB25";
"VSS<916>":   PN = "AB23"  !CDS_PN = "AB23";
"VSS<917>":   PN = "AB21"  !CDS_PN = "AB21";
"VSS<918>":   PN = "AB11"  !CDS_PN = "AB11";
"VSS<919>":   PN = "AB5"  !CDS_PN = "AB5";
"VSS<920>":   PN = "AB1"  !CDS_PN = "AB1";
"VSS<921>":   PN = "AA82"  !CDS_PN = "AA82";
"VSS<922>":   PN = "AA80"  !CDS_PN = "AA80";
"VSS<923>":   PN = "AA78"  !CDS_PN = "AA78";
"VSS<924>":   PN = "AA76"  !CDS_PN = "AA76";
"VSS<925>":   PN = "AA68"  !CDS_PN = "AA68";
"VSS<926>":   PN = "AA66"  !CDS_PN = "AA66";
"VSS<927>":   PN = "AA64"  !CDS_PN = "AA64";
"VSS<928>":   PN = "AA42"  !CDS_PN = "AA42";
"VSS<929>":   PN = "AA36"  !CDS_PN = "AA36";
"VSS<930>":   PN = "AA30"  !CDS_PN = "AA30";
"VSS<931>":   PN = "AA24"  !CDS_PN = "AA24";
"VSS<932>":   PN = "AA22"  !CDS_PN = "AA22";
"VSS<933>":   PN = "AA18"  !CDS_PN = "AA18";
BODY = "SKX_EXT_B","I23": #LOCATION = "U2D1" !CDS_LOCATION = "U2D1" #SEC = "26" !CDS_SEC = "26";
"VSS<614>":   PN = "BG72"  !CDS_PN = "BG72";
"VSS<615>":   PN = "BG24"  !CDS_PN = "BG24";
"VSS<616>":   PN = "BG22"  !CDS_PN = "BG22";
"VSS<617>":   PN = "BG10"  !CDS_PN = "BG10";
"VSS<618>":   PN = "BG8"  !CDS_PN = "BG8";
"VSS<619>":   PN = "BG6"  !CDS_PN = "BG6";
"VSS<620>":   PN = "BF71"  !CDS_PN = "BF71";
"VSS<621>":   PN = "BF69"  !CDS_PN = "BF69";
"VSS<622>":   PN = "BF67"  !CDS_PN = "BF67";
"VSS<623>":   PN = "BF65"  !CDS_PN = "BF65";
"VSS<624>":   PN = "BF63"  !CDS_PN = "BF63";
"VSS<625>":   PN = "BF25"  !CDS_PN = "BF25";
"VSS<626>":   PN = "BF19"  !CDS_PN = "BF19";
"VSS<627>":   PN = "BF17"  !CDS_PN = "BF17";
"VSS<628>":   PN = "BF15"  !CDS_PN = "BF15";
"VSS<629>":   PN = "BF9"  !CDS_PN = "BF9";
"VSS<630>":   PN = "BE70"  !CDS_PN = "BE70";
"VSS<631>":   PN = "BE68"  !CDS_PN = "BE68";
"VSS<632>":   PN = "BE66"  !CDS_PN = "BE66";
"VSS<633>":   PN = "BE64"  !CDS_PN = "BE64";
"VSS<634>":   PN = "BE26"  !CDS_PN = "BE26";
"VSS<635>":   PN = "BE10"  !CDS_PN = "BE10";
"VSS<636>":   PN = "BE8"  !CDS_PN = "BE8";
"VSS<637>":   PN = "BE6"  !CDS_PN = "BE6";
"VSS<638>":   PN = "BE4"  !CDS_PN = "BE4";
"VSS<639>":   PN = "BD71"  !CDS_PN = "BD71";
"VSS<640>":   PN = "BD63"  !CDS_PN = "BD63";
"VSS<641>":   PN = "BD27"  !CDS_PN = "BD27";
"VSS<642>":   PN = "BD21"  !CDS_PN = "BD21";
"VSS<643>":   PN = "BD15"  !CDS_PN = "BD15";
"VSS<644>":   PN = "BD11"  !CDS_PN = "BD11";
"VSS<645>":   PN = "BD5"  !CDS_PN = "BD5";
"VSS<646>":   PN = "BC82"  !CDS_PN = "BC82";
"VSS<647>":   PN = "BC80"  !CDS_PN = "BC80";
"VSS<648>":   PN = "BC78"  !CDS_PN = "BC78";
"VSS<649>":   PN = "BC76"  !CDS_PN = "BC76";
"VSS<650>":   PN = "BC74"  !CDS_PN = "BC74";
"VSS<651>":   PN = "BC72"  !CDS_PN = "BC72";
"VSS<652>":   PN = "BC70"  !CDS_PN = "BC70";
"VSS<653>":   PN = "BC16"  !CDS_PN = "BC16";
"VSS<654>":   PN = "BC12"  !CDS_PN = "BC12";
"VSS<655>":   PN = "BC8"  !CDS_PN = "BC8";
"VSS<656>":   PN = "BC4"  !CDS_PN = "BC4";
"VSS<657>":   PN = "BB83"  !CDS_PN = "BB83";
"VSS<658>":   PN = "BB81"  !CDS_PN = "BB81";
"VSS<659>":   PN = "BB79"  !CDS_PN = "BB79";
"VSS<660>":   PN = "BB77"  !CDS_PN = "BB77";
"VSS<661>":   PN = "BB75"  !CDS_PN = "BB75";
"VSS<662>":   PN = "BB73"  !CDS_PN = "BB73";
"VSS<663>":   PN = "BB69"  !CDS_PN = "BB69";
"VSS<664>":   PN = "BB63"  !CDS_PN = "BB63";
"VSS<665>":   PN = "BB23"  !CDS_PN = "BB23";
"VSS<666>":   PN = "BB19"  !CDS_PN = "BB19";
"VSS<667>":   PN = "BA84"  !CDS_PN = "BA84";
"VSS<668>":   PN = "BA80"  !CDS_PN = "BA80";
"VSS<669>":   PN = "BA74"  !CDS_PN = "BA74";
"VSS<670>":   PN = "BA68"  !CDS_PN = "BA68";
"VSS<671>":   PN = "BA62"  !CDS_PN = "BA62";
"VSS<672>":   PN = "BA12"  !CDS_PN = "BA12";
"VSS<673>":   PN = "BA6"  !CDS_PN = "BA6";
"VSS<674>":   PN = "BA2"  !CDS_PN = "BA2";
"VSS<675>":   PN = "AY81"  !CDS_PN = "AY81";
"VSS<676>":   PN = "AY79"  !CDS_PN = "AY79";
"VSS<677>":   PN = "AY63"  !CDS_PN = "AY63";
"VSS<678>":   PN = "AY25"  !CDS_PN = "AY25";
"VSS<679>":   PN = "AY23"  !CDS_PN = "AY23";
"VSS<680>":   PN = "AY21"  !CDS_PN = "AY21";
"VSS<681>":   PN = "AY17"  !CDS_PN = "AY17";
"VSS<682>":   PN = "AY15"  !CDS_PN = "AY15";
"VSS<683>":   PN = "AY5"  !CDS_PN = "AY5";
"VSS<684>":   PN = "AW84"  !CDS_PN = "AW84";
"VSS<685>":   PN = "AW82"  !CDS_PN = "AW82";
"VSS<686>":   PN = "AW78"  !CDS_PN = "AW78";
"VSS<687>":   PN = "AW74"  !CDS_PN = "AW74";
"VSS<688>":   PN = "AW72"  !CDS_PN = "AW72";
"VSS<689>":   PN = "AW70"  !CDS_PN = "AW70";
"VSS<690>":   PN = "AW68"  !CDS_PN = "AW68";
"VSS<691>":   PN = "AW66"  !CDS_PN = "AW66";
"VSS<692>":   PN = "AW62"  !CDS_PN = "AW62";
"VSS<693>":   PN = "AW10"  !CDS_PN = "AW10";
"VSS<694>":   PN = "AW2"  !CDS_PN = "AW2";
"VSS<695>":   PN = "AV83"  !CDS_PN = "AV83";
"VSS<696>":   PN = "AV75"  !CDS_PN = "AV75";
"VSS<697>":   PN = "AV67"  !CDS_PN = "AV67";
"VSS<698>":   PN = "AV65"  !CDS_PN = "AV65";
"VSS<699>":   PN = "AV63"  !CDS_PN = "AV63";
"VSS<700>":   PN = "AV25"  !CDS_PN = "AV25";
"VSS<701>":   PN = "AV23"  !CDS_PN = "AV23";
"VSS<702>":   PN = "AV19"  !CDS_PN = "AV19";
"VSS<703>":   PN = "AV13"  !CDS_PN = "AV13";
"VSS<704>":   PN = "AV11"  !CDS_PN = "AV11";
"VSS<705>":   PN = "AV7"  !CDS_PN = "AV7";
"VSS<706>":   PN = "AV3"  !CDS_PN = "AV3";
"VSS<707>":   PN = "AV1"  !CDS_PN = "AV1";
"VSS<708>":   PN = "AU86"  !CDS_PN = "AU86";
"VSS<709>":   PN = "AU84"  !CDS_PN = "AU84";
"VSS<710>":   PN = "AU80"  !CDS_PN = "AU80";
"VSS<711>":   PN = "AU78"  !CDS_PN = "AU78";
"VSS<712>":   PN = "AU76"  !CDS_PN = "AU76";
"VSS<713>":   PN = "AU74"  !CDS_PN = "AU74";
"VSS<714>":   PN = "AU68"  !CDS_PN = "AU68";
"VSS<715>":   PN = "AU64"  !CDS_PN = "AU64";
"VSS<716>":   PN = "AU62"  !CDS_PN = "AU62";
"VSS<717>":   PN = "AU28"  !CDS_PN = "AU28";
"VSS<718>":   PN = "AU26"  !CDS_PN = "AU26";
"VSS<719>":   PN = "AU6"  !CDS_PN = "AU6";
"VSS<720>":   PN = "AU2"  !CDS_PN = "AU2";
"VSS<721>":   PN = "AT85"  !CDS_PN = "AT85";
"VSS<722>":   PN = "AT83"  !CDS_PN = "AT83";
"VSS<723>":   PN = "AT77"  !CDS_PN = "AT77";
"VSS<724>":   PN = "AT73"  !CDS_PN = "AT73";
"VSS<725>":   PN = "AT69"  !CDS_PN = "AT69";
"VSS<726>":   PN = "AT63"  !CDS_PN = "AT63";
"VSS<727>":   PN = "AT61"  !CDS_PN = "AT61";
"VSS<728>":   PN = "AT27"  !CDS_PN = "AT27";
"VSS<729>":   PN = "AT21"  !CDS_PN = "AT21";
"VSS<730>":   PN = "AT17"  !CDS_PN = "AT17";
"VSS<731>":   PN = "AT15"  !CDS_PN = "AT15";
"VSS<732>":   PN = "P63"  !CDS_PN = "P63";
"VSS<733>":   PN = "AC48"  !CDS_PN = "AC48";
"VSS<734>":   PN = "AR78"  !CDS_PN = "AR78";
"VSS<735>":   PN = "AR72"  !CDS_PN = "AR72";
"VSS<736>":   PN = "AR60"  !CDS_PN = "AR60";
"VSS<737>":   PN = "AR30"  !CDS_PN = "AR30";
"VSS<738>":   PN = "AR24"  !CDS_PN = "AR24";
"VSS<739>":   PN = "AR10"  !CDS_PN = "AR10";
"VSS<740>":   PN = "AP85"  !CDS_PN = "AP85";
"VSS<741>":   PN = "AP83"  !CDS_PN = "AP83";
"VSS<742>":   PN = "AP81"  !CDS_PN = "AP81";
"VSS<743>":   PN = "AP75"  !CDS_PN = "AP75";
"VSS<744>":   PN = "AP73"  !CDS_PN = "AP73";
"VSS<745>":   PN = "AP69"  !CDS_PN = "AP69";
"VSS<746>":   PN = "AP67"  !CDS_PN = "AP67";
"VSS<747>":   PN = "AP65"  !CDS_PN = "AP65";
"VSS<748>":   PN = "AP63"  !CDS_PN = "AP63";
"VSS<749>":   PN = "AP59"  !CDS_PN = "AP59";
"VSS<750>":   PN = "AP31"  !CDS_PN = "AP31";
"VSS<751>":   PN = "AP19"  !CDS_PN = "AP19";
"VSS<752>":   PN = "AP13"  !CDS_PN = "AP13";
"VSS<753>":   PN = "AP9"  !CDS_PN = "AP9";
"VSS<754>":   PN = "AP5"  !CDS_PN = "AP5";
"VSS<755>":   PN = "AN78"  !CDS_PN = "AN78";
"VSS<756>":   PN = "AN58"  !CDS_PN = "AN58";
"VSS<757>":   PN = "AN28"  !CDS_PN = "AN28";
"VSS<758>":   PN = "AN6"  !CDS_PN = "AN6";
"VSS<759>":   PN = "AN2"  !CDS_PN = "AN2";
"VSS<760>":   PN = "AM83"  !CDS_PN = "AM83";
"VSS<761>":   PN = "AM79"  !CDS_PN = "AM79";
"VSS<762>":   PN = "AM73"  !CDS_PN = "AM73";
"VSS<763>":   PN = "AM69"  !CDS_PN = "AM69";
"VSS<764>":   PN = "AM63"  !CDS_PN = "AM63";
"VSS<765>":   PN = "AM57"  !CDS_PN = "AM57";
"VSS<766>":   PN = "AM31"  !CDS_PN = "AM31";
"VSS<767>":   PN = "AC50"  !CDS_PN = "AC50";
"VSS<768>":   PN = "AM1"  !CDS_PN = "AM1";
"VSS<769>":   PN = "AL86"  !CDS_PN = "AL86";
"VSS<770>":   PN = "AL82"  !CDS_PN = "AL82";
"VSS<771>":   PN = "AL80"  !CDS_PN = "AL80";
"VSS<772>":   PN = "AL78"  !CDS_PN = "AL78";
"VSS<773>":   PN = "AL76"  !CDS_PN = "AL76";
DRAWING = "@baseboard_fab2_lib.baseboard_fab2(sch_1):page75";
BODY = "SKX_EXT_B","I17": #LOCATION = "U2D1" !CDS_LOCATION = "U2D1" #SEC = "27" !CDS_SEC = "27";
"VSS<454>":   PN = "P49"  !CDS_PN = "P49";
"VSS<455>":   PN = "CJ12"  !CDS_PN = "CJ12";
"VSS<456>":   PN = "CJ10"  !CDS_PN = "CJ10";
"VSS<457>":   PN = "CJ8"  !CDS_PN = "CJ8";
"VSS<458>":   PN = "CJ6"  !CDS_PN = "CJ6";
"VSS<459>":   PN = "CJ2"  !CDS_PN = "CJ2";
"VSS<460>":   PN = "CH83"  !CDS_PN = "CH83";
"VSS<461>":   PN = "CH81"  !CDS_PN = "CH81";
"VSS<462>":   PN = "CH79"  !CDS_PN = "CH79";
"VSS<463>":   PN = "CH73"  !CDS_PN = "CH73";
"VSS<464>":   PN = "CH67"  !CDS_PN = "CH67";
"VSS<465>":   PN = "CH63"  !CDS_PN = "CH63";
"VSS<466>":   PN = "CH19"  !CDS_PN = "CH19";
"VSS<467>":   PN = "CH15"  !CDS_PN = "CH15";
"VSS<468>":   PN = "CH3"  !CDS_PN = "CH3";
"VSS<469>":   PN = "CH1"  !CDS_PN = "CH1";
"VSS<470>":   PN = "CG80"  !CDS_PN = "CG80";
"VSS<471>":   PN = "CG72"  !CDS_PN = "CG72";
"VSS<472>":   PN = "CG68"  !CDS_PN = "CG68";
"VSS<473>":   PN = "CG62"  !CDS_PN = "CG62";
"VSS<474>":   PN = "CG22"  !CDS_PN = "CG22";
"VSS<475>":   PN = "CG18"  !CDS_PN = "CG18";
"VSS<476>":   PN = "P51"  !CDS_PN = "P51";
"VSS<477>":   PN = "CF83"  !CDS_PN = "CF83";
"VSS<478>":   PN = "CF77"  !CDS_PN = "CF77";
"VSS<479>":   PN = "CF71"  !CDS_PN = "CF71";
"VSS<480>":   PN = "CF69"  !CDS_PN = "CF69";
"VSS<481>":   PN = "CF63"  !CDS_PN = "CF63";
"VSS<482>":   PN = "CF9"  !CDS_PN = "CF9";
"VSS<483>":   PN = "P53"  !CDS_PN = "P53";
"VSS<484>":   PN = "CE82"  !CDS_PN = "CE82";
"VSS<485>":   PN = "CE70"  !CDS_PN = "CE70";
"VSS<486>":   PN = "CE62"  !CDS_PN = "CE62";
"VSS<487>":   PN = "CE26"  !CDS_PN = "CE26";
"VSS<488>":   PN = "CE20"  !CDS_PN = "CE20";
"VSS<489>":   PN = "CE14"  !CDS_PN = "CE14";
"VSS<490>":   PN = "CE10"  !CDS_PN = "CE10";
"VSS<491>":   PN = "CD81"  !CDS_PN = "CD81";
"VSS<492>":   PN = "CD79"  !CDS_PN = "CD79";
"VSS<493>":   PN = "CD77"  !CDS_PN = "CD77";
"VSS<494>":   PN = "CD75"  !CDS_PN = "CD75";
"VSS<495>":   PN = "CD73"  !CDS_PN = "CD73";
"VSS<496>":   PN = "CD63"  !CDS_PN = "CD63";
"VSS<497>":   PN = "CD13"  !CDS_PN = "CD13";
"VSS<498>":   PN = "CD5"  !CDS_PN = "CD5";
"VSS<499>":   PN = "CC82"  !CDS_PN = "CC82";
"VSS<500>":   PN = "CC80"  !CDS_PN = "CC80";
"VSS<501>":   PN = "CC78"  !CDS_PN = "CC78";
"VSS<502>":   PN = "CC76"  !CDS_PN = "CC76";
"VSS<503>":   PN = "CC74"  !CDS_PN = "CC74";
"VSS<504>":   PN = "CC72"  !CDS_PN = "CC72";
"VSS<505>":   PN = "CC64"  !CDS_PN = "CC64";
"VSS<506>":   PN = "CC24"  !CDS_PN = "CC24";
"VSS<507>":   PN = "CC18"  !CDS_PN = "CC18";
"VSS<508>":   PN = "CC16"  !CDS_PN = "CC16";
"VSS<509>":   PN = "CC4"  !CDS_PN = "CC4";
"VSS<510>":   PN = "CB71"  !CDS_PN = "CB71";
"VSS<511>":   PN = "CB63"  !CDS_PN = "CB63";
"VSS<512>":   PN = "CB27"  !CDS_PN = "CB27";
"VSS<513>":   PN = "CB9"  !CDS_PN = "CB9";
"VSS<514>":   PN = "CB7"  !CDS_PN = "CB7";
"VSS<515>":   PN = "CA70"  !CDS_PN = "CA70";
"VSS<516>":   PN = "CA68"  !CDS_PN = "CA68";
"VSS<517>":   PN = "CA66"  !CDS_PN = "CA66";
"VSS<518>":   PN = "CA64"  !CDS_PN = "CA64";
"VSS<519>":   PN = "CA26"  !CDS_PN = "CA26";
"VSS<520>":   PN = "CA18"  !CDS_PN = "CA18";
"VSS<521>":   PN = "CA14"  !CDS_PN = "CA14";
"VSS<522>":   PN = "CA10"  !CDS_PN = "CA10";
"VSS<523>":   PN = "CA8"  !CDS_PN = "CA8";
"VSS<524>":   PN = "CA6"  !CDS_PN = "CA6";
"VSS<525>":   PN = "CA2"  !CDS_PN = "CA2";
"VSS<526>":   PN = "BY71"  !CDS_PN = "BY71";
"VSS<527>":   PN = "BY69"  !CDS_PN = "BY69";
"VSS<528>":   PN = "BY67"  !CDS_PN = "BY67";
"VSS<529>":   PN = "BY65"  !CDS_PN = "BY65";
"VSS<530>":   PN = "BY63"  !CDS_PN = "BY63";
"VSS<531>":   PN = "BY23"  !CDS_PN = "BY23";
"VSS<532>":   PN = "BY13"  !CDS_PN = "BY13";
"VSS<533>":   PN = "BY11"  !CDS_PN = "BY11";
"VSS<534>":   PN = "BW82"  !CDS_PN = "BW82";
"VSS<535>":   PN = "BW80"  !CDS_PN = "BW80";
"VSS<536>":   PN = "BW78"  !CDS_PN = "BW78";
"VSS<537>":   PN = "BW76"  !CDS_PN = "BW76";
"VSS<538>":   PN = "BW74"  !CDS_PN = "BW74";
"VSS<539>":   PN = "BW72"  !CDS_PN = "BW72";
"VSS<540>":   PN = "BW26"  !CDS_PN = "BW26";
"VSS<541>":   PN = "BW18"  !CDS_PN = "BW18";
"VSS<542>":   PN = "BW16"  !CDS_PN = "BW16";
"VSS<543>":   PN = "BW14"  !CDS_PN = "BW14";
"VSS<544>":   PN = "BW12"  !CDS_PN = "BW12";
"VSS<545>":   PN = "P55"  !CDS_PN = "P55";
"VSS<546>":   PN = "BW6"  !CDS_PN = "BW6";
"VSS<547>":   PN = "BV25"  !CDS_PN = "BV25";
"VSS<548>":   PN = "BV17"  !CDS_PN = "BV17";
"VSS<549>":   PN = "BU10"  !CDS_PN = "BU10";
"VSS<550>":   PN = "BV5"  !CDS_PN = "BV5";
"VSS<551>":   PN = "BU8"  !CDS_PN = "BU8";
"VSS<552>":   PN = "BT25"  !CDS_PN = "BT25";
"VSS<553>":   PN = "BT23"  !CDS_PN = "BT23";
"VSS<554>":   PN = "BT21"  !CDS_PN = "BT21";
"VSS<555>":   PN = "BT5"  !CDS_PN = "BT5";
"VSS<556>":   PN = "BT3"  !CDS_PN = "BT3";
"VSS<557>":   PN = "BR82"  !CDS_PN = "BR82";
"VSS<558>":   PN = "BR80"  !CDS_PN = "BR80";
"VSS<559>":   PN = "BR78"  !CDS_PN = "BR78";
"VSS<560>":   PN = "BR76"  !CDS_PN = "BR76";
"VSS<561>":   PN = "BR74"  !CDS_PN = "BR74";
"VSS<562>":   PN = "BR72"  !CDS_PN = "BR72";
"VSS<563>":   PN = "BR70"  !CDS_PN = "BR70";
"VSS<564>":   PN = "BR68"  !CDS_PN = "BR68";
"VSS<565>":   PN = "BR66"  !CDS_PN = "BR66";
"VSS<566>":   PN = "BR64"  !CDS_PN = "BR64";
"VSS<567>":   PN = "P57"  !CDS_PN = "P57";
"VSS<568>":   PN = "BR16"  !CDS_PN = "BR16";
"VSS<569>":   PN = "BR10"  !CDS_PN = "BR10";
"VSS<570>":   PN = "BR6"  !CDS_PN = "BR6";
"VSS<571>":   PN = "BP27"  !CDS_PN = "BP27";
"VSS<572>":   PN = "BP3"  !CDS_PN = "BP3";
"VSS<573>":   PN = "BN26"  !CDS_PN = "BN26";
"VSS<574>":   PN = "BN20"  !CDS_PN = "BN20";
"VSS<575>":   PN = "BN10"  !CDS_PN = "BN10";
"VSS<576>":   PN = "BN6"  !CDS_PN = "BN6";
"VSS<577>":   PN = "BM25"  !CDS_PN = "BM25";
"VSS<578>":   PN = "P59"  !CDS_PN = "P59";
"VSS<579>":   PN = "BM15"  !CDS_PN = "BM15";
"VSS<580>":   PN = "BM13"  !CDS_PN = "BM13";
"VSS<581>":   PN = "BM9"  !CDS_PN = "BM9";
"VSS<582>":   PN = "BL82"  !CDS_PN = "BL82";
"VSS<583>":   PN = "BL80"  !CDS_PN = "BL80";
"VSS<584>":   PN = "BL78"  !CDS_PN = "BL78";
"VSS<585>":   PN = "BL76"  !CDS_PN = "BL76";
"VSS<586>":   PN = "BL74"  !CDS_PN = "BL74";
"VSS<587>":   PN = "BL72"  !CDS_PN = "BL72";
"VSS<588>":   PN = "BL70"  !CDS_PN = "BL70";
"VSS<589>":   PN = "BL68"  !CDS_PN = "BL68";
"VSS<590>":   PN = "BL66"  !CDS_PN = "BL66";
"VSS<591>":   PN = "BL64"  !CDS_PN = "BL64";
"VSS<592>":   PN = "BL24"  !CDS_PN = "BL24";
"VSS<593>":   PN = "BL22"  !CDS_PN = "BL22";
"VSS<594>":   PN = "P61"  !CDS_PN = "P61";
"VSS<595>":   PN = "BL12"  !CDS_PN = "BL12";
"VSS<596>":   PN = "BL10"  !CDS_PN = "BL10";
"VSS<597>":   PN = "BL6"  !CDS_PN = "BL6";
"VSS<598>":   PN = "BK19"  !CDS_PN = "BK19";
"VSS<599>":   PN = "BK11"  !CDS_PN = "BK11";
"VSS<600>":   PN = "BK7"  !CDS_PN = "BK7";
"VSS<601>":   PN = "BK3"  !CDS_PN = "BK3";
"VSS<602>":   PN = "BJ6"  !CDS_PN = "BJ6";
"VSS<603>":   PN = "BJ4"  !CDS_PN = "BJ4";
"VSS<604>":   PN = "BH21"  !CDS_PN = "BH21";
"VSS<605>":   PN = "BH15"  !CDS_PN = "BH15";
"VSS<606>":   PN = "BH11"  !CDS_PN = "BH11";
"VSS<607>":   PN = "BH9"  !CDS_PN = "BH9";
"VSS<608>":   PN = "BH7"  !CDS_PN = "BH7";
"VSS<609>":   PN = "BG82"  !CDS_PN = "BG82";
"VSS<610>":   PN = "BG80"  !CDS_PN = "BG80";
"VSS<611>":   PN = "BG78"  !CDS_PN = "BG78";
"VSS<612>":   PN = "BG76"  !CDS_PN = "BG76";
"VSS<613>":   PN = "BG74"  !CDS_PN = "BG74";
BODY = "SKX_EXT_B","I18": #LOCATION = "U2D1" !CDS_LOCATION = "U2D1" #SEC = "28" !CDS_SEC = "28";
"VSS<294>":   PN = "DA46"  !CDS_PN = "DA46";
"VSS<295>":   PN = "DA44"  !CDS_PN = "DA44";
"VSS<296>":   PN = "DA38"  !CDS_PN = "DA38";
"VSS<297>":   PN = "DA36"  !CDS_PN = "DA36";
"VSS<298>":   PN = "DA34"  !CDS_PN = "DA34";
"VSS<299>":   PN = "DA32"  !CDS_PN = "DA32";
"VSS<300>":   PN = "DA30"  !CDS_PN = "DA30";
"VSS<301>":   PN = "DA28"  !CDS_PN = "DA28";
"VSS<302>":   PN = "DA26"  !CDS_PN = "DA26";
"VSS<303>":   PN = "DA18"  !CDS_PN = "DA18";
"VSS<304>":   PN = "H53"  !CDS_PN = "H53";
"VSS<305>":   PN = "DA6"  !CDS_PN = "DA6";
"VSS<306>":   PN = "CY85"  !CDS_PN = "CY85";
"VSS<307>":   PN = "CY83"  !CDS_PN = "CY83";
"VSS<308>":   PN = "CY77"  !CDS_PN = "CY77";
"VSS<309>":   PN = "CY75"  !CDS_PN = "CY75";
"VSS<310>":   PN = "CY69"  !CDS_PN = "CY69";
"VSS<311>":   PN = "CY65"  !CDS_PN = "CY65";
"VSS<312>":   PN = "CY61"  !CDS_PN = "CY61";
"VSS<313>":   PN = "CY59"  !CDS_PN = "CY59";
"VSS<314>":   PN = "CY51"  !CDS_PN = "CY51";
"VSS<315>":   PN = "CY45"  !CDS_PN = "CY45";
"VSS<316>":   PN = "CY41"  !CDS_PN = "CY41";
"VSS<317>":   PN = "CY21"  !CDS_PN = "CY21";
"VSS<318>":   PN = "CY15"  !CDS_PN = "CY15";
"VSS<319>":   PN = "CY13"  !CDS_PN = "CY13";
"VSS<320>":   PN = "CY9"  !CDS_PN = "CY9";
"VSS<321>":   PN = "CY1"  !CDS_PN = "CY1";
"VSS<322>":   PN = "CW82"  !CDS_PN = "CW82";
"VSS<323>":   PN = "CW78"  !CDS_PN = "CW78";
"VSS<324>":   PN = "CW74"  !CDS_PN = "CW74";
"VSS<325>":   PN = "CW68"  !CDS_PN = "CW68";
"VSS<326>":   PN = "CW66"  !CDS_PN = "CW66";
"VSS<327>":   PN = "CW64"  !CDS_PN = "CW64";
"VSS<328>":   PN = "CW54"  !CDS_PN = "CW54";
"VSS<329>":   PN = "CW52"  !CDS_PN = "CW52";
"VSS<330>":   PN = "CW42"  !CDS_PN = "CW42";
"VSS<331>":   PN = "CW40"  !CDS_PN = "CW40";
"VSS<332>":   PN = "CW38"  !CDS_PN = "CW38";
"VSS<333>":   PN = "CW32"  !CDS_PN = "CW32";
"VSS<334>":   PN = "CW26"  !CDS_PN = "CW26";
"VSS<335>":   PN = "CW12"  !CDS_PN = "CW12";
"VSS<336>":   PN = "CV83"  !CDS_PN = "CV83";
"VSS<337>":   PN = "CV81"  !CDS_PN = "CV81";
"VSS<338>":   PN = "CV79"  !CDS_PN = "CV79";
"VSS<339>":   PN = "CV73"  !CDS_PN = "CV73";
"VSS<340>":   PN = "CV67"  !CDS_PN = "CV67";
"VSS<341>":   PN = "CV63"  !CDS_PN = "CV63";
"VSS<342>":   PN = "CV55"  !CDS_PN = "CV55";
"VSS<343>":   PN = "CV53"  !CDS_PN = "CV53";
"VSS<344>":   PN = "CV41"  !CDS_PN = "CV41";
"VSS<345>":   PN = "CV39"  !CDS_PN = "CV39";
"VSS<346>":   PN = "CV37"  !CDS_PN = "CV37";
"VSS<347>":   PN = "CV33"  !CDS_PN = "CV33";
"VSS<348>":   PN = "CV31"  !CDS_PN = "CV31";
"VSS<349>":   PN = "CV27"  !CDS_PN = "CV27";
"VSS<350>":   PN = "CV25"  !CDS_PN = "CV25";
"VSS<351>":   PN = "CV17"  !CDS_PN = "CV17";
"VSS<352>":   PN = "H55"  !CDS_PN = "H55";
"VSS<353>":   PN = "CV1"  !CDS_PN = "CV1";
"VSS<354>":   PN = "CU86"  !CDS_PN = "CU86";
"VSS<355>":   PN = "CU82"  !CDS_PN = "CU82";
"VSS<356>":   PN = "CU80"  !CDS_PN = "CU80";
"VSS<357>":   PN = "CU78"  !CDS_PN = "CU78";
"VSS<358>":   PN = "CU76"  !CDS_PN = "CU76";
"VSS<359>":   PN = "CU68"  !CDS_PN = "CU68";
"VSS<360>":   PN = "CU62"  !CDS_PN = "CU62";
"VSS<361>":   PN = "CU56"  !CDS_PN = "CU56";
"VSS<362>":   PN = "CU36"  !CDS_PN = "CU36";
"VSS<363>":   PN = "CU34"  !CDS_PN = "CU34";
"VSS<364>":   PN = "CU30"  !CDS_PN = "CU30";
"VSS<365>":   PN = "CU28"  !CDS_PN = "CU28";
"VSS<366>":   PN = "CU22"  !CDS_PN = "CU22";
"VSS<367>":   PN = "CU4"  !CDS_PN = "CU4";
"VSS<368>":   PN = "CT85"  !CDS_PN = "CT85";
"VSS<369>":   PN = "CT83"  !CDS_PN = "CT83";
"VSS<370>":   PN = "CT79"  !CDS_PN = "CT79";
"VSS<371>":   PN = "CT73"  !CDS_PN = "CT73";
"VSS<372>":   PN = "CT57"  !CDS_PN = "CT57";
"VSS<373>":   PN = "CT35"  !CDS_PN = "CT35";
"VSS<374>":   PN = "CT33"  !CDS_PN = "CT33";
"VSS<375>":   PN = "CT29"  !CDS_PN = "CT29";
"VSS<376>":   PN = "CT27"  !CDS_PN = "CT27";
"VSS<377>":   PN = "CT19"  !CDS_PN = "CT19";
"VSS<378>":   PN = "CT13"  !CDS_PN = "CT13";
"VSS<379>":   PN = "H57"  !CDS_PN = "H57";
"VSS<380>":   PN = "CR86"  !CDS_PN = "CR86";
"VSS<381>":   PN = "CR78"  !CDS_PN = "CR78";
"VSS<382>":   PN = "CR68"  !CDS_PN = "CR68";
"VSS<383>":   PN = "CR66"  !CDS_PN = "CR66";
"VSS<384>":   PN = "CR64"  !CDS_PN = "CR64";
"VSS<385>":   PN = "CR62"  !CDS_PN = "CR62";
"VSS<386>":   PN = "CR58"  !CDS_PN = "CR58";
"VSS<387>":   PN = "CR32"  !CDS_PN = "CR32";
"VSS<388>":   PN = "CR24"  !CDS_PN = "CR24";
"VSS<389>":   PN = "CR22"  !CDS_PN = "CR22";
"VSS<390>":   PN = "CR10"  !CDS_PN = "CR10";
"VSS<391>":   PN = "CR6"  !CDS_PN = "CR6";
"VSS<392>":   PN = "CP83"  !CDS_PN = "CP83";
"VSS<393>":   PN = "CP81"  !CDS_PN = "CP81";
"VSS<394>":   PN = "CP75"  !CDS_PN = "CP75";
"VSS<395>":   PN = "CP73"  !CDS_PN = "CP73";
"VSS<396>":   PN = "CP69"  !CDS_PN = "CP69";
"VSS<397>":   PN = "CP59"  !CDS_PN = "CP59";
"VSS<398>":   PN = "CP25"  !CDS_PN = "CP25";
"VSS<399>":   PN = "H59"  !CDS_PN = "H59";
"VSS<400>":   PN = "CP1"  !CDS_PN = "CP1";
"VSS<401>":   PN = "CN78"  !CDS_PN = "CN78";
"VSS<402>":   PN = "CN68"  !CDS_PN = "CN68";
"VSS<403>":   PN = "CN62"  !CDS_PN = "CN62";
"VSS<404>":   PN = "CN60"  !CDS_PN = "CN60";
"VSS<405>":   PN = "CN32"  !CDS_PN = "CN32";
"VSS<406>":   PN = "CN26"  !CDS_PN = "CN26";
"VSS<407>":   PN = "H61"  !CDS_PN = "H61";
"VSS<408>":   PN = "CN12"  !CDS_PN = "CN12";
"VSS<409>":   PN = "CN2"  !CDS_PN = "CN2";
"VSS<410>":   PN = "CM85"  !CDS_PN = "CM85";
"VSS<411>":   PN = "CM83"  !CDS_PN = "CM83";
"VSS<412>":   PN = "CM77"  !CDS_PN = "CM77";
"VSS<413>":   PN = "CM73"  !CDS_PN = "CM73";
"VSS<414>":   PN = "CM67"  !CDS_PN = "CM67";
"VSS<415>":   PN = "CM63"  !CDS_PN = "CM63";
"VSS<416>":   PN = "CM61"  !CDS_PN = "CM61";
"VSS<417>":   PN = "CM31"  !CDS_PN = "CM31";
"VSS<418>":   PN = "CM5"  !CDS_PN = "CM5";
"VSS<419>":   PN = "CM29"  !CDS_PN = "CM29";
"VSS<420>":   PN = "CM19"  !CDS_PN = "CM19";
"VSS<421>":   PN = "CL80"  !CDS_PN = "CL80";
"VSS<422>":   PN = "CL78"  !CDS_PN = "CL78";
"VSS<423>":   PN = "CL76"  !CDS_PN = "CL76";
"VSS<424>":   PN = "CL74"  !CDS_PN = "CL74";
"VSS<425>":   PN = "CL66"  !CDS_PN = "CL66";
"VSS<426>":   PN = "CL64"  !CDS_PN = "CL64";
"VSS<427>":   PN = "CL62"  !CDS_PN = "CL62";
"VSS<428>":   PN = "H63"  !CDS_PN = "H63";
"VSS<429>":   PN = "P45"  !CDS_PN = "P45";
"VSS<430>":   PN = "CL18"  !CDS_PN = "CL18";
"VSS<431>":   PN = "CL14"  !CDS_PN = "CL14";
"VSS<432>":   PN = "CL8"  !CDS_PN = "CL8";
"VSS<433>":   PN = "CK85"  !CDS_PN = "CK85";
"VSS<434>":   PN = "CK83"  !CDS_PN = "CK83";
"VSS<435>":   PN = "CK75"  !CDS_PN = "CK75";
"VSS<436>":   PN = "CK73"  !CDS_PN = "CK73";
"VSS<437>":   PN = "CK71"  !CDS_PN = "CK71";
"VSS<438>":   PN = "CK69"  !CDS_PN = "CK69";
"VSS<439>":   PN = "CK67"  !CDS_PN = "CK67";
"VSS<440>":   PN = "CK65"  !CDS_PN = "CK65";
"VSS<441>":   PN = "CK63"  !CDS_PN = "CK63";
"VSS<442>":   PN = "CK27"  !CDS_PN = "CK27";
"VSS<443>":   PN = "CK21"  !CDS_PN = "CK21";
"VSS<444>":   PN = "CK15"  !CDS_PN = "CK15";
"VSS<445>":   PN = "CK11"  !CDS_PN = "CK11";
"VSS<446>":   PN = "CJ86"  !CDS_PN = "CJ86";
"VSS<447>":   PN = "CJ84"  !CDS_PN = "CJ84";
"VSS<448>":   PN = "CJ82"  !CDS_PN = "CJ82";
"VSS<449>":   PN = "CJ78"  !CDS_PN = "CJ78";
"VSS<450>":   PN = "CJ76"  !CDS_PN = "CJ76";
"VSS<451>":   PN = "CJ74"  !CDS_PN = "CJ74";
"VSS<452>":   PN = "CJ62"  !CDS_PN = "CJ62";
"VSS<453>":   PN = "P47"  !CDS_PN = "P47";
BODY = "SKX_EXT_B","I19": #LOCATION = "U2D1" !CDS_LOCATION = "U2D1" #SEC = "29" !CDS_SEC = "29";
"VSS<134>":   PN = "DN72"  !CDS_PN = "DN72";
"VSS<135>":   PN = "DN68"  !CDS_PN = "DN68";
"VSS<136>":   PN = "DN38"  !CDS_PN = "DN38";
"VSS<137>":   PN = "DN32"  !CDS_PN = "DN32";
"VSS<138>":   PN = "DN26"  !CDS_PN = "DN26";
"VSS<139>":   PN = "DN22"  !CDS_PN = "DN22";
"VSS<140>":   PN = "DN12"  !CDS_PN = "DN12";
"VSS<141>":   PN = "BH17"  !CDS_PN = "BH17";
"VSS<142>":   PN = "DN2"  !CDS_PN = "DN2";
"VSS<143>":   PN = "DM83"  !CDS_PN = "DM83";
"VSS<144>":   PN = "DM77"  !CDS_PN = "DM77";
"VSS<145>":   PN = "DM73"  !CDS_PN = "DM73";
"VSS<146>":   PN = "DM65"  !CDS_PN = "DM65";
"VSS<147>":   PN = "DM39"  !CDS_PN = "DM39";
"VSS<148>":   PN = "DM37"  !CDS_PN = "DM37";
"VSS<149>":   PN = "DM33"  !CDS_PN = "DM33";
"VSS<150>":   PN = "DM31"  !CDS_PN = "DM31";
"VSS<151>":   PN = "DM27"  !CDS_PN = "DM27";
"VSS<152>":   PN = "DM25"  !CDS_PN = "DM25";
"VSS<153>":   PN = "H45"  !CDS_PN = "H45";
"VSS<154>":   PN = "DM15"  !CDS_PN = "DM15";
"VSS<155>":   PN = "DL80"  !CDS_PN = "DL80";
"VSS<156>":   PN = "DL78"  !CDS_PN = "DL78";
"VSS<157>":   PN = "DL76"  !CDS_PN = "DL76";
"VSS<158>":   PN = "DL74"  !CDS_PN = "DL74";
"VSS<159>":   PN = "DL70"  !CDS_PN = "DL70";
"VSS<160>":   PN = "DL68"  !CDS_PN = "DL68";
"VSS<161>":   PN = "DL40"  !CDS_PN = "DL40";
"VSS<162>":   PN = "DL36"  !CDS_PN = "DL36";
"VSS<163>":   PN = "DL34"  !CDS_PN = "DL34";
"VSS<164>":   PN = "DL30"  !CDS_PN = "DL30";
"VSS<165>":   PN = "DL28"  !CDS_PN = "DL28";
"VSS<166>":   PN = "DL24"  !CDS_PN = "DL24";
"VSS<167>":   PN = "DL22"  !CDS_PN = "DL22";
"VSS<168>":   PN = "DL4"  !CDS_PN = "DL4";
"VSS<169>":   PN = "DL18"  !CDS_PN = "DL18";
"VSS<170>":   PN = "DL16"  !CDS_PN = "DL16";
"VSS<171>":   PN = "DK85"  !CDS_PN = "DK85";
"VSS<172>":   PN = "DK83"  !CDS_PN = "DK83";
"VSS<173>":   PN = "DK77"  !CDS_PN = "DK77";
"VSS<174>":   PN = "DK75"  !CDS_PN = "DK75";
"VSS<175>":   PN = "DK73"  !CDS_PN = "DK73";
"VSS<176>":   PN = "DK41"  !CDS_PN = "DK41";
"VSS<177>":   PN = "DK39"  !CDS_PN = "DK39";
"VSS<178>":   PN = "DK35"  !CDS_PN = "DK35";
"VSS<179>":   PN = "DK29"  !CDS_PN = "DK29";
"VSS<180>":   PN = "DK23"  !CDS_PN = "DK23";
"VSS<181>":   PN = "DK7"  !CDS_PN = "DK7";
"VSS<182>":   PN = "DJ84"  !CDS_PN = "DJ84";
"VSS<183>":   PN = "DJ82"  !CDS_PN = "DJ82";
"VSS<184>":   PN = "DJ78"  !CDS_PN = "DJ78";
"VSS<185>":   PN = "DJ74"  !CDS_PN = "DJ74";
"VSS<186>":   PN = "DJ68"  !CDS_PN = "DJ68";
"VSS<187>":   PN = "DJ42"  !CDS_PN = "DJ42";
"VSS<188>":   PN = "DJ38"  !CDS_PN = "DJ38";
"VSS<189>":   PN = "DJ22"  !CDS_PN = "DJ22";
"VSS<190>":   PN = "H47"  !CDS_PN = "H47";
"VSS<191>":   PN = "DJ10"  !CDS_PN = "DJ10";
"VSS<192>":   PN = "DJ2"  !CDS_PN = "DJ2";
"VSS<193>":   PN = "DH83"  !CDS_PN = "DH83";
"VSS<194>":   PN = "DH81"  !CDS_PN = "DH81";
"VSS<195>":   PN = "DH79"  !CDS_PN = "DH79";
"VSS<196>":   PN = "DH73"  !CDS_PN = "DH73";
"VSS<197>":   PN = "DH71"  !CDS_PN = "DH71";
"VSS<198>":   PN = "DH67"  !CDS_PN = "DH67";
"VSS<199>":   PN = "DH41"  !CDS_PN = "DH41";
"VSS<200>":   PN = "DH37"  !CDS_PN = "DH37";
"VSS<201>":   PN = "DH35"  !CDS_PN = "DH35";
"VSS<202>":   PN = "DH33"  !CDS_PN = "DH33";
"VSS<203>":   PN = "DH31"  !CDS_PN = "DH31";
"VSS<204>":   PN = "DH29"  !CDS_PN = "DH29";
"VSS<205>":   PN = "DH27"  !CDS_PN = "DH27";
"VSS<206>":   PN = "DH25"  !CDS_PN = "DH25";
"VSS<207>":   PN = "DH23"  !CDS_PN = "DH23";
"VSS<208>":   PN = "DH15"  !CDS_PN = "DH15";
"VSS<209>":   PN = "DH13"  !CDS_PN = "DH13";
"VSS<210>":   PN = "DG82"  !CDS_PN = "DG82";
"VSS<211>":   PN = "DG80"  !CDS_PN = "DG80";
"VSS<212>":   PN = "DG78"  !CDS_PN = "DG78";
"VSS<213>":   PN = "DG76"  !CDS_PN = "DG76";
"VSS<214>":   PN = "DG68"  !CDS_PN = "DG68";
"VSS<215>":   PN = "DG66"  !CDS_PN = "DG66";
"VSS<216>":   PN = "DG24"  !CDS_PN = "DG24";
"VSS<217>":   PN = "DG16"  !CDS_PN = "DG16";
"VSS<218>":   PN = "DG14"  !CDS_PN = "DG14";
"VSS<219>":   PN = "H49"  !CDS_PN = "H49";
"VSS<220>":   PN = "DG2"  !CDS_PN = "DG2";
"VSS<221>":   PN = "DF85"  !CDS_PN = "DF85";
"VSS<222>":   PN = "DF83"  !CDS_PN = "DF83";
"VSS<223>":   PN = "DF79"  !CDS_PN = "DF79";
"VSS<224>":   PN = "DF73"  !CDS_PN = "DF73";
"VSS<225>":   PN = "DF69"  !CDS_PN = "DF69";
"VSS<226>":   PN = "DF65"  !CDS_PN = "DF65";
"VSS<227>":   PN = "DF41"  !CDS_PN = "DF41";
"VSS<228>":   PN = "DF39"  !CDS_PN = "DF39";
"VSS<229>":   PN = "DF37"  !CDS_PN = "DF37";
"VSS<230>":   PN = "DF35"  !CDS_PN = "DF35";
"VSS<231>":   PN = "DF29"  !CDS_PN = "DF29";
"VSS<232>":   PN = "DF19"  !CDS_PN = "DF19";
"VSS<233>":   PN = "H51"  !CDS_PN = "H51";
"VSS<234>":   PN = "DF7"  !CDS_PN = "DF7";
"VSS<235>":   PN = "DF5"  !CDS_PN = "DF5";
"VSS<236>":   PN = "DE78"  !CDS_PN = "DE78";
"VSS<237>":   PN = "DE72"  !CDS_PN = "DE72";
"VSS<238>":   PN = "DE70"  !CDS_PN = "DE70";
"VSS<239>":   PN = "DE64"  !CDS_PN = "DE64";
"VSS<240>":   PN = "DE36"  !CDS_PN = "DE36";
"VSS<241>":   PN = "DE34"  !CDS_PN = "DE34";
"VSS<242>":   PN = "DE30"  !CDS_PN = "DE30";
"VSS<243>":   PN = "DE28"  !CDS_PN = "DE28";
"VSS<244>":   PN = "DE24"  !CDS_PN = "DE24";
"VSS<245>":   PN = "DE20"  !CDS_PN = "DE20";
"VSS<246>":   PN = "DE18"  !CDS_PN = "DE18";
"VSS<247>":   PN = "DE8"  !CDS_PN = "DE8";
"VSS<248>":   PN = "DE6"  !CDS_PN = "DE6";
"VSS<249>":   PN = "DD83"  !CDS_PN = "DD83";
"VSS<250>":   PN = "DD81"  !CDS_PN = "DD81";
"VSS<251>":   PN = "DD75"  !CDS_PN = "DD75";
"VSS<252>":   PN = "DD73"  !CDS_PN = "DD73";
"VSS<253>":   PN = "DD71"  !CDS_PN = "DD71";
"VSS<254>":   PN = "DD37"  !CDS_PN = "DD37";
"VSS<255>":   PN = "DD33"  !CDS_PN = "DD33";
"VSS<256>":   PN = "DD31"  !CDS_PN = "DD31";
"VSS<257>":   PN = "DD27"  !CDS_PN = "DD27";
"VSS<258>":   PN = "DD23"  !CDS_PN = "DD23";
"VSS<259>":   PN = "DD11"  !CDS_PN = "DD11";
"VSS<260>":   PN = "DC86"  !CDS_PN = "DC86";
"VSS<261>":   PN = "DC84"  !CDS_PN = "DC84";
"VSS<262>":   PN = "DC78"  !CDS_PN = "DC78";
"VSS<263>":   PN = "DC70"  !CDS_PN = "DC70";
"VSS<264>":   PN = "DC68"  !CDS_PN = "DC68";
"VSS<265>":   PN = "DC66"  !CDS_PN = "DC66";
"VSS<266>":   PN = "DC64"  !CDS_PN = "DC64";
"VSS<267>":   PN = "DC42"  !CDS_PN = "DC42";
"VSS<268>":   PN = "DC38"  !CDS_PN = "DC38";
"VSS<269>":   PN = "DC32"  !CDS_PN = "DC32";
"VSS<270>":   PN = "DC26"  !CDS_PN = "DC26";
"VSS<271>":   PN = "DC24"  !CDS_PN = "DC24";
"VSS<272>":   PN = "DC14"  !CDS_PN = "DC14";
"VSS<273>":   PN = "DB85"  !CDS_PN = "DB85";
"VSS<274>":   PN = "DB83"  !CDS_PN = "DB83";
"VSS<275>":   PN = "DB77"  !CDS_PN = "DB77";
"VSS<276>":   PN = "DB73"  !CDS_PN = "DB73";
"VSS<277>":   PN = "DB49"  !CDS_PN = "DB49";
"VSS<278>":   PN = "DB47"  !CDS_PN = "DB47";
"VSS<279>":   PN = "DB41"  !CDS_PN = "DB41";
"VSS<280>":   PN = "DB39"  !CDS_PN = "DB39";
"VSS<281>":   PN = "DB25"  !CDS_PN = "DB25";
"VSS<282>":   PN = "DB23"  !CDS_PN = "DB23";
"VSS<283>":   PN = "DB17"  !CDS_PN = "DB17";
"VSS<284>":   PN = "DB13"  !CDS_PN = "DB13";
"VSS<285>":   PN = "DB3"  !CDS_PN = "DB3";
"VSS<286>":   PN = "DA80"  !CDS_PN = "DA80";
"VSS<287>":   PN = "DA78"  !CDS_PN = "DA78";
"VSS<288>":   PN = "DA76"  !CDS_PN = "DA76";
"VSS<289>":   PN = "DA74"  !CDS_PN = "DA74";
"VSS<290>":   PN = "DA70"  !CDS_PN = "DA70";
"VSS<291>":   PN = "DA64"  !CDS_PN = "DA64";
"VSS<292>":   PN = "DA50"  !CDS_PN = "DA50";
"VSS<293>":   PN = "DA48"  !CDS_PN = "DA48";
BODY = "SKX_EXT_B","I20": #LOCATION = "U2D1" !CDS_LOCATION = "U2D1" #SEC = "30" !CDS_SEC = "30";
"VSS<0>":   PN = "EF79"  !CDS_PN = "EF79";
"VSS<1>":   PN = "EF75"  !CDS_PN = "EF75";
"VSS<2>":   PN = "EF71"  !CDS_PN = "EF71";
"VSS<3>":   PN = "EE78"  !CDS_PN = "EE78";
"VSS<4>":   PN = "EE76"  !CDS_PN = "EE76";
"VSS<5>":   PN = "EE70"  !CDS_PN = "EE70";
"VSS<6>":   PN = "EE36"  !CDS_PN = "EE36";
"VSS<7>":   PN = "EE34"  !CDS_PN = "EE34";
"VSS<8>":   PN = "EE30"  !CDS_PN = "EE30";
"VSS<9>":   PN = "EE28"  !CDS_PN = "EE28";
"VSS<10>":   PN = "EE24"  !CDS_PN = "EE24";
"VSS<11>":   PN = "ED77"  !CDS_PN = "ED77";
"VSS<12>":   PN = "ED35"  !CDS_PN = "ED35";
"VSS<13>":   PN = "ED29"  !CDS_PN = "ED29";
"VSS<14>":   PN = "ED23"  !CDS_PN = "ED23";
"VSS<15>":   PN = "ED15"  !CDS_PN = "ED15";
"VSS<16>":   PN = "ED11"  !CDS_PN = "ED11";
"VSS<17>":   PN = "EC76"  !CDS_PN = "EC76";
"VSS<18>":   PN = "EC74"  !CDS_PN = "EC74";
"VSS<19>":   PN = "EC72"  !CDS_PN = "EC72";
"VSS<20>":   PN = "EC70"  !CDS_PN = "EC70";
"VSS<21>":   PN = "EC10"  !CDS_PN = "EC10";
"VSS<22>":   PN = "EB69"  !CDS_PN = "EB69";
"VSS<23>":   PN = "EB65"  !CDS_PN = "EB65";
"VSS<24>":   PN = "EB41"  !CDS_PN = "EB41";
"VSS<25>":   PN = "EB39"  !CDS_PN = "EB39";
"VSS<26>":   PN = "EB37"  !CDS_PN = "EB37";
"VSS<27>":   PN = "EB35"  !CDS_PN = "EB35";
"VSS<28>":   PN = "EB33"  !CDS_PN = "EB33";
"VSS<29>":   PN = "EB31"  !CDS_PN = "EB31";
"VSS<30>":   PN = "EB29"  !CDS_PN = "EB29";
"VSS<31>":   PN = "EB27"  !CDS_PN = "EB27";
"VSS<32>":   PN = "EB25"  !CDS_PN = "EB25";
"VSS<33>":   PN = "EB23"  !CDS_PN = "EB23";
"VSS<34>":   PN = "BR18"  !CDS_PN = "BR18";
"VSS<35>":   PN = "EB13"  !CDS_PN = "EB13";
"VSS<36>":   PN = "EA82"  !CDS_PN = "EA82";
"VSS<37>":   PN = "EA80"  !CDS_PN = "EA80";
"VSS<38>":   PN = "EA78"  !CDS_PN = "EA78";
"VSS<39>":   PN = "EA76"  !CDS_PN = "EA76";
"VSS<40>":   PN = "EA70"  !CDS_PN = "EA70";
"VSS<41>":   PN = "EA64"  !CDS_PN = "EA64";
"VSS<42>":   PN = "EA42"  !CDS_PN = "EA42";
"VSS<43>":   PN = "EA22"  !CDS_PN = "EA22";
"VSS<44>":   PN = "EA20"  !CDS_PN = "EA20";
"VSS<45>":   PN = "EA16"  !CDS_PN = "EA16";
"VSS<46>":   PN = "J16"  !CDS_PN = "J16";
"VSS<47>":   PN = "EA6"  !CDS_PN = "EA6";
"VSS<48>":   PN = "DY75"  !CDS_PN = "DY75";
"VSS<49>":   PN = "DY71"  !CDS_PN = "DY71";
"VSS<50>":   PN = "DY41"  !CDS_PN = "DY41";
"VSS<51>":   PN = "DY35"  !CDS_PN = "DY35";
"VSS<52>":   PN = "DY29"  !CDS_PN = "DY29";
"VSS<53>":   PN = "DY23"  !CDS_PN = "DY23";
"VSS<54>":   PN = "DY19"  !CDS_PN = "DY19";
"VSS<55>":   PN = "DY5"  !CDS_PN = "DY5";
"VSS<56>":   PN = "DW84"  !CDS_PN = "DW84";
"VSS<57>":   PN = "DW82"  !CDS_PN = "DW82";
"VSS<58>":   PN = "DW8"  !CDS_PN = "DW8";
"VSS<59>":   PN = "DW76"  !CDS_PN = "DW76";
"VSS<60>":   PN = "DW74"  !CDS_PN = "DW74";
"VSS<61>":   PN = "DW72"  !CDS_PN = "DW72";
"VSS<62>":   PN = "DW70"  !CDS_PN = "DW70";
"VSS<63>":   PN = "DW68"  !CDS_PN = "DW68";
"VSS<64>":   PN = "DW66"  !CDS_PN = "DW66";
"VSS<65>":   PN = "DW64"  !CDS_PN = "DW64";
"VSS<66>":   PN = "DW40"  !CDS_PN = "DW40";
"VSS<67>":   PN = "DW36"  !CDS_PN = "DW36";
"VSS<68>":   PN = "DW34"  !CDS_PN = "DW34";
"VSS<69>":   PN = "DW30"  !CDS_PN = "DW30";
"VSS<70>":   PN = "DW28"  !CDS_PN = "DW28";
"VSS<71>":   PN = "DW24"  !CDS_PN = "DW24";
"VSS<72>":   PN = "DW20"  !CDS_PN = "DW20";
"VSS<73>":   PN = "DW12"  !CDS_PN = "DW12";
"VSS<74>":   PN = "DV81"  !CDS_PN = "DV81";
"VSS<75>":   PN = "DV77"  !CDS_PN = "DV77";
"VSS<76>":   PN = "DV73"  !CDS_PN = "DV73";
"VSS<77>":   PN = "DV39"  !CDS_PN = "DV39";
"VSS<78>":   PN = "DV37"  !CDS_PN = "DV37";
"VSS<79>":   PN = "DV33"  !CDS_PN = "DV33";
"VSS<80>":   PN = "DV31"  !CDS_PN = "DV31";
"VSS<81>":   PN = "DV27"  !CDS_PN = "DV27";
"VSS<82>":   PN = "DV25"  !CDS_PN = "DV25";
"VSS<83>":   PN = "DV21"  !CDS_PN = "DV21";
"VSS<84>":   PN = "DU84"  !CDS_PN = "DU84";
"VSS<85>":   PN = "DU82"  !CDS_PN = "DU82";
"VSS<86>":   PN = "DU80"  !CDS_PN = "DU80";
"VSS<87>":   PN = "DU78"  !CDS_PN = "DU78";
"VSS<88>":   PN = "DU72"  !CDS_PN = "DU72";
"VSS<89>":   PN = "DU70"  !CDS_PN = "DU70";
"VSS<90>":   PN = "DU38"  !CDS_PN = "DU38";
"VSS<91>":   PN = "DU32"  !CDS_PN = "DU32";
"VSS<92>":   PN = "DU26"  !CDS_PN = "DU26";
"VSS<93>":   PN = "DU22"  !CDS_PN = "DU22";
"VSS<94>":   PN = "CN14"  !CDS_PN = "CN14";
"VSS<95>":   PN = "DU14"  !CDS_PN = "DU14";
"VSS<96>":   PN = "DU10"  !CDS_PN = "DU10";
"VSS<97>":   PN = "DT85"  !CDS_PN = "DT85";
"VSS<98>":   PN = "DT83"  !CDS_PN = "DT83";
"VSS<99>":   PN = "DT79"  !CDS_PN = "DT79";
"VSS<100>":   PN = "DT69"  !CDS_PN = "DT69";
"VSS<101>":   PN = "DT65"  !CDS_PN = "DT65";
"VSS<102>":   PN = "DH21"  !CDS_PN = "DH21";
"VSS<103>":   PN = "DT17"  !CDS_PN = "DT17";
"VSS<104>":   PN = "DT3"  !CDS_PN = "DT3";
"VSS<105>":   PN = "DR78"  !CDS_PN = "DR78";
"VSS<106>":   PN = "DR76"  !CDS_PN = "DR76";
"VSS<107>":   PN = "DR74"  !CDS_PN = "DR74";
"VSS<108>":   PN = "DR72"  !CDS_PN = "DR72";
"VSS<109>":   PN = "DR70"  !CDS_PN = "DR70";
"VSS<110>":   PN = "DR68"  !CDS_PN = "DR68";
"VSS<111>":   PN = "DR66"  !CDS_PN = "DR66";
"VSS<112>":   PN = "DR42"  !CDS_PN = "DR42";
"VSS<113>":   PN = "DR40"  !CDS_PN = "DR40";
"VSS<114>":   PN = "DR38"  !CDS_PN = "DR38";
"VSS<115>":   PN = "DR36"  !CDS_PN = "DR36";
"VSS<116>":   PN = "DR34"  !CDS_PN = "DR34";
"VSS<117>":   PN = "DR32"  !CDS_PN = "DR32";
"VSS<118>":   PN = "DR30"  !CDS_PN = "DR30";
"VSS<119>":   PN = "DR28"  !CDS_PN = "DR28";
"VSS<120>":   PN = "DR26"  !CDS_PN = "DR26";
"VSS<121>":   PN = "DR24"  !CDS_PN = "DR24";
"VSS<122>":   PN = "DR22"  !CDS_PN = "DR22";
"VSS<123>":   PN = "DR20"  !CDS_PN = "DR20";
"VSS<124>":   PN = "CL22"  !CDS_PN = "CL22";
"VSS<125>":   PN = "CA20"  !CDS_PN = "CA20";
"VSS<126>":   PN = "DR6"  !CDS_PN = "DR6";
"VSS<127>":   PN = "BR26"  !CDS_PN = "BR26";
"VSS<128>":   PN = "DP83"  !CDS_PN = "DP83";
"VSS<129>":   PN = "DP81"  !CDS_PN = "DP81";
"VSS<130>":   PN = "DP71"  !CDS_PN = "DP71";
"VSS<131>":   PN = "DP69"  !CDS_PN = "DP69";
"VSS<132>":   PN = "DP67"  !CDS_PN = "DP67";
"VSS<133>":   PN = "DN78"  !CDS_PN = "DN78";
DRAWING = "@baseboard_fab2_lib.baseboard_fab2(sch_1):page76";
BODY = "CAP_A","I1": #LOCATION = "C3D21" !CDS_LOCATION = "C3D21" &SEC = "1" #&CDS_SEC = "1";
"A":   PN = "1"  !CDS_PN = "1";
"B":   PN = "2"  !CDS_PN = "2";
BODY = "CAP_A","I3": #LOCATION = "C3D5" !CDS_LOCATION = "C3D5" &SEC = "1" #&CDS_SEC = "1";
"A":   PN = "1"  !CDS_PN = "1";
"B":   PN = "2"  !CDS_PN = "2";
BODY = "CAP_A","I4": #LOCATION = "C3D12" !CDS_LOCATION = "C3D12" &SEC = "1" #&CDS_SEC = "1";
"A":   PN = "1"  !CDS_PN = "1";
"B":   PN = "2"  !CDS_PN = "2";
BODY = "CAP_A","I5": #LOCATION = "C3D4" !CDS_LOCATION = "C3D4" &SEC = "1" #&CDS_SEC = "1";
"A":   PN = "1"  !CDS_PN = "1";
"B":   PN = "2"  !CDS_PN = "2";
BODY = "CAP_A","I7": #LOCATION = "C3D11" !CDS_LOCATION = "C3D11" &SEC = "1" #&CDS_SEC = "1";
"A":   PN = "1"  !CDS_PN = "1";
"B":   PN = "2"  !CDS_PN = "2";
BODY = "CAP_A","I8": #LOCATION = "C3D13" !CDS_LOCATION = "C3D13" &SEC = "1" #&CDS_SEC = "1";
"A":   PN = "1"  !CDS_PN = "1";
"B":   PN = "2"  !CDS_PN = "2";
BODY = "CAP_A","I10": #LOCATION = "C2D40" !CDS_LOCATION = "C2D40" &SEC = "1" #&CDS_SEC = "1";
"A":   PN = "1"  !CDS_PN = "1";
"B":   PN = "2"  !CDS_PN = "2";
BODY = "CAP_A","I15": #LOCATION = "C3D9" !CDS_LOCATION = "C3D9" &SEC = "1" #&CDS_SEC = "1";
"A":   PN = "1"  !CDS_PN = "1";
"B":   PN = "2"  !CDS_PN = "2";
BODY = "CAP_A","I18": #LOCATION = "C3D8" !CDS_LOCATION = "C3D8" &SEC = "1" #&CDS_SEC = "1";
"A":   PN = "1"  !CDS_PN = "1";
"B":   PN = "2"  !CDS_PN = "2";
BODY = "CAP","I23": #LOCATION = "C7P6" !CDS_LOCATION = "C7P6" &SEC = "1" #&CDS_SEC = "1";
"A":   PN = "1"  !CDS_PN = "1";
"B":   PN = "2"  !CDS_PN = "2";
BODY = "CAP","I25": #LOCATION = "C7P13" !CDS_LOCATION = "C7P13" &SEC = "1" #&CDS_SEC = "1";
"A":   PN = "1"  !CDS_PN = "1";
"B":   PN = "2"  !CDS_PN = "2";
BODY = "CAP","I26": #LOCATION = "C7P10" !CDS_LOCATION = "C7P10" &SEC = "1" #&CDS_SEC = "1";
"A":   PN = "1"  !CDS_PN = "1";
"B":   PN = "2"  !CDS_PN = "2";
BODY = "CAP","I27": #LOCATION = "C7P7" !CDS_LOCATION = "C7P7" &SEC = "1" #&CDS_SEC = "1";
"A":   PN = "1"  !CDS_PN = "1";
"B":   PN = "2"  !CDS_PN = "2";
BODY = "CAP","I28": #LOCATION = "C8P22" !CDS_LOCATION = "C8P22" &SEC = "1" #&CDS_SEC = "1";
"A":   PN = "1"  !CDS_PN = "1";
"B":   PN = "2"  !CDS_PN = "2";
BODY = "CAP","I29": #LOCATION = "C7P17" !CDS_LOCATION = "C7P17" &SEC = "1" #&CDS_SEC = "1";
"A":   PN = "1"  !CDS_PN = "1";
"B":   PN = "2"  !CDS_PN = "2";
BODY = "CAP","I33": #LOCATION = "C2D8" !CDS_LOCATION = "C2D8" &SEC = "1" #&CDS_SEC = "1";
"A":   PN = "1"  !CDS_PN = "1";
"B":   PN = "2"  !CDS_PN = "2";
BODY = "CAP","I37": #LOCATION = "C2D10" !CDS_LOCATION = "C2D10" &SEC = "1" #&CDS_SEC = "1";
"A":   PN = "1"  !CDS_PN = "1";
"B":   PN = "2"  !CDS_PN = "2";
BODY = "CAP","I42": #LOCATION = "C2D11" !CDS_LOCATION = "C2D11" &SEC = "1" #&CDS_SEC = "1";
"A":   PN = "1"  !CDS_PN = "1";
"B":   PN = "2"  !CDS_PN = "2";
BODY = "CAP","I43": #LOCATION = "C2D9" !CDS_LOCATION = "C2D9" &SEC = "1" #&CDS_SEC = "1";
"A":   PN = "1"  !CDS_PN = "1";
"B":   PN = "2"  !CDS_PN = "2";
BODY = "CAP","I45": #LOCATION = "C7P15" !CDS_LOCATION = "C7P15" &SEC = "1" #&CDS_SEC = "1";
"A":   PN = "1"  !CDS_PN = "1";
"B":   PN = "2"  !CDS_PN = "2";
BODY = "CAP","I48": #LOCATION = "C8P23" !CDS_LOCATION = "C8P23" &SEC = "1" #&CDS_SEC = "1";
"A":   PN = "1"  !CDS_PN = "1";
"B":   PN = "2"  !CDS_PN = "2";
BODY = "CAP","I49": #LOCATION = "C7P14" !CDS_LOCATION = "C7P14" &SEC = "1" #&CDS_SEC = "1";
"A":   PN = "1"  !CDS_PN = "1";
"B":   PN = "2"  !CDS_PN = "2";
BODY = "CAP","I50": #LOCATION = "C8P7" !CDS_LOCATION = "C8P7" &SEC = "1" #&CDS_SEC = "1";
"A":   PN = "1"  !CDS_PN = "1";
"B":   PN = "2"  !CDS_PN = "2";
BODY = "CAP","I51": #LOCATION = "C7P18" !CDS_LOCATION = "C7P18" &SEC = "1" #&CDS_SEC = "1";
"A":   PN = "1"  !CDS_PN = "1";
"B":   PN = "2"  !CDS_PN = "2";
BODY = "CAP","I52": #LOCATION = "C7P3" !CDS_LOCATION = "C7P3" &SEC = "1" #&CDS_SEC = "1";
"A":   PN = "1"  !CDS_PN = "1";
"B":   PN = "2"  !CDS_PN = "2";
BODY = "CAP","I55": #LOCATION = "C8P6" !CDS_LOCATION = "C8P6" &SEC = "1" #&CDS_SEC = "1";
"A":   PN = "1"  !CDS_PN = "1";
"B":   PN = "2"  !CDS_PN = "2";
BODY = "CAP","I58": #LOCATION = "C8P5" !CDS_LOCATION = "C8P5" &SEC = "1" #&CDS_SEC = "1";
"A":   PN = "1"  !CDS_PN = "1";
"B":   PN = "2"  !CDS_PN = "2";
BODY = "CAP_A","I59": #LOCATION = "C2D12" !CDS_LOCATION = "C2D12" &SEC = "1" #&CDS_SEC = "1";
"A":   PN = "1"  !CDS_PN = "1";
"B":   PN = "2"  !CDS_PN = "2";
BODY = "CAP_A","I61": #LOCATION = "C2D22" !CDS_LOCATION = "C2D22" &SEC = "1" #&CDS_SEC = "1";
"A":   PN = "1"  !CDS_PN = "1";
"B":   PN = "2"  !CDS_PN = "2";
BODY = "CAP_A","I63": #LOCATION = "C2D31" !CDS_LOCATION = "C2D31" &SEC = "1" #&CDS_SEC = "1";
"A":   PN = "1"  !CDS_PN = "1";
"B":   PN = "2"  !CDS_PN = "2";
BODY = "CAP_A","I65": #LOCATION = "C2D21" !CDS_LOCATION = "C2D21" &SEC = "1" #&CDS_SEC = "1";
"A":   PN = "1"  !CDS_PN = "1";
"B":   PN = "2"  !CDS_PN = "2";
BODY = "CAP_A","I66": #LOCATION = "C2D27" !CDS_LOCATION = "C2D27" &SEC = "1" #&CDS_SEC = "1";
"A":   PN = "1"  !CDS_PN = "1";
"B":   PN = "2"  !CDS_PN = "2";
BODY = "CAP_A","I69": #LOCATION = "C3D2" !CDS_LOCATION = "C3D2" &SEC = "1" #&CDS_SEC = "1";
"A":   PN = "1"  !CDS_PN = "1";
"B":   PN = "2"  !CDS_PN = "2";
BODY = "CAP_A","I70": #LOCATION = "C2D36" !CDS_LOCATION = "C2D36" &SEC = "1" #&CDS_SEC = "1";
"A":   PN = "1"  !CDS_PN = "1";
"B":   PN = "2"  !CDS_PN = "2";
BODY = "CAP_A","I73": #LOCATION = "C2D13" !CDS_LOCATION = "C2D13" &SEC = "1" #&CDS_SEC = "1";
"A":   PN = "1"  !CDS_PN = "1";
"B":   PN = "2"  !CDS_PN = "2";
BODY = "CAP_A","I75": #LOCATION = "C2D19" !CDS_LOCATION = "C2D19" &SEC = "1" #&CDS_SEC = "1";
"A":   PN = "1"  !CDS_PN = "1";
"B":   PN = "2"  !CDS_PN = "2";
BODY = "CAP_A","I76": #LOCATION = "C2D14" !CDS_LOCATION = "C2D14" &SEC = "1" #&CDS_SEC = "1";
"A":   PN = "1"  !CDS_PN = "1";
"B":   PN = "2"  !CDS_PN = "2";
BODY = "CAP_A","I79": #LOCATION = "C2D20" !CDS_LOCATION = "C2D20" &SEC = "1" #&CDS_SEC = "1";
"A":   PN = "1"  !CDS_PN = "1";
"B":   PN = "2"  !CDS_PN = "2";
BODY = "CAP_A","I80": #LOCATION = "C2D24" !CDS_LOCATION = "C2D24" &SEC = "1" #&CDS_SEC = "1";
"A":   PN = "1"  !CDS_PN = "1";
"B":   PN = "2"  !CDS_PN = "2";
BODY = "CAP_A","I82": #LOCATION = "C2D25" !CDS_LOCATION = "C2D25" &SEC = "1" #&CDS_SEC = "1";
"A":   PN = "1"  !CDS_PN = "1";
"B":   PN = "2"  !CDS_PN = "2";
BODY = "CAP_A","I83": #LOCATION = "C2D30" !CDS_LOCATION = "C2D30" &SEC = "1" #&CDS_SEC = "1";
"A":   PN = "1"  !CDS_PN = "1";
"B":   PN = "2"  !CDS_PN = "2";
BODY = "CAP_A","I85": #LOCATION = "C2D33" !CDS_LOCATION = "C2D33" &SEC = "1" #&CDS_SEC = "1";
"A":   PN = "1"  !CDS_PN = "1";
"B":   PN = "2"  !CDS_PN = "2";
BODY = "CAP","I88": #LOCATION = "C8P4" !CDS_LOCATION = "C8P4" &SEC = "1" #&CDS_SEC = "1";
"A":   PN = "1"  !CDS_PN = "1";
"B":   PN = "2"  !CDS_PN = "2";
BODY = "CAP","I89": #LOCATION = "C8P20" !CDS_LOCATION = "C8P20" &SEC = "1" #&CDS_SEC = "1";
"A":   PN = "1"  !CDS_PN = "1";
"B":   PN = "2"  !CDS_PN = "2";
BODY = "CAP_A","I90": #LOCATION = "C2D32" !CDS_LOCATION = "C2D32" &SEC = "1" #&CDS_SEC = "1";
"A":   PN = "1"  !CDS_PN = "1";
"B":   PN = "2"  !CDS_PN = "2";
BODY = "CAP","I92": #LOCATION = "C8P18" !CDS_LOCATION = "C8P18" &SEC = "1" #&CDS_SEC = "1";
"A":   PN = "1"  !CDS_PN = "1";
"B":   PN = "2"  !CDS_PN = "2";
BODY = "CAP","I100": #LOCATION = "C7P2" !CDS_LOCATION = "C7P2" &SEC = "1" #&CDS_SEC = "1";
"A":   PN = "1"  !CDS_PN = "1";
"B":   PN = "2"  !CDS_PN = "2";
BODY = "CAP","I101": #LOCATION = "C8P3" !CDS_LOCATION = "C8P3" &SEC = "1" #&CDS_SEC = "1";
"A":   PN = "1"  !CDS_PN = "1";
"B":   PN = "2"  !CDS_PN = "2";
BODY = "CAP","I103": #LOCATION = "C8P19" !CDS_LOCATION = "C8P19" &SEC = "1" #&CDS_SEC = "1";
"A":   PN = "1"  !CDS_PN = "1";
"B":   PN = "2"  !CDS_PN = "2";
BODY = "CAP","I105": #LOCATION = "C7P1" !CDS_LOCATION = "C7P1" &SEC = "1" #&CDS_SEC = "1";
"A":   PN = "1"  !CDS_PN = "1";
"B":   PN = "2"  !CDS_PN = "2";
BODY = "CAP","I106": #LOCATION = "C8P34" !CDS_LOCATION = "C8P34" &SEC = "1" #&CDS_SEC = "1";
"A":   PN = "1"  !CDS_PN = "1";
"B":   PN = "2"  !CDS_PN = "2";
BODY = "CAP","I107": #LOCATION = "C8P12" !CDS_LOCATION = "C8P12" &SEC = "1" #&CDS_SEC = "1";
"A":   PN = "1"  !CDS_PN = "1";
"B":   PN = "2"  !CDS_PN = "2";
BODY = "CAP_A","I108": #LOCATION = "C2D26" !CDS_LOCATION = "C2D26" &SEC = "1" #&CDS_SEC = "1";
"A":   PN = "1"  !CDS_PN = "1";
"B":   PN = "2"  !CDS_PN = "2";
BODY = "CAP_A","I111": #LOCATION = "C3D1" !CDS_LOCATION = "C3D1" &SEC = "1" #&CDS_SEC = "1";
"A":   PN = "1"  !CDS_PN = "1";
"B":   PN = "2"  !CDS_PN = "2";
BODY = "CAP_A","I112": #LOCATION = "C2D23" !CDS_LOCATION = "C2D23" &SEC = "1" #&CDS_SEC = "1";
"A":   PN = "1"  !CDS_PN = "1";
"B":   PN = "2"  !CDS_PN = "2";
BODY = "CAP_A","I114": #LOCATION = "C2D17" !CDS_LOCATION = "C2D17" &SEC = "1" #&CDS_SEC = "1";
"A":   PN = "1"  !CDS_PN = "1";
"B":   PN = "2"  !CDS_PN = "2";
BODY = "CAP_A","I116": #LOCATION = "C2D1" !CDS_LOCATION = "C2D1" &SEC = "1" #&CDS_SEC = "1";
"A":   PN = "1"  !CDS_PN = "1";
"B":   PN = "2"  !CDS_PN = "2";
BODY = "CAP","I118": #LOCATION = "C8P26" !CDS_LOCATION = "C8P26" &SEC = "1" #&CDS_SEC = "1";
"A":   PN = "1"  !CDS_PN = "1";
"B":   PN = "2"  !CDS_PN = "2";
BODY = "CAP_A","I119": #LOCATION = "C2D37" !CDS_LOCATION = "C2D37" &SEC = "1" #&CDS_SEC = "1";
"A":   PN = "1"  !CDS_PN = "1";
"B":   PN = "2"  !CDS_PN = "2";
BODY = "CAP_A","I122": #LOCATION = "C2D34" !CDS_LOCATION = "C2D34" &SEC = "1" #&CDS_SEC = "1";
"A":   PN = "1"  !CDS_PN = "1";
"B":   PN = "2"  !CDS_PN = "2";
BODY = "CAP_A","I123": #LOCATION = "C2D45" !CDS_LOCATION = "C2D45" &SEC = "1" #&CDS_SEC = "1";
"A":   PN = "1"  !CDS_PN = "1";
"B":   PN = "2"  !CDS_PN = "2";
BODY = "CAP_A","I124": #LOCATION = "C2D16" !CDS_LOCATION = "C2D16" &SEC = "1" #&CDS_SEC = "1";
"A":   PN = "1"  !CDS_PN = "1";
"B":   PN = "2"  !CDS_PN = "2";
BODY = "CAP","I125": #LOCATION = "C8P29" !CDS_LOCATION = "C8P29" &SEC = "1" #&CDS_SEC = "1";
"A":   PN = "1"  !CDS_PN = "1";
"B":   PN = "2"  !CDS_PN = "2";
BODY = "CAP","I127": #LOCATION = "C8P10" !CDS_LOCATION = "C8P10" &SEC = "1" #&CDS_SEC = "1";
"A":   PN = "1"  !CDS_PN = "1";
"B":   PN = "2"  !CDS_PN = "2";
BODY = "CAP","I129": #LOCATION = "C8P16" !CDS_LOCATION = "C8P16" &SEC = "1" #&CDS_SEC = "1";
"A":   PN = "1"  !CDS_PN = "1";
"B":   PN = "2"  !CDS_PN = "2";
BODY = "CAP","I131": #LOCATION = "C8P33" !CDS_LOCATION = "C8P33" &SEC = "1" #&CDS_SEC = "1";
"A":   PN = "1"  !CDS_PN = "1";
"B":   PN = "2"  !CDS_PN = "2";
BODY = "CAP","I132": #LOCATION = "C8P13" !CDS_LOCATION = "C8P13" &SEC = "1" #&CDS_SEC = "1";
"A":   PN = "1"  !CDS_PN = "1";
"B":   PN = "2"  !CDS_PN = "2";
BODY = "CAP","I133": #LOCATION = "C8P17" !CDS_LOCATION = "C8P17" &SEC = "1" #&CDS_SEC = "1";
"A":   PN = "1"  !CDS_PN = "1";
"B":   PN = "2"  !CDS_PN = "2";
BODY = "CAP","I135": #LOCATION = "C8P21" !CDS_LOCATION = "C8P21" &SEC = "1" #&CDS_SEC = "1";
"A":   PN = "1"  !CDS_PN = "1";
"B":   PN = "2"  !CDS_PN = "2";
BODY = "CAP","I136": #LOCATION = "C8P25" !CDS_LOCATION = "C8P25" &SEC = "1" #&CDS_SEC = "1";
"A":   PN = "1"  !CDS_PN = "1";
"B":   PN = "2"  !CDS_PN = "2";
BODY = "CAP","I137": #LOCATION = "C8P28" !CDS_LOCATION = "C8P28" &SEC = "1" #&CDS_SEC = "1";
"A":   PN = "1"  !CDS_PN = "1";
"B":   PN = "2"  !CDS_PN = "2";
BODY = "CAP","I139": #LOCATION = "C8P11" !CDS_LOCATION = "C8P11" &SEC = "1" #&CDS_SEC = "1";
"A":   PN = "1"  !CDS_PN = "1";
"B":   PN = "2"  !CDS_PN = "2";
BODY = "CAP","I141": #LOCATION = "C8P27" !CDS_LOCATION = "C8P27" &SEC = "1" #&CDS_SEC = "1";
"A":   PN = "1"  !CDS_PN = "1";
"B":   PN = "2"  !CDS_PN = "2";
BODY = "CAP_A","I159": #LOCATION = "C2D15" !CDS_LOCATION = "C2D15" &SEC = "1" #&CDS_SEC = "1";
"A":   PN = "1"  !CDS_PN = "1";
"B":   PN = "2"  !CDS_PN = "2";
BODY = "CAP_A","I160": #LOCATION = "C2D38" !CDS_LOCATION = "C2D38" &SEC = "1" #&CDS_SEC = "1";
"A":   PN = "1"  !CDS_PN = "1";
"B":   PN = "2"  !CDS_PN = "2";
BODY = "CAP_A","I161": #LOCATION = "C2D35" !CDS_LOCATION = "C2D35" &SEC = "1" #&CDS_SEC = "1";
"A":   PN = "1"  !CDS_PN = "1";
"B":   PN = "2"  !CDS_PN = "2";
BODY = "CAP_A","I164": #LOCATION = "C3D7" !CDS_LOCATION = "C3D7" &SEC = "1" #&CDS_SEC = "1";
"A":   PN = "1"  !CDS_PN = "1";
"B":   PN = "2"  !CDS_PN = "2";
BODY = "CAP_A","I165": #LOCATION = "C2D39" !CDS_LOCATION = "C2D39" &SEC = "1" #&CDS_SEC = "1";
"A":   PN = "1"  !CDS_PN = "1";
"B":   PN = "2"  !CDS_PN = "2";
BODY = "CAP_A","I166": #LOCATION = "C3D17" !CDS_LOCATION = "C3D17" &SEC = "1" #&CDS_SEC = "1";
"A":   PN = "1"  !CDS_PN = "1";
"B":   PN = "2"  !CDS_PN = "2";
BODY = "CAP_A","I169": #LOCATION = "C3D18" !CDS_LOCATION = "C3D18" &SEC = "1" #&CDS_SEC = "1";
"A":   PN = "1"  !CDS_PN = "1";
"B":   PN = "2"  !CDS_PN = "2";
BODY = "CAP_A","I170": #LOCATION = "C3D6" !CDS_LOCATION = "C3D6" &SEC = "1" #&CDS_SEC = "1";
"A":   PN = "1"  !CDS_PN = "1";
"B":   PN = "2"  !CDS_PN = "2";
BODY = "CAP_A","I171": #LOCATION = "C3D14" !CDS_LOCATION = "C3D14" &SEC = "1" #&CDS_SEC = "1";
"A":   PN = "1"  !CDS_PN = "1";
"B":   PN = "2"  !CDS_PN = "2";
BODY = "CAP_A","I172": #LOCATION = "C3D23" !CDS_LOCATION = "C3D23" &SEC = "1" #&CDS_SEC = "1";
"A":   PN = "1"  !CDS_PN = "1";
"B":   PN = "2"  !CDS_PN = "2";
BODY = "CAP_A","I174": #LOCATION = "C3D15" !CDS_LOCATION = "C3D15" &SEC = "1" #&CDS_SEC = "1";
"A":   PN = "1"  !CDS_PN = "1";
"B":   PN = "2"  !CDS_PN = "2";
BODY = "CAP_A","I175": #LOCATION = "C3D24" !CDS_LOCATION = "C3D24" &SEC = "1" #&CDS_SEC = "1";
"A":   PN = "1"  !CDS_PN = "1";
"B":   PN = "2"  !CDS_PN = "2";
BODY = "CAP_A","I176": #LOCATION = "C3D16" !CDS_LOCATION = "C3D16" &SEC = "1" #&CDS_SEC = "1";
"A":   PN = "1"  !CDS_PN = "1";
"B":   PN = "2"  !CDS_PN = "2";
BODY = "CAP_A","I179": #LOCATION = "C7P12" !CDS_LOCATION = "C7P12" &SEC = "1" #&CDS_SEC = "1";
"A":   PN = "1"  !CDS_PN = "1";
"B":   PN = "2"  !CDS_PN = "2";
BODY = "CAP","I181": #LOCATION = "C7P9" !CDS_LOCATION = "C7P9" #SEC = "1" !CDS_SEC = "1";
"A":   PN = "1"  !CDS_PN = "1";
"B":   PN = "2"  !CDS_PN = "2";
BODY = "CAP","I182": #LOCATION = "C7P5" !CDS_LOCATION = "C7P5" &SEC = "1" #&CDS_SEC = "1";
"A":   PN = "1"  !CDS_PN = "1";
"B":   PN = "2"  !CDS_PN = "2";
BODY = "CAP","I183": #LOCATION = "C7P11" !CDS_LOCATION = "C7P11" &SEC = "1" #&CDS_SEC = "1";
"A":   PN = "1"  !CDS_PN = "1";
"B":   PN = "2"  !CDS_PN = "2";
BODY = "CAP","I184": #LOCATION = "C7P8" !CDS_LOCATION = "C7P8" &SEC = "1" #&CDS_SEC = "1";
"A":   PN = "1"  !CDS_PN = "1";
"B":   PN = "2"  !CDS_PN = "2";
BODY = "CAP","I195": #LOCATION = "C7P4" !CDS_LOCATION = "C7P4" &SEC = "1" #&CDS_SEC = "1";
"A":   PN = "1"  !CDS_PN = "1";
"B":   PN = "2"  !CDS_PN = "2";
BODY = "CAP_A","I196": #LOCATION = "C3D10" !CDS_LOCATION = "C3D10" &SEC = "1" #&CDS_SEC = "1";
"A":   PN = "1"  !CDS_PN = "1";
"B":   PN = "2"  !CDS_PN = "2";
BODY = "CAP_A","I197": #LOCATION = "C2D18" !CDS_LOCATION = "C2D18" &SEC = "1" #&CDS_SEC = "1";
"A":   PN = "1"  !CDS_PN = "1";
"B":   PN = "2"  !CDS_PN = "2";
BODY = "CAP_A","I198": #LOCATION = "C2D28" !CDS_LOCATION = "C2D28" &SEC = "1" #&CDS_SEC = "1";
"A":   PN = "1"  !CDS_PN = "1";
"B":   PN = "2"  !CDS_PN = "2";
BODY = "CAP_A","I199": #LOCATION = "C2D29" !CDS_LOCATION = "C2D29" &SEC = "1" #&CDS_SEC = "1";
"A":   PN = "1"  !CDS_PN = "1";
"B":   PN = "2"  !CDS_PN = "2";
BODY = "CAP_A","I201": #LOCATION = "C2D2" !CDS_LOCATION = "C2D2" &SEC = "1" #&CDS_SEC = "1";
"A":   PN = "1"  !CDS_PN = "1";
"B":   PN = "2"  !CDS_PN = "2";
BODY = "CAP_A","I202": #LOCATION = "C2D3" !CDS_LOCATION = "C2D3" &SEC = "1" #&CDS_SEC = "1";
"A":   PN = "1"  !CDS_PN = "1";
"B":   PN = "2"  !CDS_PN = "2";
BODY = "CAP_A","I203": #LOCATION = "C2D47" !CDS_LOCATION = "C2D47" &SEC = "1" #&CDS_SEC = "1";
"A":   PN = "1"  !CDS_PN = "1";
"B":   PN = "2"  !CDS_PN = "2";
BODY = "CAP_A","I204": #LOCATION = "C2D46" !CDS_LOCATION = "C2D46" &SEC = "1" #&CDS_SEC = "1";
"A":   PN = "1"  !CDS_PN = "1";
"B":   PN = "2"  !CDS_PN = "2";
BODY = "CAP_A","I205": #LOCATION = "C3D25" !CDS_LOCATION = "C3D25" &SEC = "1" #&CDS_SEC = "1";
"A":   PN = "1"  !CDS_PN = "1";
"B":   PN = "2"  !CDS_PN = "2";
BODY = "CAP_A","I206": #LOCATION = "C7P16" !CDS_LOCATION = "C7P16" &SEC = "1" #&CDS_SEC = "1";
"A":   PN = "1"  !CDS_PN = "1";
"B":   PN = "2"  !CDS_PN = "2";
BODY = "CAP_A","I207": #LOCATION = "C3D20" !CDS_LOCATION = "C3D20" &SEC = "1" #&CDS_SEC = "1";
"A":   PN = "1"  !CDS_PN = "1";
"B":   PN = "2"  !CDS_PN = "2";
BODY = "CAP_A","I208": #LOCATION = "C3D19" !CDS_LOCATION = "C3D19" &SEC = "1" #&CDS_SEC = "1";
"A":   PN = "1"  !CDS_PN = "1";
"B":   PN = "2"  !CDS_PN = "2";
BODY = "CAP","I211": #LOCATION = "C8P14" !CDS_LOCATION = "C8P14" &SEC = "1" #&CDS_SEC = "1";
"A":   PN = "1"  !CDS_PN = "1";
"B":   PN = "2"  !CDS_PN = "2";
BODY = "CAP","I212": #LOCATION = "C8P15" !CDS_LOCATION = "C8P15" &SEC = "1" #&CDS_SEC = "1";
"A":   PN = "1"  !CDS_PN = "1";
"B":   PN = "2"  !CDS_PN = "2";
BODY = "CAP","I213": #LOCATION = "C8P8" !CDS_LOCATION = "C8P8" &SEC = "1" #&CDS_SEC = "1";
"A":   PN = "1"  !CDS_PN = "1";
"B":   PN = "2"  !CDS_PN = "2";
BODY = "CAP","I214": #LOCATION = "C8P9" !CDS_LOCATION = "C8P9" &SEC = "1" #&CDS_SEC = "1";
"A":   PN = "1"  !CDS_PN = "1";
"B":   PN = "2"  !CDS_PN = "2";
BODY = "CAP","I215": #LOCATION = "C7P19" !CDS_LOCATION = "C7P19" &SEC = "1" #&CDS_SEC = "1";
"A":   PN = "1"  !CDS_PN = "1";
"B":   PN = "2"  !CDS_PN = "2";
BODY = "CAP","I216": #LOCATION = "C8P32" !CDS_LOCATION = "C8P32" &SEC = "1" #&CDS_SEC = "1";
"A":   PN = "1"  !CDS_PN = "1";
"B":   PN = "2"  !CDS_PN = "2";
BODY = "CAP","I217": #LOCATION = "C8P24" !CDS_LOCATION = "C8P24" &SEC = "1" #&CDS_SEC = "1";
"A":   PN = "1"  !CDS_PN = "1";
"B":   PN = "2"  !CDS_PN = "2";
BODY = "CAP","I218": #LOCATION = "C7P20" !CDS_LOCATION = "C7P20" &SEC = "1" #&CDS_SEC = "1";
"A":   PN = "1"  !CDS_PN = "1";
"B":   PN = "2"  !CDS_PN = "2";
DRAWING = "@baseboard_fab2_lib.baseboard_fab2(sch_1):page77";
BODY = "SCONN288_H44441004","I43": #LOCATION = "J1G1" !CDS_LOCATION = "J1G1" #SEC = "3" !CDS_SEC = "3";
"VSS<0>":   PN = "283"  !CDS_PN = "283";
"VSS<1>":   PN = "281"  !CDS_PN = "281";
"VSS<2>":   PN = "279"  !CDS_PN = "279";
"VSS<3>":   PN = "276"  !CDS_PN = "276";
"VSS<4>":   PN = "274"  !CDS_PN = "274";
"VSS<5>":   PN = "272"  !CDS_PN = "272";
"VSS<6>":   PN = "270"  !CDS_PN = "270";
"VSS<7>":   PN = "268"  !CDS_PN = "268";
"VSS<8>":   PN = "265"  !CDS_PN = "265";
"VSS<9>":   PN = "263"  !CDS_PN = "263";
"VSS<10>":   PN = "261"  !CDS_PN = "261";
"VSS<11>":   PN = "259"  !CDS_PN = "259";
"VSS<12>":   PN = "257"  !CDS_PN = "257";
"VSS<13>":   PN = "254"  !CDS_PN = "254";
"VSS<14>":   PN = "252"  !CDS_PN = "252";
"VSS<15>":   PN = "250"  !CDS_PN = "250";
"VSS<16>":   PN = "248"  !CDS_PN = "248";
"VSS<17>":   PN = "246"  !CDS_PN = "246";
"VSS<18>":   PN = "243"  !CDS_PN = "243";
"VSS<19>":   PN = "241"  !CDS_PN = "241";
"VSS<20>":   PN = "239"  !CDS_PN = "239";
"VSS<21>":   PN = "202"  !CDS_PN = "202";
"VSS<22>":   PN = "200"  !CDS_PN = "200";
"VSS<23>":   PN = "198"  !CDS_PN = "198";
"VSS<24>":   PN = "195"  !CDS_PN = "195";
"VSS<25>":   PN = "193"  !CDS_PN = "193";
"VSS<26>":   PN = "191"  !CDS_PN = "191";
"VSS<27>":   PN = "189"  !CDS_PN = "189";
"VSS<28>":   PN = "187"  !CDS_PN = "187";
"VSS<29>":   PN = "184"  !CDS_PN = "184";
"VSS<30>":   PN = "182"  !CDS_PN = "182";
"VSS<31>":   PN = "180"  !CDS_PN = "180";
"VSS<32>":   PN = "178"  !CDS_PN = "178";
"VSS<33>":   PN = "176"  !CDS_PN = "176";
"VSS<34>":   PN = "173"  !CDS_PN = "173";
"VSS<35>":   PN = "171"  !CDS_PN = "171";
"VSS<36>":   PN = "169"  !CDS_PN = "169";
"VSS<37>":   PN = "167"  !CDS_PN = "167";
"VSS<38>":   PN = "165"  !CDS_PN = "165";
"VSS<39>":   PN = "162"  !CDS_PN = "162";
"VSS<40>":   PN = "160"  !CDS_PN = "160";
"VSS<41>":   PN = "158"  !CDS_PN = "158";
"VSS<42>":   PN = "156"  !CDS_PN = "156";
"VSS<43>":   PN = "154"  !CDS_PN = "154";
"VSS<44>":   PN = "151"  !CDS_PN = "151";
"VSS<45>":   PN = "149"  !CDS_PN = "149";
"VSS<46>":   PN = "147"  !CDS_PN = "147";
"VSS<47>":   PN = "138"  !CDS_PN = "138";
"VSS<48>":   PN = "136"  !CDS_PN = "136";
"VSS<49>":   PN = "134"  !CDS_PN = "134";
"VSS<50>":   PN = "131"  !CDS_PN = "131";
"VSS<51>":   PN = "129"  !CDS_PN = "129";
"VSS<52>":   PN = "127"  !CDS_PN = "127";
"VSS<53>":   PN = "125"  !CDS_PN = "125";
"VSS<54>":   PN = "123"  !CDS_PN = "123";
"VSS<55>":   PN = "120"  !CDS_PN = "120";
"VSS<56>":   PN = "118"  !CDS_PN = "118";
"VSS<57>":   PN = "116"  !CDS_PN = "116";
"VSS<58>":   PN = "114"  !CDS_PN = "114";
"VSS<59>":   PN = "112"  !CDS_PN = "112";
"VSS<60>":   PN = "109"  !CDS_PN = "109";
"VSS<61>":   PN = "107"  !CDS_PN = "107";
"VSS<62>":   PN = "105"  !CDS_PN = "105";
"VSS<63>":   PN = "103"  !CDS_PN = "103";
"VSS<64>":   PN = "101"  !CDS_PN = "101";
"VSS<65>":   PN = "98"  !CDS_PN = "98";
"VSS<66>":   PN = "96"  !CDS_PN = "96";
"VSS<67>":   PN = "94"  !CDS_PN = "94";
"VSS<68>":   PN = "57"  !CDS_PN = "57";
"VSS<69>":   PN = "55"  !CDS_PN = "55";
"VSS<70>":   PN = "53"  !CDS_PN = "53";
"VSS<71>":   PN = "50"  !CDS_PN = "50";
"VSS<72>":   PN = "48"  !CDS_PN = "48";
"VSS<73>":   PN = "46"  !CDS_PN = "46";
"VSS<74>":   PN = "44"  !CDS_PN = "44";
"VSS<75>":   PN = "42"  !CDS_PN = "42";
"VSS<76>":   PN = "39"  !CDS_PN = "39";
"VSS<77>":   PN = "37"  !CDS_PN = "37";
"VSS<78>":   PN = "35"  !CDS_PN = "35";
"VSS<79>":   PN = "33"  !CDS_PN = "33";
"VSS<80>":   PN = "31"  !CDS_PN = "31";
"VSS<81>":   PN = "28"  !CDS_PN = "28";
"VSS<82>":   PN = "26"  !CDS_PN = "26";
"VSS<83>":   PN = "24"  !CDS_PN = "24";
"VSS<84>":   PN = "22"  !CDS_PN = "22";
"VSS<85>":   PN = "20"  !CDS_PN = "20";
"VSS<86>":   PN = "17"  !CDS_PN = "17";
"VSS<87>":   PN = "15"  !CDS_PN = "15";
"VSS<88>":   PN = "13"  !CDS_PN = "13";
"VSS<89>":   PN = "11"  !CDS_PN = "11";
"VSS<90>":   PN = "9"  !CDS_PN = "9";
"VSS<91>":   PN = "6"  !CDS_PN = "6";
"VSS<92>":   PN = "4"  !CDS_PN = "4";
"VSS<93>":   PN = "2"  !CDS_PN = "2";
BODY = "SCONN288_H44441004","I66": #LOCATION = "J1G1" !CDS_LOCATION = "J1G1" #SEC = "2" !CDS_SEC = "2";
"DQS0N":   PN = "152"  !CDS_PN = "152";
"DQS0P":   PN = "153"  !CDS_PN = "153";
"DQS1N":   PN = "163"  !CDS_PN = "163";
"DQS1P":   PN = "164"  !CDS_PN = "164";
"DQS2N":   PN = "174"  !CDS_PN = "174";
"DQS2P":   PN = "175"  !CDS_PN = "175";
"DQS3N":   PN = "185"  !CDS_PN = "185";
"DQS3P":   PN = "186"  !CDS_PN = "186";
"DQS4N":   PN = "244"  !CDS_PN = "244";
"DQS4P":   PN = "245"  !CDS_PN = "245";
"DQS5N":   PN = "255"  !CDS_PN = "255";
"DQS5P":   PN = "256"  !CDS_PN = "256";
"DQS6N":   PN = "266"  !CDS_PN = "266";
"DQS6P":   PN = "267"  !CDS_PN = "267";
"DQS7N":   PN = "277"  !CDS_PN = "277";
"DQS7P":   PN = "278"  !CDS_PN = "278";
"DQS8N":   PN = "196"  !CDS_PN = "196";
"DQS8P":   PN = "197"  !CDS_PN = "197";
"DQS9N":   PN = "8"  !CDS_PN = "8";
"DQS9P":   PN = "7"  !CDS_PN = "7";
"DQS10N":   PN = "19"  !CDS_PN = "19";
"DQS10P":   PN = "18"  !CDS_PN = "18";
"DQS11N":   PN = "30"  !CDS_PN = "30";
"DQS11P":   PN = "29"  !CDS_PN = "29";
"DQS12N":   PN = "41"  !CDS_PN = "41";
"DQS12P":   PN = "40"  !CDS_PN = "40";
"DQS13N":   PN = "100"  !CDS_PN = "100";
"DQS13P":   PN = "99"  !CDS_PN = "99";
"DQS14N":   PN = "111"  !CDS_PN = "111";
"DQS14P":   PN = "110"  !CDS_PN = "110";
"DQS15N":   PN = "122"  !CDS_PN = "122";
"DQS15P":   PN = "121"  !CDS_PN = "121";
"DQS16N":   PN = "133"  !CDS_PN = "133";
"DQS16P":   PN = "132"  !CDS_PN = "132";
"DQS17N":   PN = "52"  !CDS_PN = "52";
"DQS17P":   PN = "51"  !CDS_PN = "51";
BODY = "SCONN288_H44441004","I111": #LOCATION = "J1G1" !CDS_LOCATION = "J1G1" #SEC = "1" !CDS_SEC = "1";
"A0":   PN = "79"  !CDS_PN = "79";
"A1":   PN = "72"  !CDS_PN = "72";
"A2":   PN = "216"  !CDS_PN = "216";
"A3":   PN = "71"  !CDS_PN = "71";
"A4":   PN = "214"  !CDS_PN = "214";
"A5":   PN = "213"  !CDS_PN = "213";
"A6":   PN = "69"  !CDS_PN = "69";
"A7":   PN = "211"  !CDS_PN = "211";
"A8":   PN = "68"  !CDS_PN = "68";
"A9":   PN = "66"  !CDS_PN = "66";
"A10":   PN = "225"  !CDS_PN = "225";
"A11":   PN = "210"  !CDS_PN = "210";
"A12":   PN = "65"  !CDS_PN = "65";
"A13":   PN = "232"  !CDS_PN = "232";
"A14_WE_N":   PN = "228"  !CDS_PN = "228";
"A15_CAS_N":   PN = "86"  !CDS_PN = "86";
"A16_RAS_N":   PN = "82"  !CDS_PN = "82";
"A17":   PN = "234"  !CDS_PN = "234";
"ACT_N":   PN = "62"  !CDS_PN = "62";
"ALERT_N":   PN = "208"  !CDS_PN = "208";
"BA<0>":   PN = "81"  !CDS_PN = "81";
"BA<1>":   PN = "224"  !CDS_PN = "224";
"BG<0>":   PN = "63"  !CDS_PN = "63";
"BG<1>":   PN = "207"  !CDS_PN = "207";
"C<2>":   PN = "235"  !CDS_PN = "235";
"CB<0>":   PN = "49"  !CDS_PN = "49";
"CB<1>":   PN = "194"  !CDS_PN = "194";
"CB<2>":   PN = "56"  !CDS_PN = "56";
"CB<3>":   PN = "201"  !CDS_PN = "201";
"CB<4>":   PN = "47"  !CDS_PN = "47";
"CB<5>":   PN = "192"  !CDS_PN = "192";
"CB<6>":   PN = "54"  !CDS_PN = "54";
"CB<7>":   PN = "199"  !CDS_PN = "199";
"CK0N":   PN = "75"  !CDS_PN = "75";
"CK0P":   PN = "74"  !CDS_PN = "74";
"CK1N":   PN = "219"  !CDS_PN = "219";
"CK1P":   PN = "218"  !CDS_PN = "218";
"CKE<0>":   PN = "60"  !CDS_PN = "60";
"CKE<1>":   PN = "203"  !CDS_PN = "203";
"DQ<0>":   PN = "5"  !CDS_PN = "5";
"DQ<1>":   PN = "150"  !CDS_PN = "150";
"DQ<2>":   PN = "12"  !CDS_PN = "12";
"DQ<3>":   PN = "157"  !CDS_PN = "157";
"DQ<4>":   PN = "3"  !CDS_PN = "3";
"DQ<5>":   PN = "148"  !CDS_PN = "148";
"DQ<6>":   PN = "10"  !CDS_PN = "10";
"DQ<7>":   PN = "155"  !CDS_PN = "155";
"DQ<8>":   PN = "16"  !CDS_PN = "16";
"DQ<9>":   PN = "161"  !CDS_PN = "161";
"DQ<10>":   PN = "23"  !CDS_PN = "23";
"DQ<11>":   PN = "168"  !CDS_PN = "168";
"DQ<12>":   PN = "14"  !CDS_PN = "14";
"DQ<13>":   PN = "159"  !CDS_PN = "159";
"DQ<14>":   PN = "21"  !CDS_PN = "21";
"DQ<15>":   PN = "166"  !CDS_PN = "166";
"DQ<16>":   PN = "27"  !CDS_PN = "27";
"DQ<17>":   PN = "172"  !CDS_PN = "172";
"DQ<18>":   PN = "34"  !CDS_PN = "34";
"DQ<19>":   PN = "179"  !CDS_PN = "179";
"DQ<20>":   PN = "25"  !CDS_PN = "25";
"DQ<21>":   PN = "170"  !CDS_PN = "170";
"DQ<22>":   PN = "32"  !CDS_PN = "32";
"DQ<23>":   PN = "177"  !CDS_PN = "177";
"DQ<24>":   PN = "38"  !CDS_PN = "38";
"DQ<25>":   PN = "183"  !CDS_PN = "183";
"DQ<26>":   PN = "45"  !CDS_PN = "45";
"DQ<27>":   PN = "190"  !CDS_PN = "190";
"DQ<28>":   PN = "36"  !CDS_PN = "36";
"DQ<29>":   PN = "181"  !CDS_PN = "181";
"DQ<30>":   PN = "43"  !CDS_PN = "43";
"DQ<31>":   PN = "188"  !CDS_PN = "188";
"DQ<32>":   PN = "97"  !CDS_PN = "97";
"DQ<33>":   PN = "242"  !CDS_PN = "242";
"DQ<34>":   PN = "104"  !CDS_PN = "104";
"DQ<35>":   PN = "249"  !CDS_PN = "249";
"DQ<36>":   PN = "95"  !CDS_PN = "95";
"DQ<37>":   PN = "240"  !CDS_PN = "240";
"DQ<38>":   PN = "102"  !CDS_PN = "102";
"DQ<39>":   PN = "247"  !CDS_PN = "247";
"DQ<40>":   PN = "108"  !CDS_PN = "108";
"DQ<41>":   PN = "253"  !CDS_PN = "253";
"DQ<42>":   PN = "115"  !CDS_PN = "115";
"DQ<43>":   PN = "260"  !CDS_PN = "260";
"DQ<44>":   PN = "106"  !CDS_PN = "106";
"DQ<45>":   PN = "251"  !CDS_PN = "251";
"DQ<46>":   PN = "113"  !CDS_PN = "113";
"DQ<47>":   PN = "258"  !CDS_PN = "258";
"DQ<48>":   PN = "119"  !CDS_PN = "119";
"DQ<49>":   PN = "264"  !CDS_PN = "264";
"DQ<50>":   PN = "126"  !CDS_PN = "126";
"DQ<51>":   PN = "271"  !CDS_PN = "271";
"DQ<52>":   PN = "117"  !CDS_PN = "117";
"DQ<53>":   PN = "262"  !CDS_PN = "262";
"DQ<54>":   PN = "124"  !CDS_PN = "124";
"DQ<55>":   PN = "269"  !CDS_PN = "269";
"DQ<56>":   PN = "130"  !CDS_PN = "130";
"DQ<57>":   PN = "275"  !CDS_PN = "275";
"DQ<58>":   PN = "137"  !CDS_PN = "137";
"DQ<59>":   PN = "282"  !CDS_PN = "282";
"DQ<60>":   PN = "128"  !CDS_PN = "128";
"DQ<61>":   PN = "273"  !CDS_PN = "273";
"DQ<62>":   PN = "135"  !CDS_PN = "135";
"DQ<63>":   PN = "280"  !CDS_PN = "280";
"EVENT_N":   PN = "78"  !CDS_PN = "78";
"ODT<0>":   PN = "87"  !CDS_PN = "87";
"ODT<1>":   PN = "91"  !CDS_PN = "91";
"PAR":   PN = "222"  !CDS_PN = "222";
"RESET_N":   PN = "58"  !CDS_PN = "58";
"RFU<0>":   PN = "205"  !CDS_PN = "205";
"RFU<1>":   PN = "227"  !CDS_PN = "227";
"RFU<2>":   PN = "144"  !CDS_PN = "144";
"S0_N":   PN = "84"  !CDS_PN = "84";
"S1_N":   PN = "89"  !CDS_PN = "89";
"S2_N_C<0>":   PN = "93"  !CDS_PN = "93";
"S3_N_C<1>":   PN = "237"  !CDS_PN = "237";
"SA<0>":   PN = "139"  !CDS_PN = "139";
"SA<1>":   PN = "140"  !CDS_PN = "140";
"SA<2>":   PN = "238"  !CDS_PN = "238";
"SAVE_N_NC":   PN = "230"  !CDS_PN = "230";
"SCL":   PN = "141"  !CDS_PN = "141";
"SDA":   PN = "285"  !CDS_PN = "285";
"VDDSPD":   PN = "284"  !CDS_PN = "284";
"VREFCA":   PN = "146"  !CDS_PN = "146";
BODY = "SCONN288_H44441004","I171": #LOCATION = "J1G1" !CDS_LOCATION = "J1G1" #SEC = "4" !CDS_SEC = "4";
"12V<0>":   PN = "145"  !CDS_PN = "145";
"12V<1>":   PN = "1"  !CDS_PN = "1";
"VDD<0>":   PN = "236"  !CDS_PN = "236";
"VDD<1>":   PN = "233"  !CDS_PN = "233";
"VDD<2>":   PN = "231"  !CDS_PN = "231";
"VDD<3>":   PN = "229"  !CDS_PN = "229";
"VDD<4>":   PN = "226"  !CDS_PN = "226";
"VDD<5>":   PN = "223"  !CDS_PN = "223";
"VDD<6>":   PN = "220"  !CDS_PN = "220";
"VDD<7>":   PN = "217"  !CDS_PN = "217";
"VDD<8>":   PN = "215"  !CDS_PN = "215";
"VDD<9>":   PN = "212"  !CDS_PN = "212";
"VDD<10>":   PN = "209"  !CDS_PN = "209";
"VDD<11>":   PN = "206"  !CDS_PN = "206";
"VDD<12>":   PN = "204"  !CDS_PN = "204";
"VDD<13>":   PN = "92"  !CDS_PN = "92";
"VDD<14>":   PN = "90"  !CDS_PN = "90";
"VDD<15>":   PN = "88"  !CDS_PN = "88";
"VDD<16>":   PN = "85"  !CDS_PN = "85";
"VDD<17>":   PN = "83"  !CDS_PN = "83";
"VDD<18>":   PN = "80"  !CDS_PN = "80";
"VDD<19>":   PN = "76"  !CDS_PN = "76";
"VDD<20>":   PN = "73"  !CDS_PN = "73";
"VDD<21>":   PN = "70"  !CDS_PN = "70";
"VDD<22>":   PN = "67"  !CDS_PN = "67";
"VDD<23>":   PN = "64"  !CDS_PN = "64";
"VDD<24>":   PN = "61"  !CDS_PN = "61";
"VDD<25>":   PN = "59"  !CDS_PN = "59";
"VPP<0>":   PN = "287"  !CDS_PN = "287";
"VPP<1>":   PN = "286"  !CDS_PN = "286";
"VPP<2>":   PN = "288"  !CDS_PN = "288";
"VPP<3>":   PN = "143"  !CDS_PN = "143";
"VPP<4>":   PN = "142"  !CDS_PN = "142";
"VTT<0>":   PN = "221"  !CDS_PN = "221";
"VTT<1>":   PN = "77"  !CDS_PN = "77";
BODY = "CAP_A","I181": #LOCATION = "C1F22" !CDS_LOCATION = "C1F22" &SEC = "1" #&CDS_SEC = "1";
"A":   PN = "1"  !CDS_PN = "1";
"B":   PN = "2"  !CDS_PN = "2";
DRAWING = "@baseboard_fab2_lib.baseboard_fab2(sch_1):page78";
BODY = "CAP_A","I2": #LOCATION = "C9T7" !CDS_LOCATION = "C9T7" &SEC = "1" #&CDS_SEC = "1";
"A":   PN = "1"  !CDS_PN = "1";
"B":   PN = "2"  !CDS_PN = "2";
BODY = "SCONN288_H44441003","I13": #LOCATION = "J9T1" !CDS_LOCATION = "J9T1" #SEC = "1" !CDS_SEC = "1";
"A0":   PN = "79"  !CDS_PN = "79";
"A1":   PN = "72"  !CDS_PN = "72";
"A2":   PN = "216"  !CDS_PN = "216";
"A3":   PN = "71"  !CDS_PN = "71";
"A4":   PN = "214"  !CDS_PN = "214";
"A5":   PN = "213"  !CDS_PN = "213";
"A6":   PN = "69"  !CDS_PN = "69";
"A7":   PN = "211"  !CDS_PN = "211";
"A8":   PN = "68"  !CDS_PN = "68";
"A9":   PN = "66"  !CDS_PN = "66";
"A10":   PN = "225"  !CDS_PN = "225";
"A11":   PN = "210"  !CDS_PN = "210";
"A12":   PN = "65"  !CDS_PN = "65";
"A13":   PN = "232"  !CDS_PN = "232";
"A14_WE_N":   PN = "228"  !CDS_PN = "228";
"A15_CAS_N":   PN = "86"  !CDS_PN = "86";
"A16_RAS_N":   PN = "82"  !CDS_PN = "82";
"A17":   PN = "234"  !CDS_PN = "234";
"ACT_N":   PN = "62"  !CDS_PN = "62";
"ALERT_N":   PN = "208"  !CDS_PN = "208";
"BA<0>":   PN = "81"  !CDS_PN = "81";
"BA<1>":   PN = "224"  !CDS_PN = "224";
"BG<0>":   PN = "63"  !CDS_PN = "63";
"BG<1>":   PN = "207"  !CDS_PN = "207";
"C<2>":   PN = "235"  !CDS_PN = "235";
"CB<0>":   PN = "49"  !CDS_PN = "49";
"CB<1>":   PN = "194"  !CDS_PN = "194";
"CB<2>":   PN = "56"  !CDS_PN = "56";
"CB<3>":   PN = "201"  !CDS_PN = "201";
"CB<4>":   PN = "47"  !CDS_PN = "47";
"CB<5>":   PN = "192"  !CDS_PN = "192";
"CB<6>":   PN = "54"  !CDS_PN = "54";
"CB<7>":   PN = "199"  !CDS_PN = "199";
"CK0N":   PN = "75"  !CDS_PN = "75";
"CK0P":   PN = "74"  !CDS_PN = "74";
"CK1N":   PN = "219"  !CDS_PN = "219";
"CK1P":   PN = "218"  !CDS_PN = "218";
"CKE<0>":   PN = "60"  !CDS_PN = "60";
"CKE<1>":   PN = "203"  !CDS_PN = "203";
"DQ<0>":   PN = "5"  !CDS_PN = "5";
"DQ<1>":   PN = "150"  !CDS_PN = "150";
"DQ<2>":   PN = "12"  !CDS_PN = "12";
"DQ<3>":   PN = "157"  !CDS_PN = "157";
"DQ<4>":   PN = "3"  !CDS_PN = "3";
"DQ<5>":   PN = "148"  !CDS_PN = "148";
"DQ<6>":   PN = "10"  !CDS_PN = "10";
"DQ<7>":   PN = "155"  !CDS_PN = "155";
"DQ<8>":   PN = "16"  !CDS_PN = "16";
"DQ<9>":   PN = "161"  !CDS_PN = "161";
"DQ<10>":   PN = "23"  !CDS_PN = "23";
"DQ<11>":   PN = "168"  !CDS_PN = "168";
"DQ<12>":   PN = "14"  !CDS_PN = "14";
"DQ<13>":   PN = "159"  !CDS_PN = "159";
"DQ<14>":   PN = "21"  !CDS_PN = "21";
"DQ<15>":   PN = "166"  !CDS_PN = "166";
"DQ<16>":   PN = "27"  !CDS_PN = "27";
"DQ<17>":   PN = "172"  !CDS_PN = "172";
"DQ<18>":   PN = "34"  !CDS_PN = "34";
"DQ<19>":   PN = "179"  !CDS_PN = "179";
"DQ<20>":   PN = "25"  !CDS_PN = "25";
"DQ<21>":   PN = "170"  !CDS_PN = "170";
"DQ<22>":   PN = "32"  !CDS_PN = "32";
"DQ<23>":   PN = "177"  !CDS_PN = "177";
"DQ<24>":   PN = "38"  !CDS_PN = "38";
"DQ<25>":   PN = "183"  !CDS_PN = "183";
"DQ<26>":   PN = "45"  !CDS_PN = "45";
"DQ<27>":   PN = "190"  !CDS_PN = "190";
"DQ<28>":   PN = "36"  !CDS_PN = "36";
"DQ<29>":   PN = "181"  !CDS_PN = "181";
"DQ<30>":   PN = "43"  !CDS_PN = "43";
"DQ<31>":   PN = "188"  !CDS_PN = "188";
"DQ<32>":   PN = "97"  !CDS_PN = "97";
"DQ<33>":   PN = "242"  !CDS_PN = "242";
"DQ<34>":   PN = "104"  !CDS_PN = "104";
"DQ<35>":   PN = "249"  !CDS_PN = "249";
"DQ<36>":   PN = "95"  !CDS_PN = "95";
"DQ<37>":   PN = "240"  !CDS_PN = "240";
"DQ<38>":   PN = "102"  !CDS_PN = "102";
"DQ<39>":   PN = "247"  !CDS_PN = "247";
"DQ<40>":   PN = "108"  !CDS_PN = "108";
"DQ<41>":   PN = "253"  !CDS_PN = "253";
"DQ<42>":   PN = "115"  !CDS_PN = "115";
"DQ<43>":   PN = "260"  !CDS_PN = "260";
"DQ<44>":   PN = "106"  !CDS_PN = "106";
"DQ<45>":   PN = "251"  !CDS_PN = "251";
"DQ<46>":   PN = "113"  !CDS_PN = "113";
"DQ<47>":   PN = "258"  !CDS_PN = "258";
"DQ<48>":   PN = "119"  !CDS_PN = "119";
"DQ<49>":   PN = "264"  !CDS_PN = "264";
"DQ<50>":   PN = "126"  !CDS_PN = "126";
"DQ<51>":   PN = "271"  !CDS_PN = "271";
"DQ<52>":   PN = "117"  !CDS_PN = "117";
"DQ<53>":   PN = "262"  !CDS_PN = "262";
"DQ<54>":   PN = "124"  !CDS_PN = "124";
"DQ<55>":   PN = "269"  !CDS_PN = "269";
"DQ<56>":   PN = "130"  !CDS_PN = "130";
"DQ<57>":   PN = "275"  !CDS_PN = "275";
"DQ<58>":   PN = "137"  !CDS_PN = "137";
"DQ<59>":   PN = "282"  !CDS_PN = "282";
"DQ<60>":   PN = "128"  !CDS_PN = "128";
"DQ<61>":   PN = "273"  !CDS_PN = "273";
"DQ<62>":   PN = "135"  !CDS_PN = "135";
"DQ<63>":   PN = "280"  !CDS_PN = "280";
"EVENT_N":   PN = "78"  !CDS_PN = "78";
"ODT<0>":   PN = "87"  !CDS_PN = "87";
"ODT<1>":   PN = "91"  !CDS_PN = "91";
"PAR":   PN = "222"  !CDS_PN = "222";
"RESET_N":   PN = "58"  !CDS_PN = "58";
"RFU<0>":   PN = "205"  !CDS_PN = "205";
"RFU<1>":   PN = "227"  !CDS_PN = "227";
"RFU<2>":   PN = "144"  !CDS_PN = "144";
"S0_N":   PN = "84"  !CDS_PN = "84";
"S1_N":   PN = "89"  !CDS_PN = "89";
"S2_N_C<0>":   PN = "93"  !CDS_PN = "93";
"S3_N_C<1>":   PN = "237"  !CDS_PN = "237";
"SA<0>":   PN = "139"  !CDS_PN = "139";
"SA<1>":   PN = "140"  !CDS_PN = "140";
"SA<2>":   PN = "238"  !CDS_PN = "238";
"SAVE_N_NC":   PN = "230"  !CDS_PN = "230";
"SCL":   PN = "141"  !CDS_PN = "141";
"SDA":   PN = "285"  !CDS_PN = "285";
"VDDSPD":   PN = "284"  !CDS_PN = "284";
"VREFCA":   PN = "146"  !CDS_PN = "146";
BODY = "SCONN288_H44441003","I75": #LOCATION = "J9T1" !CDS_LOCATION = "J9T1" #SEC = "4" !CDS_SEC = "4";
"12V<0>":   PN = "145"  !CDS_PN = "145";
"12V<1>":   PN = "1"  !CDS_PN = "1";
"VDD<0>":   PN = "236"  !CDS_PN = "236";
"VDD<1>":   PN = "233"  !CDS_PN = "233";
"VDD<2>":   PN = "231"  !CDS_PN = "231";
"VDD<3>":   PN = "229"  !CDS_PN = "229";
"VDD<4>":   PN = "226"  !CDS_PN = "226";
"VDD<5>":   PN = "223"  !CDS_PN = "223";
"VDD<6>":   PN = "220"  !CDS_PN = "220";
"VDD<7>":   PN = "217"  !CDS_PN = "217";
"VDD<8>":   PN = "215"  !CDS_PN = "215";
"VDD<9>":   PN = "212"  !CDS_PN = "212";
"VDD<10>":   PN = "209"  !CDS_PN = "209";
"VDD<11>":   PN = "206"  !CDS_PN = "206";
"VDD<12>":   PN = "204"  !CDS_PN = "204";
"VDD<13>":   PN = "92"  !CDS_PN = "92";
"VDD<14>":   PN = "90"  !CDS_PN = "90";
"VDD<15>":   PN = "88"  !CDS_PN = "88";
"VDD<16>":   PN = "85"  !CDS_PN = "85";
"VDD<17>":   PN = "83"  !CDS_PN = "83";
"VDD<18>":   PN = "80"  !CDS_PN = "80";
"VDD<19>":   PN = "76"  !CDS_PN = "76";
"VDD<20>":   PN = "73"  !CDS_PN = "73";
"VDD<21>":   PN = "70"  !CDS_PN = "70";
"VDD<22>":   PN = "67"  !CDS_PN = "67";
"VDD<23>":   PN = "64"  !CDS_PN = "64";
"VDD<24>":   PN = "61"  !CDS_PN = "61";
"VDD<25>":   PN = "59"  !CDS_PN = "59";
"VPP<0>":   PN = "287"  !CDS_PN = "287";
"VPP<1>":   PN = "286"  !CDS_PN = "286";
"VPP<2>":   PN = "288"  !CDS_PN = "288";
"VPP<3>":   PN = "143"  !CDS_PN = "143";
"VPP<4>":   PN = "142"  !CDS_PN = "142";
"VTT<0>":   PN = "221"  !CDS_PN = "221";
"VTT<1>":   PN = "77"  !CDS_PN = "77";
BODY = "SCONN288_H44441003","I120": #LOCATION = "J9T1" !CDS_LOCATION = "J9T1" #SEC = "2" !CDS_SEC = "2";
"DQS0N":   PN = "152"  !CDS_PN = "152";
"DQS0P":   PN = "153"  !CDS_PN = "153";
"DQS1N":   PN = "163"  !CDS_PN = "163";
"DQS1P":   PN = "164"  !CDS_PN = "164";
"DQS2N":   PN = "174"  !CDS_PN = "174";
"DQS2P":   PN = "175"  !CDS_PN = "175";
"DQS3N":   PN = "185"  !CDS_PN = "185";
"DQS3P":   PN = "186"  !CDS_PN = "186";
"DQS4N":   PN = "244"  !CDS_PN = "244";
"DQS4P":   PN = "245"  !CDS_PN = "245";
"DQS5N":   PN = "255"  !CDS_PN = "255";
"DQS5P":   PN = "256"  !CDS_PN = "256";
"DQS6N":   PN = "266"  !CDS_PN = "266";
"DQS6P":   PN = "267"  !CDS_PN = "267";
"DQS7N":   PN = "277"  !CDS_PN = "277";
"DQS7P":   PN = "278"  !CDS_PN = "278";
"DQS8N":   PN = "196"  !CDS_PN = "196";
"DQS8P":   PN = "197"  !CDS_PN = "197";
"DQS9N":   PN = "8"  !CDS_PN = "8";
"DQS9P":   PN = "7"  !CDS_PN = "7";
"DQS10N":   PN = "19"  !CDS_PN = "19";
"DQS10P":   PN = "18"  !CDS_PN = "18";
"DQS11N":   PN = "30"  !CDS_PN = "30";
"DQS11P":   PN = "29"  !CDS_PN = "29";
"DQS12N":   PN = "41"  !CDS_PN = "41";
"DQS12P":   PN = "40"  !CDS_PN = "40";
"DQS13N":   PN = "100"  !CDS_PN = "100";
"DQS13P":   PN = "99"  !CDS_PN = "99";
"DQS14N":   PN = "111"  !CDS_PN = "111";
"DQS14P":   PN = "110"  !CDS_PN = "110";
"DQS15N":   PN = "122"  !CDS_PN = "122";
"DQS15P":   PN = "121"  !CDS_PN = "121";
"DQS16N":   PN = "133"  !CDS_PN = "133";
"DQS16P":   PN = "132"  !CDS_PN = "132";
"DQS17N":   PN = "52"  !CDS_PN = "52";
"DQS17P":   PN = "51"  !CDS_PN = "51";
BODY = "SCONN288_H44441003","I144": #LOCATION = "J9T1" !CDS_LOCATION = "J9T1" #SEC = "3" !CDS_SEC = "3";
"VSS<0>":   PN = "283"  !CDS_PN = "283";
"VSS<1>":   PN = "281"  !CDS_PN = "281";
"VSS<2>":   PN = "279"  !CDS_PN = "279";
"VSS<3>":   PN = "276"  !CDS_PN = "276";
"VSS<4>":   PN = "274"  !CDS_PN = "274";
"VSS<5>":   PN = "272"  !CDS_PN = "272";
"VSS<6>":   PN = "270"  !CDS_PN = "270";
"VSS<7>":   PN = "268"  !CDS_PN = "268";
"VSS<8>":   PN = "265"  !CDS_PN = "265";
"VSS<9>":   PN = "263"  !CDS_PN = "263";
"VSS<10>":   PN = "261"  !CDS_PN = "261";
"VSS<11>":   PN = "259"  !CDS_PN = "259";
"VSS<12>":   PN = "257"  !CDS_PN = "257";
"VSS<13>":   PN = "254"  !CDS_PN = "254";
"VSS<14>":   PN = "252"  !CDS_PN = "252";
"VSS<15>":   PN = "250"  !CDS_PN = "250";
"VSS<16>":   PN = "248"  !CDS_PN = "248";
"VSS<17>":   PN = "246"  !CDS_PN = "246";
"VSS<18>":   PN = "243"  !CDS_PN = "243";
"VSS<19>":   PN = "241"  !CDS_PN = "241";
"VSS<20>":   PN = "239"  !CDS_PN = "239";
"VSS<21>":   PN = "202"  !CDS_PN = "202";
"VSS<22>":   PN = "200"  !CDS_PN = "200";
"VSS<23>":   PN = "198"  !CDS_PN = "198";
"VSS<24>":   PN = "195"  !CDS_PN = "195";
"VSS<25>":   PN = "193"  !CDS_PN = "193";
"VSS<26>":   PN = "191"  !CDS_PN = "191";
"VSS<27>":   PN = "189"  !CDS_PN = "189";
"VSS<28>":   PN = "187"  !CDS_PN = "187";
"VSS<29>":   PN = "184"  !CDS_PN = "184";
"VSS<30>":   PN = "182"  !CDS_PN = "182";
"VSS<31>":   PN = "180"  !CDS_PN = "180";
"VSS<32>":   PN = "178"  !CDS_PN = "178";
"VSS<33>":   PN = "176"  !CDS_PN = "176";
"VSS<34>":   PN = "173"  !CDS_PN = "173";
"VSS<35>":   PN = "171"  !CDS_PN = "171";
"VSS<36>":   PN = "169"  !CDS_PN = "169";
"VSS<37>":   PN = "167"  !CDS_PN = "167";
"VSS<38>":   PN = "165"  !CDS_PN = "165";
"VSS<39>":   PN = "162"  !CDS_PN = "162";
"VSS<40>":   PN = "160"  !CDS_PN = "160";
"VSS<41>":   PN = "158"  !CDS_PN = "158";
"VSS<42>":   PN = "156"  !CDS_PN = "156";
"VSS<43>":   PN = "154"  !CDS_PN = "154";
"VSS<44>":   PN = "151"  !CDS_PN = "151";
"VSS<45>":   PN = "149"  !CDS_PN = "149";
"VSS<46>":   PN = "147"  !CDS_PN = "147";
"VSS<47>":   PN = "138"  !CDS_PN = "138";
"VSS<48>":   PN = "136"  !CDS_PN = "136";
"VSS<49>":   PN = "134"  !CDS_PN = "134";
"VSS<50>":   PN = "131"  !CDS_PN = "131";
"VSS<51>":   PN = "129"  !CDS_PN = "129";
"VSS<52>":   PN = "127"  !CDS_PN = "127";
"VSS<53>":   PN = "125"  !CDS_PN = "125";
"VSS<54>":   PN = "123"  !CDS_PN = "123";
"VSS<55>":   PN = "120"  !CDS_PN = "120";
"VSS<56>":   PN = "118"  !CDS_PN = "118";
"VSS<57>":   PN = "116"  !CDS_PN = "116";
"VSS<58>":   PN = "114"  !CDS_PN = "114";
"VSS<59>":   PN = "112"  !CDS_PN = "112";
"VSS<60>":   PN = "109"  !CDS_PN = "109";
"VSS<61>":   PN = "107"  !CDS_PN = "107";
"VSS<62>":   PN = "105"  !CDS_PN = "105";
"VSS<63>":   PN = "103"  !CDS_PN = "103";
"VSS<64>":   PN = "101"  !CDS_PN = "101";
"VSS<65>":   PN = "98"  !CDS_PN = "98";
"VSS<66>":   PN = "96"  !CDS_PN = "96";
"VSS<67>":   PN = "94"  !CDS_PN = "94";
"VSS<68>":   PN = "57"  !CDS_PN = "57";
"VSS<69>":   PN = "55"  !CDS_PN = "55";
"VSS<70>":   PN = "53"  !CDS_PN = "53";
"VSS<71>":   PN = "50"  !CDS_PN = "50";
"VSS<72>":   PN = "48"  !CDS_PN = "48";
"VSS<73>":   PN = "46"  !CDS_PN = "46";
"VSS<74>":   PN = "44"  !CDS_PN = "44";
"VSS<75>":   PN = "42"  !CDS_PN = "42";
"VSS<76>":   PN = "39"  !CDS_PN = "39";
"VSS<77>":   PN = "37"  !CDS_PN = "37";
"VSS<78>":   PN = "35"  !CDS_PN = "35";
"VSS<79>":   PN = "33"  !CDS_PN = "33";
"VSS<80>":   PN = "31"  !CDS_PN = "31";
"VSS<81>":   PN = "28"  !CDS_PN = "28";
"VSS<82>":   PN = "26"  !CDS_PN = "26";
"VSS<83>":   PN = "24"  !CDS_PN = "24";
"VSS<84>":   PN = "22"  !CDS_PN = "22";
"VSS<85>":   PN = "20"  !CDS_PN = "20";
"VSS<86>":   PN = "17"  !CDS_PN = "17";
"VSS<87>":   PN = "15"  !CDS_PN = "15";
"VSS<88>":   PN = "13"  !CDS_PN = "13";
"VSS<89>":   PN = "11"  !CDS_PN = "11";
"VSS<90>":   PN = "9"  !CDS_PN = "9";
"VSS<91>":   PN = "6"  !CDS_PN = "6";
"VSS<92>":   PN = "4"  !CDS_PN = "4";
"VSS<93>":   PN = "2"  !CDS_PN = "2";
DRAWING = "@baseboard_fab2_lib.baseboard_fab2(sch_1):page79";
BODY = "SCONN288_H44441004","I43": #LOCATION = "J1G2" !CDS_LOCATION = "J1G2" #SEC = "3" !CDS_SEC = "3";
"VSS<0>":   PN = "283"  !CDS_PN = "283";
"VSS<1>":   PN = "281"  !CDS_PN = "281";
"VSS<2>":   PN = "279"  !CDS_PN = "279";
"VSS<3>":   PN = "276"  !CDS_PN = "276";
"VSS<4>":   PN = "274"  !CDS_PN = "274";
"VSS<5>":   PN = "272"  !CDS_PN = "272";
"VSS<6>":   PN = "270"  !CDS_PN = "270";
"VSS<7>":   PN = "268"  !CDS_PN = "268";
"VSS<8>":   PN = "265"  !CDS_PN = "265";
"VSS<9>":   PN = "263"  !CDS_PN = "263";
"VSS<10>":   PN = "261"  !CDS_PN = "261";
"VSS<11>":   PN = "259"  !CDS_PN = "259";
"VSS<12>":   PN = "257"  !CDS_PN = "257";
"VSS<13>":   PN = "254"  !CDS_PN = "254";
"VSS<14>":   PN = "252"  !CDS_PN = "252";
"VSS<15>":   PN = "250"  !CDS_PN = "250";
"VSS<16>":   PN = "248"  !CDS_PN = "248";
"VSS<17>":   PN = "246"  !CDS_PN = "246";
"VSS<18>":   PN = "243"  !CDS_PN = "243";
"VSS<19>":   PN = "241"  !CDS_PN = "241";
"VSS<20>":   PN = "239"  !CDS_PN = "239";
"VSS<21>":   PN = "202"  !CDS_PN = "202";
"VSS<22>":   PN = "200"  !CDS_PN = "200";
"VSS<23>":   PN = "198"  !CDS_PN = "198";
"VSS<24>":   PN = "195"  !CDS_PN = "195";
"VSS<25>":   PN = "193"  !CDS_PN = "193";
"VSS<26>":   PN = "191"  !CDS_PN = "191";
"VSS<27>":   PN = "189"  !CDS_PN = "189";
"VSS<28>":   PN = "187"  !CDS_PN = "187";
"VSS<29>":   PN = "184"  !CDS_PN = "184";
"VSS<30>":   PN = "182"  !CDS_PN = "182";
"VSS<31>":   PN = "180"  !CDS_PN = "180";
"VSS<32>":   PN = "178"  !CDS_PN = "178";
"VSS<33>":   PN = "176"  !CDS_PN = "176";
"VSS<34>":   PN = "173"  !CDS_PN = "173";
"VSS<35>":   PN = "171"  !CDS_PN = "171";
"VSS<36>":   PN = "169"  !CDS_PN = "169";
"VSS<37>":   PN = "167"  !CDS_PN = "167";
"VSS<38>":   PN = "165"  !CDS_PN = "165";
"VSS<39>":   PN = "162"  !CDS_PN = "162";
"VSS<40>":   PN = "160"  !CDS_PN = "160";
"VSS<41>":   PN = "158"  !CDS_PN = "158";
"VSS<42>":   PN = "156"  !CDS_PN = "156";
"VSS<43>":   PN = "154"  !CDS_PN = "154";
"VSS<44>":   PN = "151"  !CDS_PN = "151";
"VSS<45>":   PN = "149"  !CDS_PN = "149";
"VSS<46>":   PN = "147"  !CDS_PN = "147";
"VSS<47>":   PN = "138"  !CDS_PN = "138";
"VSS<48>":   PN = "136"  !CDS_PN = "136";
"VSS<49>":   PN = "134"  !CDS_PN = "134";
"VSS<50>":   PN = "131"  !CDS_PN = "131";
"VSS<51>":   PN = "129"  !CDS_PN = "129";
"VSS<52>":   PN = "127"  !CDS_PN = "127";
"VSS<53>":   PN = "125"  !CDS_PN = "125";
"VSS<54>":   PN = "123"  !CDS_PN = "123";
"VSS<55>":   PN = "120"  !CDS_PN = "120";
"VSS<56>":   PN = "118"  !CDS_PN = "118";
"VSS<57>":   PN = "116"  !CDS_PN = "116";
"VSS<58>":   PN = "114"  !CDS_PN = "114";
"VSS<59>":   PN = "112"  !CDS_PN = "112";
"VSS<60>":   PN = "109"  !CDS_PN = "109";
"VSS<61>":   PN = "107"  !CDS_PN = "107";
"VSS<62>":   PN = "105"  !CDS_PN = "105";
"VSS<63>":   PN = "103"  !CDS_PN = "103";
"VSS<64>":   PN = "101"  !CDS_PN = "101";
"VSS<65>":   PN = "98"  !CDS_PN = "98";
"VSS<66>":   PN = "96"  !CDS_PN = "96";
"VSS<67>":   PN = "94"  !CDS_PN = "94";
"VSS<68>":   PN = "57"  !CDS_PN = "57";
"VSS<69>":   PN = "55"  !CDS_PN = "55";
"VSS<70>":   PN = "53"  !CDS_PN = "53";
"VSS<71>":   PN = "50"  !CDS_PN = "50";
"VSS<72>":   PN = "48"  !CDS_PN = "48";
"VSS<73>":   PN = "46"  !CDS_PN = "46";
"VSS<74>":   PN = "44"  !CDS_PN = "44";
"VSS<75>":   PN = "42"  !CDS_PN = "42";
"VSS<76>":   PN = "39"  !CDS_PN = "39";
"VSS<77>":   PN = "37"  !CDS_PN = "37";
"VSS<78>":   PN = "35"  !CDS_PN = "35";
"VSS<79>":   PN = "33"  !CDS_PN = "33";
"VSS<80>":   PN = "31"  !CDS_PN = "31";
"VSS<81>":   PN = "28"  !CDS_PN = "28";
"VSS<82>":   PN = "26"  !CDS_PN = "26";
"VSS<83>":   PN = "24"  !CDS_PN = "24";
"VSS<84>":   PN = "22"  !CDS_PN = "22";
"VSS<85>":   PN = "20"  !CDS_PN = "20";
"VSS<86>":   PN = "17"  !CDS_PN = "17";
"VSS<87>":   PN = "15"  !CDS_PN = "15";
"VSS<88>":   PN = "13"  !CDS_PN = "13";
"VSS<89>":   PN = "11"  !CDS_PN = "11";
"VSS<90>":   PN = "9"  !CDS_PN = "9";
"VSS<91>":   PN = "6"  !CDS_PN = "6";
"VSS<92>":   PN = "4"  !CDS_PN = "4";
"VSS<93>":   PN = "2"  !CDS_PN = "2";
BODY = "SCONN288_H44441004","I64": #LOCATION = "J1G2" !CDS_LOCATION = "J1G2" #SEC = "2" !CDS_SEC = "2";
"DQS0N":   PN = "152"  !CDS_PN = "152";
"DQS0P":   PN = "153"  !CDS_PN = "153";
"DQS1N":   PN = "163"  !CDS_PN = "163";
"DQS1P":   PN = "164"  !CDS_PN = "164";
"DQS2N":   PN = "174"  !CDS_PN = "174";
"DQS2P":   PN = "175"  !CDS_PN = "175";
"DQS3N":   PN = "185"  !CDS_PN = "185";
"DQS3P":   PN = "186"  !CDS_PN = "186";
"DQS4N":   PN = "244"  !CDS_PN = "244";
"DQS4P":   PN = "245"  !CDS_PN = "245";
"DQS5N":   PN = "255"  !CDS_PN = "255";
"DQS5P":   PN = "256"  !CDS_PN = "256";
"DQS6N":   PN = "266"  !CDS_PN = "266";
"DQS6P":   PN = "267"  !CDS_PN = "267";
"DQS7N":   PN = "277"  !CDS_PN = "277";
"DQS7P":   PN = "278"  !CDS_PN = "278";
"DQS8N":   PN = "196"  !CDS_PN = "196";
"DQS8P":   PN = "197"  !CDS_PN = "197";
"DQS9N":   PN = "8"  !CDS_PN = "8";
"DQS9P":   PN = "7"  !CDS_PN = "7";
"DQS10N":   PN = "19"  !CDS_PN = "19";
"DQS10P":   PN = "18"  !CDS_PN = "18";
"DQS11N":   PN = "30"  !CDS_PN = "30";
"DQS11P":   PN = "29"  !CDS_PN = "29";
"DQS12N":   PN = "41"  !CDS_PN = "41";
"DQS12P":   PN = "40"  !CDS_PN = "40";
"DQS13N":   PN = "100"  !CDS_PN = "100";
"DQS13P":   PN = "99"  !CDS_PN = "99";
"DQS14N":   PN = "111"  !CDS_PN = "111";
"DQS14P":   PN = "110"  !CDS_PN = "110";
"DQS15N":   PN = "122"  !CDS_PN = "122";
"DQS15P":   PN = "121"  !CDS_PN = "121";
"DQS16N":   PN = "133"  !CDS_PN = "133";
"DQS16P":   PN = "132"  !CDS_PN = "132";
"DQS17N":   PN = "52"  !CDS_PN = "52";
"DQS17P":   PN = "51"  !CDS_PN = "51";
BODY = "SCONN288_H44441004","I111": #LOCATION = "J1G2" !CDS_LOCATION = "J1G2" #SEC = "1" !CDS_SEC = "1";
"A0":   PN = "79"  !CDS_PN = "79";
"A1":   PN = "72"  !CDS_PN = "72";
"A2":   PN = "216"  !CDS_PN = "216";
"A3":   PN = "71"  !CDS_PN = "71";
"A4":   PN = "214"  !CDS_PN = "214";
"A5":   PN = "213"  !CDS_PN = "213";
"A6":   PN = "69"  !CDS_PN = "69";
"A7":   PN = "211"  !CDS_PN = "211";
"A8":   PN = "68"  !CDS_PN = "68";
"A9":   PN = "66"  !CDS_PN = "66";
"A10":   PN = "225"  !CDS_PN = "225";
"A11":   PN = "210"  !CDS_PN = "210";
"A12":   PN = "65"  !CDS_PN = "65";
"A13":   PN = "232"  !CDS_PN = "232";
"A14_WE_N":   PN = "228"  !CDS_PN = "228";
"A15_CAS_N":   PN = "86"  !CDS_PN = "86";
"A16_RAS_N":   PN = "82"  !CDS_PN = "82";
"A17":   PN = "234"  !CDS_PN = "234";
"ACT_N":   PN = "62"  !CDS_PN = "62";
"ALERT_N":   PN = "208"  !CDS_PN = "208";
"BA<0>":   PN = "81"  !CDS_PN = "81";
"BA<1>":   PN = "224"  !CDS_PN = "224";
"BG<0>":   PN = "63"  !CDS_PN = "63";
"BG<1>":   PN = "207"  !CDS_PN = "207";
"C<2>":   PN = "235"  !CDS_PN = "235";
"CB<0>":   PN = "49"  !CDS_PN = "49";
"CB<1>":   PN = "194"  !CDS_PN = "194";
"CB<2>":   PN = "56"  !CDS_PN = "56";
"CB<3>":   PN = "201"  !CDS_PN = "201";
"CB<4>":   PN = "47"  !CDS_PN = "47";
"CB<5>":   PN = "192"  !CDS_PN = "192";
"CB<6>":   PN = "54"  !CDS_PN = "54";
"CB<7>":   PN = "199"  !CDS_PN = "199";
"CK0N":   PN = "75"  !CDS_PN = "75";
"CK0P":   PN = "74"  !CDS_PN = "74";
"CK1N":   PN = "219"  !CDS_PN = "219";
"CK1P":   PN = "218"  !CDS_PN = "218";
"CKE<0>":   PN = "60"  !CDS_PN = "60";
"CKE<1>":   PN = "203"  !CDS_PN = "203";
"DQ<0>":   PN = "5"  !CDS_PN = "5";
"DQ<1>":   PN = "150"  !CDS_PN = "150";
"DQ<2>":   PN = "12"  !CDS_PN = "12";
"DQ<3>":   PN = "157"  !CDS_PN = "157";
"DQ<4>":   PN = "3"  !CDS_PN = "3";
"DQ<5>":   PN = "148"  !CDS_PN = "148";
"DQ<6>":   PN = "10"  !CDS_PN = "10";
"DQ<7>":   PN = "155"  !CDS_PN = "155";
"DQ<8>":   PN = "16"  !CDS_PN = "16";
"DQ<9>":   PN = "161"  !CDS_PN = "161";
"DQ<10>":   PN = "23"  !CDS_PN = "23";
"DQ<11>":   PN = "168"  !CDS_PN = "168";
"DQ<12>":   PN = "14"  !CDS_PN = "14";
"DQ<13>":   PN = "159"  !CDS_PN = "159";
"DQ<14>":   PN = "21"  !CDS_PN = "21";
"DQ<15>":   PN = "166"  !CDS_PN = "166";
"DQ<16>":   PN = "27"  !CDS_PN = "27";
"DQ<17>":   PN = "172"  !CDS_PN = "172";
"DQ<18>":   PN = "34"  !CDS_PN = "34";
"DQ<19>":   PN = "179"  !CDS_PN = "179";
"DQ<20>":   PN = "25"  !CDS_PN = "25";
"DQ<21>":   PN = "170"  !CDS_PN = "170";
"DQ<22>":   PN = "32"  !CDS_PN = "32";
"DQ<23>":   PN = "177"  !CDS_PN = "177";
"DQ<24>":   PN = "38"  !CDS_PN = "38";
"DQ<25>":   PN = "183"  !CDS_PN = "183";
"DQ<26>":   PN = "45"  !CDS_PN = "45";
"DQ<27>":   PN = "190"  !CDS_PN = "190";
"DQ<28>":   PN = "36"  !CDS_PN = "36";
"DQ<29>":   PN = "181"  !CDS_PN = "181";
"DQ<30>":   PN = "43"  !CDS_PN = "43";
"DQ<31>":   PN = "188"  !CDS_PN = "188";
"DQ<32>":   PN = "97"  !CDS_PN = "97";
"DQ<33>":   PN = "242"  !CDS_PN = "242";
"DQ<34>":   PN = "104"  !CDS_PN = "104";
"DQ<35>":   PN = "249"  !CDS_PN = "249";
"DQ<36>":   PN = "95"  !CDS_PN = "95";
"DQ<37>":   PN = "240"  !CDS_PN = "240";
"DQ<38>":   PN = "102"  !CDS_PN = "102";
"DQ<39>":   PN = "247"  !CDS_PN = "247";
"DQ<40>":   PN = "108"  !CDS_PN = "108";
"DQ<41>":   PN = "253"  !CDS_PN = "253";
"DQ<42>":   PN = "115"  !CDS_PN = "115";
"DQ<43>":   PN = "260"  !CDS_PN = "260";
"DQ<44>":   PN = "106"  !CDS_PN = "106";
"DQ<45>":   PN = "251"  !CDS_PN = "251";
"DQ<46>":   PN = "113"  !CDS_PN = "113";
"DQ<47>":   PN = "258"  !CDS_PN = "258";
"DQ<48>":   PN = "119"  !CDS_PN = "119";
"DQ<49>":   PN = "264"  !CDS_PN = "264";
"DQ<50>":   PN = "126"  !CDS_PN = "126";
"DQ<51>":   PN = "271"  !CDS_PN = "271";
"DQ<52>":   PN = "117"  !CDS_PN = "117";
"DQ<53>":   PN = "262"  !CDS_PN = "262";
"DQ<54>":   PN = "124"  !CDS_PN = "124";
"DQ<55>":   PN = "269"  !CDS_PN = "269";
"DQ<56>":   PN = "130"  !CDS_PN = "130";
"DQ<57>":   PN = "275"  !CDS_PN = "275";
"DQ<58>":   PN = "137"  !CDS_PN = "137";
"DQ<59>":   PN = "282"  !CDS_PN = "282";
"DQ<60>":   PN = "128"  !CDS_PN = "128";
"DQ<61>":   PN = "273"  !CDS_PN = "273";
"DQ<62>":   PN = "135"  !CDS_PN = "135";
"DQ<63>":   PN = "280"  !CDS_PN = "280";
"EVENT_N":   PN = "78"  !CDS_PN = "78";
"ODT<0>":   PN = "87"  !CDS_PN = "87";
"ODT<1>":   PN = "91"  !CDS_PN = "91";
"PAR":   PN = "222"  !CDS_PN = "222";
"RESET_N":   PN = "58"  !CDS_PN = "58";
"RFU<0>":   PN = "205"  !CDS_PN = "205";
"RFU<1>":   PN = "227"  !CDS_PN = "227";
"RFU<2>":   PN = "144"  !CDS_PN = "144";
"S0_N":   PN = "84"  !CDS_PN = "84";
"S1_N":   PN = "89"  !CDS_PN = "89";
"S2_N_C<0>":   PN = "93"  !CDS_PN = "93";
"S3_N_C<1>":   PN = "237"  !CDS_PN = "237";
"SA<0>":   PN = "139"  !CDS_PN = "139";
"SA<1>":   PN = "140"  !CDS_PN = "140";
"SA<2>":   PN = "238"  !CDS_PN = "238";
"SAVE_N_NC":   PN = "230"  !CDS_PN = "230";
"SCL":   PN = "141"  !CDS_PN = "141";
"SDA":   PN = "285"  !CDS_PN = "285";
"VDDSPD":   PN = "284"  !CDS_PN = "284";
"VREFCA":   PN = "146"  !CDS_PN = "146";
BODY = "SCONN288_H44441004","I169": #LOCATION = "J1G2" !CDS_LOCATION = "J1G2" #SEC = "4" !CDS_SEC = "4";
"12V<0>":   PN = "145"  !CDS_PN = "145";
"12V<1>":   PN = "1"  !CDS_PN = "1";
"VDD<0>":   PN = "236"  !CDS_PN = "236";
"VDD<1>":   PN = "233"  !CDS_PN = "233";
"VDD<2>":   PN = "231"  !CDS_PN = "231";
"VDD<3>":   PN = "229"  !CDS_PN = "229";
"VDD<4>":   PN = "226"  !CDS_PN = "226";
"VDD<5>":   PN = "223"  !CDS_PN = "223";
"VDD<6>":   PN = "220"  !CDS_PN = "220";
"VDD<7>":   PN = "217"  !CDS_PN = "217";
"VDD<8>":   PN = "215"  !CDS_PN = "215";
"VDD<9>":   PN = "212"  !CDS_PN = "212";
"VDD<10>":   PN = "209"  !CDS_PN = "209";
"VDD<11>":   PN = "206"  !CDS_PN = "206";
"VDD<12>":   PN = "204"  !CDS_PN = "204";
"VDD<13>":   PN = "92"  !CDS_PN = "92";
"VDD<14>":   PN = "90"  !CDS_PN = "90";
"VDD<15>":   PN = "88"  !CDS_PN = "88";
"VDD<16>":   PN = "85"  !CDS_PN = "85";
"VDD<17>":   PN = "83"  !CDS_PN = "83";
"VDD<18>":   PN = "80"  !CDS_PN = "80";
"VDD<19>":   PN = "76"  !CDS_PN = "76";
"VDD<20>":   PN = "73"  !CDS_PN = "73";
"VDD<21>":   PN = "70"  !CDS_PN = "70";
"VDD<22>":   PN = "67"  !CDS_PN = "67";
"VDD<23>":   PN = "64"  !CDS_PN = "64";
"VDD<24>":   PN = "61"  !CDS_PN = "61";
"VDD<25>":   PN = "59"  !CDS_PN = "59";
"VPP<0>":   PN = "287"  !CDS_PN = "287";
"VPP<1>":   PN = "286"  !CDS_PN = "286";
"VPP<2>":   PN = "288"  !CDS_PN = "288";
"VPP<3>":   PN = "143"  !CDS_PN = "143";
"VPP<4>":   PN = "142"  !CDS_PN = "142";
"VTT<0>":   PN = "221"  !CDS_PN = "221";
"VTT<1>":   PN = "77"  !CDS_PN = "77";
BODY = "CAP_A","I178": #LOCATION = "C9U7" !CDS_LOCATION = "C9U7" &SEC = "1" #&CDS_SEC = "1";
"A":   PN = "1"  !CDS_PN = "1";
"B":   PN = "2"  !CDS_PN = "2";
DRAWING = "@baseboard_fab2_lib.baseboard_fab2(sch_1):page80";
BODY = "CAP_A","I3": #LOCATION = "C1G10" !CDS_LOCATION = "C1G10" &SEC = "1" #&CDS_SEC = "1";
"A":   PN = "1"  !CDS_PN = "1";
"B":   PN = "2"  !CDS_PN = "2";
BODY = "SCONN288_H44441003","I24": #LOCATION = "J9U1" !CDS_LOCATION = "J9U1" #SEC = "1" !CDS_SEC = "1";
"A0":   PN = "79"  !CDS_PN = "79";
"A1":   PN = "72"  !CDS_PN = "72";
"A2":   PN = "216"  !CDS_PN = "216";
"A3":   PN = "71"  !CDS_PN = "71";
"A4":   PN = "214"  !CDS_PN = "214";
"A5":   PN = "213"  !CDS_PN = "213";
"A6":   PN = "69"  !CDS_PN = "69";
"A7":   PN = "211"  !CDS_PN = "211";
"A8":   PN = "68"  !CDS_PN = "68";
"A9":   PN = "66"  !CDS_PN = "66";
"A10":   PN = "225"  !CDS_PN = "225";
"A11":   PN = "210"  !CDS_PN = "210";
"A12":   PN = "65"  !CDS_PN = "65";
"A13":   PN = "232"  !CDS_PN = "232";
"A14_WE_N":   PN = "228"  !CDS_PN = "228";
"A15_CAS_N":   PN = "86"  !CDS_PN = "86";
"A16_RAS_N":   PN = "82"  !CDS_PN = "82";
"A17":   PN = "234"  !CDS_PN = "234";
"ACT_N":   PN = "62"  !CDS_PN = "62";
"ALERT_N":   PN = "208"  !CDS_PN = "208";
"BA<0>":   PN = "81"  !CDS_PN = "81";
"BA<1>":   PN = "224"  !CDS_PN = "224";
"BG<0>":   PN = "63"  !CDS_PN = "63";
"BG<1>":   PN = "207"  !CDS_PN = "207";
"C<2>":   PN = "235"  !CDS_PN = "235";
"CB<0>":   PN = "49"  !CDS_PN = "49";
"CB<1>":   PN = "194"  !CDS_PN = "194";
"CB<2>":   PN = "56"  !CDS_PN = "56";
"CB<3>":   PN = "201"  !CDS_PN = "201";
"CB<4>":   PN = "47"  !CDS_PN = "47";
"CB<5>":   PN = "192"  !CDS_PN = "192";
"CB<6>":   PN = "54"  !CDS_PN = "54";
"CB<7>":   PN = "199"  !CDS_PN = "199";
"CK0N":   PN = "75"  !CDS_PN = "75";
"CK0P":   PN = "74"  !CDS_PN = "74";
"CK1N":   PN = "219"  !CDS_PN = "219";
"CK1P":   PN = "218"  !CDS_PN = "218";
"CKE<0>":   PN = "60"  !CDS_PN = "60";
"CKE<1>":   PN = "203"  !CDS_PN = "203";
"DQ<0>":   PN = "5"  !CDS_PN = "5";
"DQ<1>":   PN = "150"  !CDS_PN = "150";
"DQ<2>":   PN = "12"  !CDS_PN = "12";
"DQ<3>":   PN = "157"  !CDS_PN = "157";
"DQ<4>":   PN = "3"  !CDS_PN = "3";
"DQ<5>":   PN = "148"  !CDS_PN = "148";
"DQ<6>":   PN = "10"  !CDS_PN = "10";
"DQ<7>":   PN = "155"  !CDS_PN = "155";
"DQ<8>":   PN = "16"  !CDS_PN = "16";
"DQ<9>":   PN = "161"  !CDS_PN = "161";
"DQ<10>":   PN = "23"  !CDS_PN = "23";
"DQ<11>":   PN = "168"  !CDS_PN = "168";
"DQ<12>":   PN = "14"  !CDS_PN = "14";
"DQ<13>":   PN = "159"  !CDS_PN = "159";
"DQ<14>":   PN = "21"  !CDS_PN = "21";
"DQ<15>":   PN = "166"  !CDS_PN = "166";
"DQ<16>":   PN = "27"  !CDS_PN = "27";
"DQ<17>":   PN = "172"  !CDS_PN = "172";
"DQ<18>":   PN = "34"  !CDS_PN = "34";
"DQ<19>":   PN = "179"  !CDS_PN = "179";
"DQ<20>":   PN = "25"  !CDS_PN = "25";
"DQ<21>":   PN = "170"  !CDS_PN = "170";
"DQ<22>":   PN = "32"  !CDS_PN = "32";
"DQ<23>":   PN = "177"  !CDS_PN = "177";
"DQ<24>":   PN = "38"  !CDS_PN = "38";
"DQ<25>":   PN = "183"  !CDS_PN = "183";
"DQ<26>":   PN = "45"  !CDS_PN = "45";
"DQ<27>":   PN = "190"  !CDS_PN = "190";
"DQ<28>":   PN = "36"  !CDS_PN = "36";
"DQ<29>":   PN = "181"  !CDS_PN = "181";
"DQ<30>":   PN = "43"  !CDS_PN = "43";
"DQ<31>":   PN = "188"  !CDS_PN = "188";
"DQ<32>":   PN = "97"  !CDS_PN = "97";
"DQ<33>":   PN = "242"  !CDS_PN = "242";
"DQ<34>":   PN = "104"  !CDS_PN = "104";
"DQ<35>":   PN = "249"  !CDS_PN = "249";
"DQ<36>":   PN = "95"  !CDS_PN = "95";
"DQ<37>":   PN = "240"  !CDS_PN = "240";
"DQ<38>":   PN = "102"  !CDS_PN = "102";
"DQ<39>":   PN = "247"  !CDS_PN = "247";
"DQ<40>":   PN = "108"  !CDS_PN = "108";
"DQ<41>":   PN = "253"  !CDS_PN = "253";
"DQ<42>":   PN = "115"  !CDS_PN = "115";
"DQ<43>":   PN = "260"  !CDS_PN = "260";
"DQ<44>":   PN = "106"  !CDS_PN = "106";
"DQ<45>":   PN = "251"  !CDS_PN = "251";
"DQ<46>":   PN = "113"  !CDS_PN = "113";
"DQ<47>":   PN = "258"  !CDS_PN = "258";
"DQ<48>":   PN = "119"  !CDS_PN = "119";
"DQ<49>":   PN = "264"  !CDS_PN = "264";
"DQ<50>":   PN = "126"  !CDS_PN = "126";
"DQ<51>":   PN = "271"  !CDS_PN = "271";
"DQ<52>":   PN = "117"  !CDS_PN = "117";
"DQ<53>":   PN = "262"  !CDS_PN = "262";
"DQ<54>":   PN = "124"  !CDS_PN = "124";
"DQ<55>":   PN = "269"  !CDS_PN = "269";
"DQ<56>":   PN = "130"  !CDS_PN = "130";
"DQ<57>":   PN = "275"  !CDS_PN = "275";
"DQ<58>":   PN = "137"  !CDS_PN = "137";
"DQ<59>":   PN = "282"  !CDS_PN = "282";
"DQ<60>":   PN = "128"  !CDS_PN = "128";
"DQ<61>":   PN = "273"  !CDS_PN = "273";
"DQ<62>":   PN = "135"  !CDS_PN = "135";
"DQ<63>":   PN = "280"  !CDS_PN = "280";
"EVENT_N":   PN = "78"  !CDS_PN = "78";
"ODT<0>":   PN = "87"  !CDS_PN = "87";
"ODT<1>":   PN = "91"  !CDS_PN = "91";
"PAR":   PN = "222"  !CDS_PN = "222";
"RESET_N":   PN = "58"  !CDS_PN = "58";
"RFU<0>":   PN = "205"  !CDS_PN = "205";
"RFU<1>":   PN = "227"  !CDS_PN = "227";
"RFU<2>":   PN = "144"  !CDS_PN = "144";
"S0_N":   PN = "84"  !CDS_PN = "84";
"S1_N":   PN = "89"  !CDS_PN = "89";
"S2_N_C<0>":   PN = "93"  !CDS_PN = "93";
"S3_N_C<1>":   PN = "237"  !CDS_PN = "237";
"SA<0>":   PN = "139"  !CDS_PN = "139";
"SA<1>":   PN = "140"  !CDS_PN = "140";
"SA<2>":   PN = "238"  !CDS_PN = "238";
"SAVE_N_NC":   PN = "230"  !CDS_PN = "230";
"SCL":   PN = "141"  !CDS_PN = "141";
"SDA":   PN = "285"  !CDS_PN = "285";
"VDDSPD":   PN = "284"  !CDS_PN = "284";
"VREFCA":   PN = "146"  !CDS_PN = "146";
BODY = "SCONN288_H44441003","I56": #LOCATION = "J9U1" !CDS_LOCATION = "J9U1" #SEC = "4" !CDS_SEC = "4";
"12V<0>":   PN = "145"  !CDS_PN = "145";
"12V<1>":   PN = "1"  !CDS_PN = "1";
"VDD<0>":   PN = "236"  !CDS_PN = "236";
"VDD<1>":   PN = "233"  !CDS_PN = "233";
"VDD<2>":   PN = "231"  !CDS_PN = "231";
"VDD<3>":   PN = "229"  !CDS_PN = "229";
"VDD<4>":   PN = "226"  !CDS_PN = "226";
"VDD<5>":   PN = "223"  !CDS_PN = "223";
"VDD<6>":   PN = "220"  !CDS_PN = "220";
"VDD<7>":   PN = "217"  !CDS_PN = "217";
"VDD<8>":   PN = "215"  !CDS_PN = "215";
"VDD<9>":   PN = "212"  !CDS_PN = "212";
"VDD<10>":   PN = "209"  !CDS_PN = "209";
"VDD<11>":   PN = "206"  !CDS_PN = "206";
"VDD<12>":   PN = "204"  !CDS_PN = "204";
"VDD<13>":   PN = "92"  !CDS_PN = "92";
"VDD<14>":   PN = "90"  !CDS_PN = "90";
"VDD<15>":   PN = "88"  !CDS_PN = "88";
"VDD<16>":   PN = "85"  !CDS_PN = "85";
"VDD<17>":   PN = "83"  !CDS_PN = "83";
"VDD<18>":   PN = "80"  !CDS_PN = "80";
"VDD<19>":   PN = "76"  !CDS_PN = "76";
"VDD<20>":   PN = "73"  !CDS_PN = "73";
"VDD<21>":   PN = "70"  !CDS_PN = "70";
"VDD<22>":   PN = "67"  !CDS_PN = "67";
"VDD<23>":   PN = "64"  !CDS_PN = "64";
"VDD<24>":   PN = "61"  !CDS_PN = "61";
"VDD<25>":   PN = "59"  !CDS_PN = "59";
"VPP<0>":   PN = "287"  !CDS_PN = "287";
"VPP<1>":   PN = "286"  !CDS_PN = "286";
"VPP<2>":   PN = "288"  !CDS_PN = "288";
"VPP<3>":   PN = "143"  !CDS_PN = "143";
"VPP<4>":   PN = "142"  !CDS_PN = "142";
"VTT<0>":   PN = "221"  !CDS_PN = "221";
"VTT<1>":   PN = "77"  !CDS_PN = "77";
BODY = "SCONN288_H44441003","I101": #LOCATION = "J9U1" !CDS_LOCATION = "J9U1" #SEC = "2" !CDS_SEC = "2";
"DQS0N":   PN = "152"  !CDS_PN = "152";
"DQS0P":   PN = "153"  !CDS_PN = "153";
"DQS1N":   PN = "163"  !CDS_PN = "163";
"DQS1P":   PN = "164"  !CDS_PN = "164";
"DQS2N":   PN = "174"  !CDS_PN = "174";
"DQS2P":   PN = "175"  !CDS_PN = "175";
"DQS3N":   PN = "185"  !CDS_PN = "185";
"DQS3P":   PN = "186"  !CDS_PN = "186";
"DQS4N":   PN = "244"  !CDS_PN = "244";
"DQS4P":   PN = "245"  !CDS_PN = "245";
"DQS5N":   PN = "255"  !CDS_PN = "255";
"DQS5P":   PN = "256"  !CDS_PN = "256";
"DQS6N":   PN = "266"  !CDS_PN = "266";
"DQS6P":   PN = "267"  !CDS_PN = "267";
"DQS7N":   PN = "277"  !CDS_PN = "277";
"DQS7P":   PN = "278"  !CDS_PN = "278";
"DQS8N":   PN = "196"  !CDS_PN = "196";
"DQS8P":   PN = "197"  !CDS_PN = "197";
"DQS9N":   PN = "8"  !CDS_PN = "8";
"DQS9P":   PN = "7"  !CDS_PN = "7";
"DQS10N":   PN = "19"  !CDS_PN = "19";
"DQS10P":   PN = "18"  !CDS_PN = "18";
"DQS11N":   PN = "30"  !CDS_PN = "30";
"DQS11P":   PN = "29"  !CDS_PN = "29";
"DQS12N":   PN = "41"  !CDS_PN = "41";
"DQS12P":   PN = "40"  !CDS_PN = "40";
"DQS13N":   PN = "100"  !CDS_PN = "100";
"DQS13P":   PN = "99"  !CDS_PN = "99";
"DQS14N":   PN = "111"  !CDS_PN = "111";
"DQS14P":   PN = "110"  !CDS_PN = "110";
"DQS15N":   PN = "122"  !CDS_PN = "122";
"DQS15P":   PN = "121"  !CDS_PN = "121";
"DQS16N":   PN = "133"  !CDS_PN = "133";
"DQS16P":   PN = "132"  !CDS_PN = "132";
"DQS17N":   PN = "52"  !CDS_PN = "52";
"DQS17P":   PN = "51"  !CDS_PN = "51";
BODY = "SCONN288_H44441003","I138": #LOCATION = "J9U1" !CDS_LOCATION = "J9U1" #SEC = "3" !CDS_SEC = "3";
"VSS<0>":   PN = "283"  !CDS_PN = "283";
"VSS<1>":   PN = "281"  !CDS_PN = "281";
"VSS<2>":   PN = "279"  !CDS_PN = "279";
"VSS<3>":   PN = "276"  !CDS_PN = "276";
"VSS<4>":   PN = "274"  !CDS_PN = "274";
"VSS<5>":   PN = "272"  !CDS_PN = "272";
"VSS<6>":   PN = "270"  !CDS_PN = "270";
"VSS<7>":   PN = "268"  !CDS_PN = "268";
"VSS<8>":   PN = "265"  !CDS_PN = "265";
"VSS<9>":   PN = "263"  !CDS_PN = "263";
"VSS<10>":   PN = "261"  !CDS_PN = "261";
"VSS<11>":   PN = "259"  !CDS_PN = "259";
"VSS<12>":   PN = "257"  !CDS_PN = "257";
"VSS<13>":   PN = "254"  !CDS_PN = "254";
"VSS<14>":   PN = "252"  !CDS_PN = "252";
"VSS<15>":   PN = "250"  !CDS_PN = "250";
"VSS<16>":   PN = "248"  !CDS_PN = "248";
"VSS<17>":   PN = "246"  !CDS_PN = "246";
"VSS<18>":   PN = "243"  !CDS_PN = "243";
"VSS<19>":   PN = "241"  !CDS_PN = "241";
"VSS<20>":   PN = "239"  !CDS_PN = "239";
"VSS<21>":   PN = "202"  !CDS_PN = "202";
"VSS<22>":   PN = "200"  !CDS_PN = "200";
"VSS<23>":   PN = "198"  !CDS_PN = "198";
"VSS<24>":   PN = "195"  !CDS_PN = "195";
"VSS<25>":   PN = "193"  !CDS_PN = "193";
"VSS<26>":   PN = "191"  !CDS_PN = "191";
"VSS<27>":   PN = "189"  !CDS_PN = "189";
"VSS<28>":   PN = "187"  !CDS_PN = "187";
"VSS<29>":   PN = "184"  !CDS_PN = "184";
"VSS<30>":   PN = "182"  !CDS_PN = "182";
"VSS<31>":   PN = "180"  !CDS_PN = "180";
"VSS<32>":   PN = "178"  !CDS_PN = "178";
"VSS<33>":   PN = "176"  !CDS_PN = "176";
"VSS<34>":   PN = "173"  !CDS_PN = "173";
"VSS<35>":   PN = "171"  !CDS_PN = "171";
"VSS<36>":   PN = "169"  !CDS_PN = "169";
"VSS<37>":   PN = "167"  !CDS_PN = "167";
"VSS<38>":   PN = "165"  !CDS_PN = "165";
"VSS<39>":   PN = "162"  !CDS_PN = "162";
"VSS<40>":   PN = "160"  !CDS_PN = "160";
"VSS<41>":   PN = "158"  !CDS_PN = "158";
"VSS<42>":   PN = "156"  !CDS_PN = "156";
"VSS<43>":   PN = "154"  !CDS_PN = "154";
"VSS<44>":   PN = "151"  !CDS_PN = "151";
"VSS<45>":   PN = "149"  !CDS_PN = "149";
"VSS<46>":   PN = "147"  !CDS_PN = "147";
"VSS<47>":   PN = "138"  !CDS_PN = "138";
"VSS<48>":   PN = "136"  !CDS_PN = "136";
"VSS<49>":   PN = "134"  !CDS_PN = "134";
"VSS<50>":   PN = "131"  !CDS_PN = "131";
"VSS<51>":   PN = "129"  !CDS_PN = "129";
"VSS<52>":   PN = "127"  !CDS_PN = "127";
"VSS<53>":   PN = "125"  !CDS_PN = "125";
"VSS<54>":   PN = "123"  !CDS_PN = "123";
"VSS<55>":   PN = "120"  !CDS_PN = "120";
"VSS<56>":   PN = "118"  !CDS_PN = "118";
"VSS<57>":   PN = "116"  !CDS_PN = "116";
"VSS<58>":   PN = "114"  !CDS_PN = "114";
"VSS<59>":   PN = "112"  !CDS_PN = "112";
"VSS<60>":   PN = "109"  !CDS_PN = "109";
"VSS<61>":   PN = "107"  !CDS_PN = "107";
"VSS<62>":   PN = "105"  !CDS_PN = "105";
"VSS<63>":   PN = "103"  !CDS_PN = "103";
"VSS<64>":   PN = "101"  !CDS_PN = "101";
"VSS<65>":   PN = "98"  !CDS_PN = "98";
"VSS<66>":   PN = "96"  !CDS_PN = "96";
"VSS<67>":   PN = "94"  !CDS_PN = "94";
"VSS<68>":   PN = "57"  !CDS_PN = "57";
"VSS<69>":   PN = "55"  !CDS_PN = "55";
"VSS<70>":   PN = "53"  !CDS_PN = "53";
"VSS<71>":   PN = "50"  !CDS_PN = "50";
"VSS<72>":   PN = "48"  !CDS_PN = "48";
"VSS<73>":   PN = "46"  !CDS_PN = "46";
"VSS<74>":   PN = "44"  !CDS_PN = "44";
"VSS<75>":   PN = "42"  !CDS_PN = "42";
"VSS<76>":   PN = "39"  !CDS_PN = "39";
"VSS<77>":   PN = "37"  !CDS_PN = "37";
"VSS<78>":   PN = "35"  !CDS_PN = "35";
"VSS<79>":   PN = "33"  !CDS_PN = "33";
"VSS<80>":   PN = "31"  !CDS_PN = "31";
"VSS<81>":   PN = "28"  !CDS_PN = "28";
"VSS<82>":   PN = "26"  !CDS_PN = "26";
"VSS<83>":   PN = "24"  !CDS_PN = "24";
"VSS<84>":   PN = "22"  !CDS_PN = "22";
"VSS<85>":   PN = "20"  !CDS_PN = "20";
"VSS<86>":   PN = "17"  !CDS_PN = "17";
"VSS<87>":   PN = "15"  !CDS_PN = "15";
"VSS<88>":   PN = "13"  !CDS_PN = "13";
"VSS<89>":   PN = "11"  !CDS_PN = "11";
"VSS<90>":   PN = "9"  !CDS_PN = "9";
"VSS<91>":   PN = "6"  !CDS_PN = "6";
"VSS<92>":   PN = "4"  !CDS_PN = "4";
"VSS<93>":   PN = "2"  !CDS_PN = "2";
DRAWING = "@baseboard_fab2_lib.baseboard_fab2(sch_1):page81";
BODY = "SCONN288_H44441004","I67": #LOCATION = "J1G3" !CDS_LOCATION = "J1G3" #SEC = "2" !CDS_SEC = "2";
"DQS0N":   PN = "152"  !CDS_PN = "152";
"DQS0P":   PN = "153"  !CDS_PN = "153";
"DQS1N":   PN = "163"  !CDS_PN = "163";
"DQS1P":   PN = "164"  !CDS_PN = "164";
"DQS2N":   PN = "174"  !CDS_PN = "174";
"DQS2P":   PN = "175"  !CDS_PN = "175";
"DQS3N":   PN = "185"  !CDS_PN = "185";
"DQS3P":   PN = "186"  !CDS_PN = "186";
"DQS4N":   PN = "244"  !CDS_PN = "244";
"DQS4P":   PN = "245"  !CDS_PN = "245";
"DQS5N":   PN = "255"  !CDS_PN = "255";
"DQS5P":   PN = "256"  !CDS_PN = "256";
"DQS6N":   PN = "266"  !CDS_PN = "266";
"DQS6P":   PN = "267"  !CDS_PN = "267";
"DQS7N":   PN = "277"  !CDS_PN = "277";
"DQS7P":   PN = "278"  !CDS_PN = "278";
"DQS8N":   PN = "196"  !CDS_PN = "196";
"DQS8P":   PN = "197"  !CDS_PN = "197";
"DQS9N":   PN = "8"  !CDS_PN = "8";
"DQS9P":   PN = "7"  !CDS_PN = "7";
"DQS10N":   PN = "19"  !CDS_PN = "19";
"DQS10P":   PN = "18"  !CDS_PN = "18";
"DQS11N":   PN = "30"  !CDS_PN = "30";
"DQS11P":   PN = "29"  !CDS_PN = "29";
"DQS12N":   PN = "41"  !CDS_PN = "41";
"DQS12P":   PN = "40"  !CDS_PN = "40";
"DQS13N":   PN = "100"  !CDS_PN = "100";
"DQS13P":   PN = "99"  !CDS_PN = "99";
"DQS14N":   PN = "111"  !CDS_PN = "111";
"DQS14P":   PN = "110"  !CDS_PN = "110";
"DQS15N":   PN = "122"  !CDS_PN = "122";
"DQS15P":   PN = "121"  !CDS_PN = "121";
"DQS16N":   PN = "133"  !CDS_PN = "133";
"DQS16P":   PN = "132"  !CDS_PN = "132";
"DQS17N":   PN = "52"  !CDS_PN = "52";
"DQS17P":   PN = "51"  !CDS_PN = "51";
BODY = "SCONN288_H44441004","I169": #LOCATION = "J1G3" !CDS_LOCATION = "J1G3" #SEC = "4" !CDS_SEC = "4";
"12V<0>":   PN = "145"  !CDS_PN = "145";
"12V<1>":   PN = "1"  !CDS_PN = "1";
"VDD<0>":   PN = "236"  !CDS_PN = "236";
"VDD<1>":   PN = "233"  !CDS_PN = "233";
"VDD<2>":   PN = "231"  !CDS_PN = "231";
"VDD<3>":   PN = "229"  !CDS_PN = "229";
"VDD<4>":   PN = "226"  !CDS_PN = "226";
"VDD<5>":   PN = "223"  !CDS_PN = "223";
"VDD<6>":   PN = "220"  !CDS_PN = "220";
"VDD<7>":   PN = "217"  !CDS_PN = "217";
"VDD<8>":   PN = "215"  !CDS_PN = "215";
"VDD<9>":   PN = "212"  !CDS_PN = "212";
"VDD<10>":   PN = "209"  !CDS_PN = "209";
"VDD<11>":   PN = "206"  !CDS_PN = "206";
"VDD<12>":   PN = "204"  !CDS_PN = "204";
"VDD<13>":   PN = "92"  !CDS_PN = "92";
"VDD<14>":   PN = "90"  !CDS_PN = "90";
"VDD<15>":   PN = "88"  !CDS_PN = "88";
"VDD<16>":   PN = "85"  !CDS_PN = "85";
"VDD<17>":   PN = "83"  !CDS_PN = "83";
"VDD<18>":   PN = "80"  !CDS_PN = "80";
"VDD<19>":   PN = "76"  !CDS_PN = "76";
"VDD<20>":   PN = "73"  !CDS_PN = "73";
"VDD<21>":   PN = "70"  !CDS_PN = "70";
"VDD<22>":   PN = "67"  !CDS_PN = "67";
"VDD<23>":   PN = "64"  !CDS_PN = "64";
"VDD<24>":   PN = "61"  !CDS_PN = "61";
"VDD<25>":   PN = "59"  !CDS_PN = "59";
"VPP<0>":   PN = "287"  !CDS_PN = "287";
"VPP<1>":   PN = "286"  !CDS_PN = "286";
"VPP<2>":   PN = "288"  !CDS_PN = "288";
"VPP<3>":   PN = "143"  !CDS_PN = "143";
"VPP<4>":   PN = "142"  !CDS_PN = "142";
"VTT<0>":   PN = "221"  !CDS_PN = "221";
"VTT<1>":   PN = "77"  !CDS_PN = "77";
BODY = "CAP_A","I178": #LOCATION = "C9U10" !CDS_LOCATION = "C9U10" &SEC = "1" #&CDS_SEC = "1";
"A":   PN = "1"  !CDS_PN = "1";
"B":   PN = "2"  !CDS_PN = "2";
BODY = "SCONN288_H44441004","I185": #LOCATION = "J1G3" !CDS_LOCATION = "J1G3" #SEC = "3" !CDS_SEC = "3";
"VSS<0>":   PN = "283"  !CDS_PN = "283";
"VSS<1>":   PN = "281"  !CDS_PN = "281";
"VSS<2>":   PN = "279"  !CDS_PN = "279";
"VSS<3>":   PN = "276"  !CDS_PN = "276";
"VSS<4>":   PN = "274"  !CDS_PN = "274";
"VSS<5>":   PN = "272"  !CDS_PN = "272";
"VSS<6>":   PN = "270"  !CDS_PN = "270";
"VSS<7>":   PN = "268"  !CDS_PN = "268";
"VSS<8>":   PN = "265"  !CDS_PN = "265";
"VSS<9>":   PN = "263"  !CDS_PN = "263";
"VSS<10>":   PN = "261"  !CDS_PN = "261";
"VSS<11>":   PN = "259"  !CDS_PN = "259";
"VSS<12>":   PN = "257"  !CDS_PN = "257";
"VSS<13>":   PN = "254"  !CDS_PN = "254";
"VSS<14>":   PN = "252"  !CDS_PN = "252";
"VSS<15>":   PN = "250"  !CDS_PN = "250";
"VSS<16>":   PN = "248"  !CDS_PN = "248";
"VSS<17>":   PN = "246"  !CDS_PN = "246";
"VSS<18>":   PN = "243"  !CDS_PN = "243";
"VSS<19>":   PN = "241"  !CDS_PN = "241";
"VSS<20>":   PN = "239"  !CDS_PN = "239";
"VSS<21>":   PN = "202"  !CDS_PN = "202";
"VSS<22>":   PN = "200"  !CDS_PN = "200";
"VSS<23>":   PN = "198"  !CDS_PN = "198";
"VSS<24>":   PN = "195"  !CDS_PN = "195";
"VSS<25>":   PN = "193"  !CDS_PN = "193";
"VSS<26>":   PN = "191"  !CDS_PN = "191";
"VSS<27>":   PN = "189"  !CDS_PN = "189";
"VSS<28>":   PN = "187"  !CDS_PN = "187";
"VSS<29>":   PN = "184"  !CDS_PN = "184";
"VSS<30>":   PN = "182"  !CDS_PN = "182";
"VSS<31>":   PN = "180"  !CDS_PN = "180";
"VSS<32>":   PN = "178"  !CDS_PN = "178";
"VSS<33>":   PN = "176"  !CDS_PN = "176";
"VSS<34>":   PN = "173"  !CDS_PN = "173";
"VSS<35>":   PN = "171"  !CDS_PN = "171";
"VSS<36>":   PN = "169"  !CDS_PN = "169";
"VSS<37>":   PN = "167"  !CDS_PN = "167";
"VSS<38>":   PN = "165"  !CDS_PN = "165";
"VSS<39>":   PN = "162"  !CDS_PN = "162";
"VSS<40>":   PN = "160"  !CDS_PN = "160";
"VSS<41>":   PN = "158"  !CDS_PN = "158";
"VSS<42>":   PN = "156"  !CDS_PN = "156";
"VSS<43>":   PN = "154"  !CDS_PN = "154";
"VSS<44>":   PN = "151"  !CDS_PN = "151";
"VSS<45>":   PN = "149"  !CDS_PN = "149";
"VSS<46>":   PN = "147"  !CDS_PN = "147";
"VSS<47>":   PN = "138"  !CDS_PN = "138";
"VSS<48>":   PN = "136"  !CDS_PN = "136";
"VSS<49>":   PN = "134"  !CDS_PN = "134";
"VSS<50>":   PN = "131"  !CDS_PN = "131";
"VSS<51>":   PN = "129"  !CDS_PN = "129";
"VSS<52>":   PN = "127"  !CDS_PN = "127";
"VSS<53>":   PN = "125"  !CDS_PN = "125";
"VSS<54>":   PN = "123"  !CDS_PN = "123";
"VSS<55>":   PN = "120"  !CDS_PN = "120";
"VSS<56>":   PN = "118"  !CDS_PN = "118";
"VSS<57>":   PN = "116"  !CDS_PN = "116";
"VSS<58>":   PN = "114"  !CDS_PN = "114";
"VSS<59>":   PN = "112"  !CDS_PN = "112";
"VSS<60>":   PN = "109"  !CDS_PN = "109";
"VSS<61>":   PN = "107"  !CDS_PN = "107";
"VSS<62>":   PN = "105"  !CDS_PN = "105";
"VSS<63>":   PN = "103"  !CDS_PN = "103";
"VSS<64>":   PN = "101"  !CDS_PN = "101";
"VSS<65>":   PN = "98"  !CDS_PN = "98";
"VSS<66>":   PN = "96"  !CDS_PN = "96";
"VSS<67>":   PN = "94"  !CDS_PN = "94";
"VSS<68>":   PN = "57"  !CDS_PN = "57";
"VSS<69>":   PN = "55"  !CDS_PN = "55";
"VSS<70>":   PN = "53"  !CDS_PN = "53";
"VSS<71>":   PN = "50"  !CDS_PN = "50";
"VSS<72>":   PN = "48"  !CDS_PN = "48";
"VSS<73>":   PN = "46"  !CDS_PN = "46";
"VSS<74>":   PN = "44"  !CDS_PN = "44";
"VSS<75>":   PN = "42"  !CDS_PN = "42";
"VSS<76>":   PN = "39"  !CDS_PN = "39";
"VSS<77>":   PN = "37"  !CDS_PN = "37";
"VSS<78>":   PN = "35"  !CDS_PN = "35";
"VSS<79>":   PN = "33"  !CDS_PN = "33";
"VSS<80>":   PN = "31"  !CDS_PN = "31";
"VSS<81>":   PN = "28"  !CDS_PN = "28";
"VSS<82>":   PN = "26"  !CDS_PN = "26";
"VSS<83>":   PN = "24"  !CDS_PN = "24";
"VSS<84>":   PN = "22"  !CDS_PN = "22";
"VSS<85>":   PN = "20"  !CDS_PN = "20";
"VSS<86>":   PN = "17"  !CDS_PN = "17";
"VSS<87>":   PN = "15"  !CDS_PN = "15";
"VSS<88>":   PN = "13"  !CDS_PN = "13";
"VSS<89>":   PN = "11"  !CDS_PN = "11";
"VSS<90>":   PN = "9"  !CDS_PN = "9";
"VSS<91>":   PN = "6"  !CDS_PN = "6";
"VSS<92>":   PN = "4"  !CDS_PN = "4";
"VSS<93>":   PN = "2"  !CDS_PN = "2";
BODY = "SCONN288_H44441004","I186": #LOCATION = "J1G3" !CDS_LOCATION = "J1G3" #SEC = "1" !CDS_SEC = "1";
"A0":   PN = "79"  !CDS_PN = "79";
"A1":   PN = "72"  !CDS_PN = "72";
"A2":   PN = "216"  !CDS_PN = "216";
"A3":   PN = "71"  !CDS_PN = "71";
"A4":   PN = "214"  !CDS_PN = "214";
"A5":   PN = "213"  !CDS_PN = "213";
"A6":   PN = "69"  !CDS_PN = "69";
"A7":   PN = "211"  !CDS_PN = "211";
"A8":   PN = "68"  !CDS_PN = "68";
"A9":   PN = "66"  !CDS_PN = "66";
"A10":   PN = "225"  !CDS_PN = "225";
"A11":   PN = "210"  !CDS_PN = "210";
"A12":   PN = "65"  !CDS_PN = "65";
"A13":   PN = "232"  !CDS_PN = "232";
"A14_WE_N":   PN = "228"  !CDS_PN = "228";
"A15_CAS_N":   PN = "86"  !CDS_PN = "86";
"A16_RAS_N":   PN = "82"  !CDS_PN = "82";
"A17":   PN = "234"  !CDS_PN = "234";
"ACT_N":   PN = "62"  !CDS_PN = "62";
"ALERT_N":   PN = "208"  !CDS_PN = "208";
"BA<0>":   PN = "81"  !CDS_PN = "81";
"BA<1>":   PN = "224"  !CDS_PN = "224";
"BG<0>":   PN = "63"  !CDS_PN = "63";
"BG<1>":   PN = "207"  !CDS_PN = "207";
"C<2>":   PN = "235"  !CDS_PN = "235";
"CB<0>":   PN = "49"  !CDS_PN = "49";
"CB<1>":   PN = "194"  !CDS_PN = "194";
"CB<2>":   PN = "56"  !CDS_PN = "56";
"CB<3>":   PN = "201"  !CDS_PN = "201";
"CB<4>":   PN = "47"  !CDS_PN = "47";
"CB<5>":   PN = "192"  !CDS_PN = "192";
"CB<6>":   PN = "54"  !CDS_PN = "54";
"CB<7>":   PN = "199"  !CDS_PN = "199";
"CK0N":   PN = "75"  !CDS_PN = "75";
"CK0P":   PN = "74"  !CDS_PN = "74";
"CK1N":   PN = "219"  !CDS_PN = "219";
"CK1P":   PN = "218"  !CDS_PN = "218";
"CKE<0>":   PN = "60"  !CDS_PN = "60";
"CKE<1>":   PN = "203"  !CDS_PN = "203";
"DQ<0>":   PN = "5"  !CDS_PN = "5";
"DQ<1>":   PN = "150"  !CDS_PN = "150";
"DQ<2>":   PN = "12"  !CDS_PN = "12";
"DQ<3>":   PN = "157"  !CDS_PN = "157";
"DQ<4>":   PN = "3"  !CDS_PN = "3";
"DQ<5>":   PN = "148"  !CDS_PN = "148";
"DQ<6>":   PN = "10"  !CDS_PN = "10";
"DQ<7>":   PN = "155"  !CDS_PN = "155";
"DQ<8>":   PN = "16"  !CDS_PN = "16";
"DQ<9>":   PN = "161"  !CDS_PN = "161";
"DQ<10>":   PN = "23"  !CDS_PN = "23";
"DQ<11>":   PN = "168"  !CDS_PN = "168";
"DQ<12>":   PN = "14"  !CDS_PN = "14";
"DQ<13>":   PN = "159"  !CDS_PN = "159";
"DQ<14>":   PN = "21"  !CDS_PN = "21";
"DQ<15>":   PN = "166"  !CDS_PN = "166";
"DQ<16>":   PN = "27"  !CDS_PN = "27";
"DQ<17>":   PN = "172"  !CDS_PN = "172";
"DQ<18>":   PN = "34"  !CDS_PN = "34";
"DQ<19>":   PN = "179"  !CDS_PN = "179";
"DQ<20>":   PN = "25"  !CDS_PN = "25";
"DQ<21>":   PN = "170"  !CDS_PN = "170";
"DQ<22>":   PN = "32"  !CDS_PN = "32";
"DQ<23>":   PN = "177"  !CDS_PN = "177";
"DQ<24>":   PN = "38"  !CDS_PN = "38";
"DQ<25>":   PN = "183"  !CDS_PN = "183";
"DQ<26>":   PN = "45"  !CDS_PN = "45";
"DQ<27>":   PN = "190"  !CDS_PN = "190";
"DQ<28>":   PN = "36"  !CDS_PN = "36";
"DQ<29>":   PN = "181"  !CDS_PN = "181";
"DQ<30>":   PN = "43"  !CDS_PN = "43";
"DQ<31>":   PN = "188"  !CDS_PN = "188";
"DQ<32>":   PN = "97"  !CDS_PN = "97";
"DQ<33>":   PN = "242"  !CDS_PN = "242";
"DQ<34>":   PN = "104"  !CDS_PN = "104";
"DQ<35>":   PN = "249"  !CDS_PN = "249";
"DQ<36>":   PN = "95"  !CDS_PN = "95";
"DQ<37>":   PN = "240"  !CDS_PN = "240";
"DQ<38>":   PN = "102"  !CDS_PN = "102";
"DQ<39>":   PN = "247"  !CDS_PN = "247";
"DQ<40>":   PN = "108"  !CDS_PN = "108";
"DQ<41>":   PN = "253"  !CDS_PN = "253";
"DQ<42>":   PN = "115"  !CDS_PN = "115";
"DQ<43>":   PN = "260"  !CDS_PN = "260";
"DQ<44>":   PN = "106"  !CDS_PN = "106";
"DQ<45>":   PN = "251"  !CDS_PN = "251";
"DQ<46>":   PN = "113"  !CDS_PN = "113";
"DQ<47>":   PN = "258"  !CDS_PN = "258";
"DQ<48>":   PN = "119"  !CDS_PN = "119";
"DQ<49>":   PN = "264"  !CDS_PN = "264";
"DQ<50>":   PN = "126"  !CDS_PN = "126";
"DQ<51>":   PN = "271"  !CDS_PN = "271";
"DQ<52>":   PN = "117"  !CDS_PN = "117";
"DQ<53>":   PN = "262"  !CDS_PN = "262";
"DQ<54>":   PN = "124"  !CDS_PN = "124";
"DQ<55>":   PN = "269"  !CDS_PN = "269";
"DQ<56>":   PN = "130"  !CDS_PN = "130";
"DQ<57>":   PN = "275"  !CDS_PN = "275";
"DQ<58>":   PN = "137"  !CDS_PN = "137";
"DQ<59>":   PN = "282"  !CDS_PN = "282";
"DQ<60>":   PN = "128"  !CDS_PN = "128";
"DQ<61>":   PN = "273"  !CDS_PN = "273";
"DQ<62>":   PN = "135"  !CDS_PN = "135";
"DQ<63>":   PN = "280"  !CDS_PN = "280";
"EVENT_N":   PN = "78"  !CDS_PN = "78";
"ODT<0>":   PN = "87"  !CDS_PN = "87";
"ODT<1>":   PN = "91"  !CDS_PN = "91";
"PAR":   PN = "222"  !CDS_PN = "222";
"RESET_N":   PN = "58"  !CDS_PN = "58";
"RFU<0>":   PN = "205"  !CDS_PN = "205";
"RFU<1>":   PN = "227"  !CDS_PN = "227";
"RFU<2>":   PN = "144"  !CDS_PN = "144";
"S0_N":   PN = "84"  !CDS_PN = "84";
"S1_N":   PN = "89"  !CDS_PN = "89";
"S2_N_C<0>":   PN = "93"  !CDS_PN = "93";
"S3_N_C<1>":   PN = "237"  !CDS_PN = "237";
"SA<0>":   PN = "139"  !CDS_PN = "139";
"SA<1>":   PN = "140"  !CDS_PN = "140";
"SA<2>":   PN = "238"  !CDS_PN = "238";
"SAVE_N_NC":   PN = "230"  !CDS_PN = "230";
"SCL":   PN = "141"  !CDS_PN = "141";
"SDA":   PN = "285"  !CDS_PN = "285";
"VDDSPD":   PN = "284"  !CDS_PN = "284";
"VREFCA":   PN = "146"  !CDS_PN = "146";
DRAWING = "@baseboard_fab2_lib.baseboard_fab2(sch_1):page82";
BODY = "SCONN288_H44441003","I64": #LOCATION = "J9U2" !CDS_LOCATION = "J9U2" #SEC = "2" !CDS_SEC = "2";
"DQS0N":   PN = "152"  !CDS_PN = "152";
"DQS0P":   PN = "153"  !CDS_PN = "153";
"DQS1N":   PN = "163"  !CDS_PN = "163";
"DQS1P":   PN = "164"  !CDS_PN = "164";
"DQS2N":   PN = "174"  !CDS_PN = "174";
"DQS2P":   PN = "175"  !CDS_PN = "175";
"DQS3N":   PN = "185"  !CDS_PN = "185";
"DQS3P":   PN = "186"  !CDS_PN = "186";
"DQS4N":   PN = "244"  !CDS_PN = "244";
"DQS4P":   PN = "245"  !CDS_PN = "245";
"DQS5N":   PN = "255"  !CDS_PN = "255";
"DQS5P":   PN = "256"  !CDS_PN = "256";
"DQS6N":   PN = "266"  !CDS_PN = "266";
"DQS6P":   PN = "267"  !CDS_PN = "267";
"DQS7N":   PN = "277"  !CDS_PN = "277";
"DQS7P":   PN = "278"  !CDS_PN = "278";
"DQS8N":   PN = "196"  !CDS_PN = "196";
"DQS8P":   PN = "197"  !CDS_PN = "197";
"DQS9N":   PN = "8"  !CDS_PN = "8";
"DQS9P":   PN = "7"  !CDS_PN = "7";
"DQS10N":   PN = "19"  !CDS_PN = "19";
"DQS10P":   PN = "18"  !CDS_PN = "18";
"DQS11N":   PN = "30"  !CDS_PN = "30";
"DQS11P":   PN = "29"  !CDS_PN = "29";
"DQS12N":   PN = "41"  !CDS_PN = "41";
"DQS12P":   PN = "40"  !CDS_PN = "40";
"DQS13N":   PN = "100"  !CDS_PN = "100";
"DQS13P":   PN = "99"  !CDS_PN = "99";
"DQS14N":   PN = "111"  !CDS_PN = "111";
"DQS14P":   PN = "110"  !CDS_PN = "110";
"DQS15N":   PN = "122"  !CDS_PN = "122";
"DQS15P":   PN = "121"  !CDS_PN = "121";
"DQS16N":   PN = "133"  !CDS_PN = "133";
"DQS16P":   PN = "132"  !CDS_PN = "132";
"DQS17N":   PN = "52"  !CDS_PN = "52";
"DQS17P":   PN = "51"  !CDS_PN = "51";
BODY = "SCONN288_H44441003","I171": #LOCATION = "J9U2" !CDS_LOCATION = "J9U2" #SEC = "4" !CDS_SEC = "4";
"12V<0>":   PN = "145"  !CDS_PN = "145";
"12V<1>":   PN = "1"  !CDS_PN = "1";
"VDD<0>":   PN = "236"  !CDS_PN = "236";
"VDD<1>":   PN = "233"  !CDS_PN = "233";
"VDD<2>":   PN = "231"  !CDS_PN = "231";
"VDD<3>":   PN = "229"  !CDS_PN = "229";
"VDD<4>":   PN = "226"  !CDS_PN = "226";
"VDD<5>":   PN = "223"  !CDS_PN = "223";
"VDD<6>":   PN = "220"  !CDS_PN = "220";
"VDD<7>":   PN = "217"  !CDS_PN = "217";
"VDD<8>":   PN = "215"  !CDS_PN = "215";
"VDD<9>":   PN = "212"  !CDS_PN = "212";
"VDD<10>":   PN = "209"  !CDS_PN = "209";
"VDD<11>":   PN = "206"  !CDS_PN = "206";
"VDD<12>":   PN = "204"  !CDS_PN = "204";
"VDD<13>":   PN = "92"  !CDS_PN = "92";
"VDD<14>":   PN = "90"  !CDS_PN = "90";
"VDD<15>":   PN = "88"  !CDS_PN = "88";
"VDD<16>":   PN = "85"  !CDS_PN = "85";
"VDD<17>":   PN = "83"  !CDS_PN = "83";
"VDD<18>":   PN = "80"  !CDS_PN = "80";
"VDD<19>":   PN = "76"  !CDS_PN = "76";
"VDD<20>":   PN = "73"  !CDS_PN = "73";
"VDD<21>":   PN = "70"  !CDS_PN = "70";
"VDD<22>":   PN = "67"  !CDS_PN = "67";
"VDD<23>":   PN = "64"  !CDS_PN = "64";
"VDD<24>":   PN = "61"  !CDS_PN = "61";
"VDD<25>":   PN = "59"  !CDS_PN = "59";
"VPP<0>":   PN = "287"  !CDS_PN = "287";
"VPP<1>":   PN = "286"  !CDS_PN = "286";
"VPP<2>":   PN = "288"  !CDS_PN = "288";
"VPP<3>":   PN = "143"  !CDS_PN = "143";
"VPP<4>":   PN = "142"  !CDS_PN = "142";
"VTT<0>":   PN = "221"  !CDS_PN = "221";
"VTT<1>":   PN = "77"  !CDS_PN = "77";
BODY = "CAP_A","I180": #LOCATION = "C1G19" !CDS_LOCATION = "C1G19" &SEC = "1" #&CDS_SEC = "1";
"A":   PN = "1"  !CDS_PN = "1";
"B":   PN = "2"  !CDS_PN = "2";
BODY = "SCONN288_H44441003","I187": #LOCATION = "J9U2" !CDS_LOCATION = "J9U2" #SEC = "1" !CDS_SEC = "1";
"A0":   PN = "79"  !CDS_PN = "79";
"A1":   PN = "72"  !CDS_PN = "72";
"A2":   PN = "216"  !CDS_PN = "216";
"A3":   PN = "71"  !CDS_PN = "71";
"A4":   PN = "214"  !CDS_PN = "214";
"A5":   PN = "213"  !CDS_PN = "213";
"A6":   PN = "69"  !CDS_PN = "69";
"A7":   PN = "211"  !CDS_PN = "211";
"A8":   PN = "68"  !CDS_PN = "68";
"A9":   PN = "66"  !CDS_PN = "66";
"A10":   PN = "225"  !CDS_PN = "225";
"A11":   PN = "210"  !CDS_PN = "210";
"A12":   PN = "65"  !CDS_PN = "65";
"A13":   PN = "232"  !CDS_PN = "232";
"A14_WE_N":   PN = "228"  !CDS_PN = "228";
"A15_CAS_N":   PN = "86"  !CDS_PN = "86";
"A16_RAS_N":   PN = "82"  !CDS_PN = "82";
"A17":   PN = "234"  !CDS_PN = "234";
"ACT_N":   PN = "62"  !CDS_PN = "62";
"ALERT_N":   PN = "208"  !CDS_PN = "208";
"BA<0>":   PN = "81"  !CDS_PN = "81";
"BA<1>":   PN = "224"  !CDS_PN = "224";
"BG<0>":   PN = "63"  !CDS_PN = "63";
"BG<1>":   PN = "207"  !CDS_PN = "207";
"C<2>":   PN = "235"  !CDS_PN = "235";
"CB<0>":   PN = "49"  !CDS_PN = "49";
"CB<1>":   PN = "194"  !CDS_PN = "194";
"CB<2>":   PN = "56"  !CDS_PN = "56";
"CB<3>":   PN = "201"  !CDS_PN = "201";
"CB<4>":   PN = "47"  !CDS_PN = "47";
"CB<5>":   PN = "192"  !CDS_PN = "192";
"CB<6>":   PN = "54"  !CDS_PN = "54";
"CB<7>":   PN = "199"  !CDS_PN = "199";
"CK0N":   PN = "75"  !CDS_PN = "75";
"CK0P":   PN = "74"  !CDS_PN = "74";
"CK1N":   PN = "219"  !CDS_PN = "219";
"CK1P":   PN = "218"  !CDS_PN = "218";
"CKE<0>":   PN = "60"  !CDS_PN = "60";
"CKE<1>":   PN = "203"  !CDS_PN = "203";
"DQ<0>":   PN = "5"  !CDS_PN = "5";
"DQ<1>":   PN = "150"  !CDS_PN = "150";
"DQ<2>":   PN = "12"  !CDS_PN = "12";
"DQ<3>":   PN = "157"  !CDS_PN = "157";
"DQ<4>":   PN = "3"  !CDS_PN = "3";
"DQ<5>":   PN = "148"  !CDS_PN = "148";
"DQ<6>":   PN = "10"  !CDS_PN = "10";
"DQ<7>":   PN = "155"  !CDS_PN = "155";
"DQ<8>":   PN = "16"  !CDS_PN = "16";
"DQ<9>":   PN = "161"  !CDS_PN = "161";
"DQ<10>":   PN = "23"  !CDS_PN = "23";
"DQ<11>":   PN = "168"  !CDS_PN = "168";
"DQ<12>":   PN = "14"  !CDS_PN = "14";
"DQ<13>":   PN = "159"  !CDS_PN = "159";
"DQ<14>":   PN = "21"  !CDS_PN = "21";
"DQ<15>":   PN = "166"  !CDS_PN = "166";
"DQ<16>":   PN = "27"  !CDS_PN = "27";
"DQ<17>":   PN = "172"  !CDS_PN = "172";
"DQ<18>":   PN = "34"  !CDS_PN = "34";
"DQ<19>":   PN = "179"  !CDS_PN = "179";
"DQ<20>":   PN = "25"  !CDS_PN = "25";
"DQ<21>":   PN = "170"  !CDS_PN = "170";
"DQ<22>":   PN = "32"  !CDS_PN = "32";
"DQ<23>":   PN = "177"  !CDS_PN = "177";
"DQ<24>":   PN = "38"  !CDS_PN = "38";
"DQ<25>":   PN = "183"  !CDS_PN = "183";
"DQ<26>":   PN = "45"  !CDS_PN = "45";
"DQ<27>":   PN = "190"  !CDS_PN = "190";
"DQ<28>":   PN = "36"  !CDS_PN = "36";
"DQ<29>":   PN = "181"  !CDS_PN = "181";
"DQ<30>":   PN = "43"  !CDS_PN = "43";
"DQ<31>":   PN = "188"  !CDS_PN = "188";
"DQ<32>":   PN = "97"  !CDS_PN = "97";
"DQ<33>":   PN = "242"  !CDS_PN = "242";
"DQ<34>":   PN = "104"  !CDS_PN = "104";
"DQ<35>":   PN = "249"  !CDS_PN = "249";
"DQ<36>":   PN = "95"  !CDS_PN = "95";
"DQ<37>":   PN = "240"  !CDS_PN = "240";
"DQ<38>":   PN = "102"  !CDS_PN = "102";
"DQ<39>":   PN = "247"  !CDS_PN = "247";
"DQ<40>":   PN = "108"  !CDS_PN = "108";
"DQ<41>":   PN = "253"  !CDS_PN = "253";
"DQ<42>":   PN = "115"  !CDS_PN = "115";
"DQ<43>":   PN = "260"  !CDS_PN = "260";
"DQ<44>":   PN = "106"  !CDS_PN = "106";
"DQ<45>":   PN = "251"  !CDS_PN = "251";
"DQ<46>":   PN = "113"  !CDS_PN = "113";
"DQ<47>":   PN = "258"  !CDS_PN = "258";
"DQ<48>":   PN = "119"  !CDS_PN = "119";
"DQ<49>":   PN = "264"  !CDS_PN = "264";
"DQ<50>":   PN = "126"  !CDS_PN = "126";
"DQ<51>":   PN = "271"  !CDS_PN = "271";
"DQ<52>":   PN = "117"  !CDS_PN = "117";
"DQ<53>":   PN = "262"  !CDS_PN = "262";
"DQ<54>":   PN = "124"  !CDS_PN = "124";
"DQ<55>":   PN = "269"  !CDS_PN = "269";
"DQ<56>":   PN = "130"  !CDS_PN = "130";
"DQ<57>":   PN = "275"  !CDS_PN = "275";
"DQ<58>":   PN = "137"  !CDS_PN = "137";
"DQ<59>":   PN = "282"  !CDS_PN = "282";
"DQ<60>":   PN = "128"  !CDS_PN = "128";
"DQ<61>":   PN = "273"  !CDS_PN = "273";
"DQ<62>":   PN = "135"  !CDS_PN = "135";
"DQ<63>":   PN = "280"  !CDS_PN = "280";
"EVENT_N":   PN = "78"  !CDS_PN = "78";
"ODT<0>":   PN = "87"  !CDS_PN = "87";
"ODT<1>":   PN = "91"  !CDS_PN = "91";
"PAR":   PN = "222"  !CDS_PN = "222";
"RESET_N":   PN = "58"  !CDS_PN = "58";
"RFU<0>":   PN = "205"  !CDS_PN = "205";
"RFU<1>":   PN = "227"  !CDS_PN = "227";
"RFU<2>":   PN = "144"  !CDS_PN = "144";
"S0_N":   PN = "84"  !CDS_PN = "84";
"S1_N":   PN = "89"  !CDS_PN = "89";
"S2_N_C<0>":   PN = "93"  !CDS_PN = "93";
"S3_N_C<1>":   PN = "237"  !CDS_PN = "237";
"SA<0>":   PN = "139"  !CDS_PN = "139";
"SA<1>":   PN = "140"  !CDS_PN = "140";
"SA<2>":   PN = "238"  !CDS_PN = "238";
"SAVE_N_NC":   PN = "230"  !CDS_PN = "230";
"SCL":   PN = "141"  !CDS_PN = "141";
"SDA":   PN = "285"  !CDS_PN = "285";
"VDDSPD":   PN = "284"  !CDS_PN = "284";
"VREFCA":   PN = "146"  !CDS_PN = "146";
BODY = "SCONN288_H44441003","I188": #LOCATION = "J9U2" !CDS_LOCATION = "J9U2" #SEC = "3" !CDS_SEC = "3";
"VSS<0>":   PN = "283"  !CDS_PN = "283";
"VSS<1>":   PN = "281"  !CDS_PN = "281";
"VSS<2>":   PN = "279"  !CDS_PN = "279";
"VSS<3>":   PN = "276"  !CDS_PN = "276";
"VSS<4>":   PN = "274"  !CDS_PN = "274";
"VSS<5>":   PN = "272"  !CDS_PN = "272";
"VSS<6>":   PN = "270"  !CDS_PN = "270";
"VSS<7>":   PN = "268"  !CDS_PN = "268";
"VSS<8>":   PN = "265"  !CDS_PN = "265";
"VSS<9>":   PN = "263"  !CDS_PN = "263";
"VSS<10>":   PN = "261"  !CDS_PN = "261";
"VSS<11>":   PN = "259"  !CDS_PN = "259";
"VSS<12>":   PN = "257"  !CDS_PN = "257";
"VSS<13>":   PN = "254"  !CDS_PN = "254";
"VSS<14>":   PN = "252"  !CDS_PN = "252";
"VSS<15>":   PN = "250"  !CDS_PN = "250";
"VSS<16>":   PN = "248"  !CDS_PN = "248";
"VSS<17>":   PN = "246"  !CDS_PN = "246";
"VSS<18>":   PN = "243"  !CDS_PN = "243";
"VSS<19>":   PN = "241"  !CDS_PN = "241";
"VSS<20>":   PN = "239"  !CDS_PN = "239";
"VSS<21>":   PN = "202"  !CDS_PN = "202";
"VSS<22>":   PN = "200"  !CDS_PN = "200";
"VSS<23>":   PN = "198"  !CDS_PN = "198";
"VSS<24>":   PN = "195"  !CDS_PN = "195";
"VSS<25>":   PN = "193"  !CDS_PN = "193";
"VSS<26>":   PN = "191"  !CDS_PN = "191";
"VSS<27>":   PN = "189"  !CDS_PN = "189";
"VSS<28>":   PN = "187"  !CDS_PN = "187";
"VSS<29>":   PN = "184"  !CDS_PN = "184";
"VSS<30>":   PN = "182"  !CDS_PN = "182";
"VSS<31>":   PN = "180"  !CDS_PN = "180";
"VSS<32>":   PN = "178"  !CDS_PN = "178";
"VSS<33>":   PN = "176"  !CDS_PN = "176";
"VSS<34>":   PN = "173"  !CDS_PN = "173";
"VSS<35>":   PN = "171"  !CDS_PN = "171";
"VSS<36>":   PN = "169"  !CDS_PN = "169";
"VSS<37>":   PN = "167"  !CDS_PN = "167";
"VSS<38>":   PN = "165"  !CDS_PN = "165";
"VSS<39>":   PN = "162"  !CDS_PN = "162";
"VSS<40>":   PN = "160"  !CDS_PN = "160";
"VSS<41>":   PN = "158"  !CDS_PN = "158";
"VSS<42>":   PN = "156"  !CDS_PN = "156";
"VSS<43>":   PN = "154"  !CDS_PN = "154";
"VSS<44>":   PN = "151"  !CDS_PN = "151";
"VSS<45>":   PN = "149"  !CDS_PN = "149";
"VSS<46>":   PN = "147"  !CDS_PN = "147";
"VSS<47>":   PN = "138"  !CDS_PN = "138";
"VSS<48>":   PN = "136"  !CDS_PN = "136";
"VSS<49>":   PN = "134"  !CDS_PN = "134";
"VSS<50>":   PN = "131"  !CDS_PN = "131";
"VSS<51>":   PN = "129"  !CDS_PN = "129";
"VSS<52>":   PN = "127"  !CDS_PN = "127";
"VSS<53>":   PN = "125"  !CDS_PN = "125";
"VSS<54>":   PN = "123"  !CDS_PN = "123";
"VSS<55>":   PN = "120"  !CDS_PN = "120";
"VSS<56>":   PN = "118"  !CDS_PN = "118";
"VSS<57>":   PN = "116"  !CDS_PN = "116";
"VSS<58>":   PN = "114"  !CDS_PN = "114";
"VSS<59>":   PN = "112"  !CDS_PN = "112";
"VSS<60>":   PN = "109"  !CDS_PN = "109";
"VSS<61>":   PN = "107"  !CDS_PN = "107";
"VSS<62>":   PN = "105"  !CDS_PN = "105";
"VSS<63>":   PN = "103"  !CDS_PN = "103";
"VSS<64>":   PN = "101"  !CDS_PN = "101";
"VSS<65>":   PN = "98"  !CDS_PN = "98";
"VSS<66>":   PN = "96"  !CDS_PN = "96";
"VSS<67>":   PN = "94"  !CDS_PN = "94";
"VSS<68>":   PN = "57"  !CDS_PN = "57";
"VSS<69>":   PN = "55"  !CDS_PN = "55";
"VSS<70>":   PN = "53"  !CDS_PN = "53";
"VSS<71>":   PN = "50"  !CDS_PN = "50";
"VSS<72>":   PN = "48"  !CDS_PN = "48";
"VSS<73>":   PN = "46"  !CDS_PN = "46";
"VSS<74>":   PN = "44"  !CDS_PN = "44";
"VSS<75>":   PN = "42"  !CDS_PN = "42";
"VSS<76>":   PN = "39"  !CDS_PN = "39";
"VSS<77>":   PN = "37"  !CDS_PN = "37";
"VSS<78>":   PN = "35"  !CDS_PN = "35";
"VSS<79>":   PN = "33"  !CDS_PN = "33";
"VSS<80>":   PN = "31"  !CDS_PN = "31";
"VSS<81>":   PN = "28"  !CDS_PN = "28";
"VSS<82>":   PN = "26"  !CDS_PN = "26";
"VSS<83>":   PN = "24"  !CDS_PN = "24";
"VSS<84>":   PN = "22"  !CDS_PN = "22";
"VSS<85>":   PN = "20"  !CDS_PN = "20";
"VSS<86>":   PN = "17"  !CDS_PN = "17";
"VSS<87>":   PN = "15"  !CDS_PN = "15";
"VSS<88>":   PN = "13"  !CDS_PN = "13";
"VSS<89>":   PN = "11"  !CDS_PN = "11";
"VSS<90>":   PN = "9"  !CDS_PN = "9";
"VSS<91>":   PN = "6"  !CDS_PN = "6";
"VSS<92>":   PN = "4"  !CDS_PN = "4";
"VSS<93>":   PN = "2"  !CDS_PN = "2";
DRAWING = "@baseboard_fab2_lib.baseboard_fab2(sch_1):page83";
BODY = "SCONN288_H44441004","I43": #LOCATION = "J1B1" !CDS_LOCATION = "J1B1" #SEC = "3" !CDS_SEC = "3";
"VSS<0>":   PN = "283"  !CDS_PN = "283";
"VSS<1>":   PN = "281"  !CDS_PN = "281";
"VSS<2>":   PN = "279"  !CDS_PN = "279";
"VSS<3>":   PN = "276"  !CDS_PN = "276";
"VSS<4>":   PN = "274"  !CDS_PN = "274";
"VSS<5>":   PN = "272"  !CDS_PN = "272";
"VSS<6>":   PN = "270"  !CDS_PN = "270";
"VSS<7>":   PN = "268"  !CDS_PN = "268";
"VSS<8>":   PN = "265"  !CDS_PN = "265";
"VSS<9>":   PN = "263"  !CDS_PN = "263";
"VSS<10>":   PN = "261"  !CDS_PN = "261";
"VSS<11>":   PN = "259"  !CDS_PN = "259";
"VSS<12>":   PN = "257"  !CDS_PN = "257";
"VSS<13>":   PN = "254"  !CDS_PN = "254";
"VSS<14>":   PN = "252"  !CDS_PN = "252";
"VSS<15>":   PN = "250"  !CDS_PN = "250";
"VSS<16>":   PN = "248"  !CDS_PN = "248";
"VSS<17>":   PN = "246"  !CDS_PN = "246";
"VSS<18>":   PN = "243"  !CDS_PN = "243";
"VSS<19>":   PN = "241"  !CDS_PN = "241";
"VSS<20>":   PN = "239"  !CDS_PN = "239";
"VSS<21>":   PN = "202"  !CDS_PN = "202";
"VSS<22>":   PN = "200"  !CDS_PN = "200";
"VSS<23>":   PN = "198"  !CDS_PN = "198";
"VSS<24>":   PN = "195"  !CDS_PN = "195";
"VSS<25>":   PN = "193"  !CDS_PN = "193";
"VSS<26>":   PN = "191"  !CDS_PN = "191";
"VSS<27>":   PN = "189"  !CDS_PN = "189";
"VSS<28>":   PN = "187"  !CDS_PN = "187";
"VSS<29>":   PN = "184"  !CDS_PN = "184";
"VSS<30>":   PN = "182"  !CDS_PN = "182";
"VSS<31>":   PN = "180"  !CDS_PN = "180";
"VSS<32>":   PN = "178"  !CDS_PN = "178";
"VSS<33>":   PN = "176"  !CDS_PN = "176";
"VSS<34>":   PN = "173"  !CDS_PN = "173";
"VSS<35>":   PN = "171"  !CDS_PN = "171";
"VSS<36>":   PN = "169"  !CDS_PN = "169";
"VSS<37>":   PN = "167"  !CDS_PN = "167";
"VSS<38>":   PN = "165"  !CDS_PN = "165";
"VSS<39>":   PN = "162"  !CDS_PN = "162";
"VSS<40>":   PN = "160"  !CDS_PN = "160";
"VSS<41>":   PN = "158"  !CDS_PN = "158";
"VSS<42>":   PN = "156"  !CDS_PN = "156";
"VSS<43>":   PN = "154"  !CDS_PN = "154";
"VSS<44>":   PN = "151"  !CDS_PN = "151";
"VSS<45>":   PN = "149"  !CDS_PN = "149";
"VSS<46>":   PN = "147"  !CDS_PN = "147";
"VSS<47>":   PN = "138"  !CDS_PN = "138";
"VSS<48>":   PN = "136"  !CDS_PN = "136";
"VSS<49>":   PN = "134"  !CDS_PN = "134";
"VSS<50>":   PN = "131"  !CDS_PN = "131";
"VSS<51>":   PN = "129"  !CDS_PN = "129";
"VSS<52>":   PN = "127"  !CDS_PN = "127";
"VSS<53>":   PN = "125"  !CDS_PN = "125";
"VSS<54>":   PN = "123"  !CDS_PN = "123";
"VSS<55>":   PN = "120"  !CDS_PN = "120";
"VSS<56>":   PN = "118"  !CDS_PN = "118";
"VSS<57>":   PN = "116"  !CDS_PN = "116";
"VSS<58>":   PN = "114"  !CDS_PN = "114";
"VSS<59>":   PN = "112"  !CDS_PN = "112";
"VSS<60>":   PN = "109"  !CDS_PN = "109";
"VSS<61>":   PN = "107"  !CDS_PN = "107";
"VSS<62>":   PN = "105"  !CDS_PN = "105";
"VSS<63>":   PN = "103"  !CDS_PN = "103";
"VSS<64>":   PN = "101"  !CDS_PN = "101";
"VSS<65>":   PN = "98"  !CDS_PN = "98";
"VSS<66>":   PN = "96"  !CDS_PN = "96";
"VSS<67>":   PN = "94"  !CDS_PN = "94";
"VSS<68>":   PN = "57"  !CDS_PN = "57";
"VSS<69>":   PN = "55"  !CDS_PN = "55";
"VSS<70>":   PN = "53"  !CDS_PN = "53";
"VSS<71>":   PN = "50"  !CDS_PN = "50";
"VSS<72>":   PN = "48"  !CDS_PN = "48";
"VSS<73>":   PN = "46"  !CDS_PN = "46";
"VSS<74>":   PN = "44"  !CDS_PN = "44";
"VSS<75>":   PN = "42"  !CDS_PN = "42";
"VSS<76>":   PN = "39"  !CDS_PN = "39";
"VSS<77>":   PN = "37"  !CDS_PN = "37";
"VSS<78>":   PN = "35"  !CDS_PN = "35";
"VSS<79>":   PN = "33"  !CDS_PN = "33";
"VSS<80>":   PN = "31"  !CDS_PN = "31";
"VSS<81>":   PN = "28"  !CDS_PN = "28";
"VSS<82>":   PN = "26"  !CDS_PN = "26";
"VSS<83>":   PN = "24"  !CDS_PN = "24";
"VSS<84>":   PN = "22"  !CDS_PN = "22";
"VSS<85>":   PN = "20"  !CDS_PN = "20";
"VSS<86>":   PN = "17"  !CDS_PN = "17";
"VSS<87>":   PN = "15"  !CDS_PN = "15";
"VSS<88>":   PN = "13"  !CDS_PN = "13";
"VSS<89>":   PN = "11"  !CDS_PN = "11";
"VSS<90>":   PN = "9"  !CDS_PN = "9";
"VSS<91>":   PN = "6"  !CDS_PN = "6";
"VSS<92>":   PN = "4"  !CDS_PN = "4";
"VSS<93>":   PN = "2"  !CDS_PN = "2";
BODY = "SCONN288_H44441004","I66": #LOCATION = "J1B1" !CDS_LOCATION = "J1B1" #SEC = "2" !CDS_SEC = "2";
"DQS0N":   PN = "152"  !CDS_PN = "152";
"DQS0P":   PN = "153"  !CDS_PN = "153";
"DQS1N":   PN = "163"  !CDS_PN = "163";
"DQS1P":   PN = "164"  !CDS_PN = "164";
"DQS2N":   PN = "174"  !CDS_PN = "174";
"DQS2P":   PN = "175"  !CDS_PN = "175";
"DQS3N":   PN = "185"  !CDS_PN = "185";
"DQS3P":   PN = "186"  !CDS_PN = "186";
"DQS4N":   PN = "244"  !CDS_PN = "244";
"DQS4P":   PN = "245"  !CDS_PN = "245";
"DQS5N":   PN = "255"  !CDS_PN = "255";
"DQS5P":   PN = "256"  !CDS_PN = "256";
"DQS6N":   PN = "266"  !CDS_PN = "266";
"DQS6P":   PN = "267"  !CDS_PN = "267";
"DQS7N":   PN = "277"  !CDS_PN = "277";
"DQS7P":   PN = "278"  !CDS_PN = "278";
"DQS8N":   PN = "196"  !CDS_PN = "196";
"DQS8P":   PN = "197"  !CDS_PN = "197";
"DQS9N":   PN = "8"  !CDS_PN = "8";
"DQS9P":   PN = "7"  !CDS_PN = "7";
"DQS10N":   PN = "19"  !CDS_PN = "19";
"DQS10P":   PN = "18"  !CDS_PN = "18";
"DQS11N":   PN = "30"  !CDS_PN = "30";
"DQS11P":   PN = "29"  !CDS_PN = "29";
"DQS12N":   PN = "41"  !CDS_PN = "41";
"DQS12P":   PN = "40"  !CDS_PN = "40";
"DQS13N":   PN = "100"  !CDS_PN = "100";
"DQS13P":   PN = "99"  !CDS_PN = "99";
"DQS14N":   PN = "111"  !CDS_PN = "111";
"DQS14P":   PN = "110"  !CDS_PN = "110";
"DQS15N":   PN = "122"  !CDS_PN = "122";
"DQS15P":   PN = "121"  !CDS_PN = "121";
"DQS16N":   PN = "133"  !CDS_PN = "133";
"DQS16P":   PN = "132"  !CDS_PN = "132";
"DQS17N":   PN = "52"  !CDS_PN = "52";
"DQS17P":   PN = "51"  !CDS_PN = "51";
BODY = "SCONN288_H44441004","I111": #LOCATION = "J1B1" !CDS_LOCATION = "J1B1" #SEC = "1" !CDS_SEC = "1";
"A0":   PN = "79"  !CDS_PN = "79";
"A1":   PN = "72"  !CDS_PN = "72";
"A2":   PN = "216"  !CDS_PN = "216";
"A3":   PN = "71"  !CDS_PN = "71";
"A4":   PN = "214"  !CDS_PN = "214";
"A5":   PN = "213"  !CDS_PN = "213";
"A6":   PN = "69"  !CDS_PN = "69";
"A7":   PN = "211"  !CDS_PN = "211";
"A8":   PN = "68"  !CDS_PN = "68";
"A9":   PN = "66"  !CDS_PN = "66";
"A10":   PN = "225"  !CDS_PN = "225";
"A11":   PN = "210"  !CDS_PN = "210";
"A12":   PN = "65"  !CDS_PN = "65";
"A13":   PN = "232"  !CDS_PN = "232";
"A14_WE_N":   PN = "228"  !CDS_PN = "228";
"A15_CAS_N":   PN = "86"  !CDS_PN = "86";
"A16_RAS_N":   PN = "82"  !CDS_PN = "82";
"A17":   PN = "234"  !CDS_PN = "234";
"ACT_N":   PN = "62"  !CDS_PN = "62";
"ALERT_N":   PN = "208"  !CDS_PN = "208";
"BA<0>":   PN = "81"  !CDS_PN = "81";
"BA<1>":   PN = "224"  !CDS_PN = "224";
"BG<0>":   PN = "63"  !CDS_PN = "63";
"BG<1>":   PN = "207"  !CDS_PN = "207";
"C<2>":   PN = "235"  !CDS_PN = "235";
"CB<0>":   PN = "49"  !CDS_PN = "49";
"CB<1>":   PN = "194"  !CDS_PN = "194";
"CB<2>":   PN = "56"  !CDS_PN = "56";
"CB<3>":   PN = "201"  !CDS_PN = "201";
"CB<4>":   PN = "47"  !CDS_PN = "47";
"CB<5>":   PN = "192"  !CDS_PN = "192";
"CB<6>":   PN = "54"  !CDS_PN = "54";
"CB<7>":   PN = "199"  !CDS_PN = "199";
"CK0N":   PN = "75"  !CDS_PN = "75";
"CK0P":   PN = "74"  !CDS_PN = "74";
"CK1N":   PN = "219"  !CDS_PN = "219";
"CK1P":   PN = "218"  !CDS_PN = "218";
"CKE<0>":   PN = "60"  !CDS_PN = "60";
"CKE<1>":   PN = "203"  !CDS_PN = "203";
"DQ<0>":   PN = "5"  !CDS_PN = "5";
"DQ<1>":   PN = "150"  !CDS_PN = "150";
"DQ<2>":   PN = "12"  !CDS_PN = "12";
"DQ<3>":   PN = "157"  !CDS_PN = "157";
"DQ<4>":   PN = "3"  !CDS_PN = "3";
"DQ<5>":   PN = "148"  !CDS_PN = "148";
"DQ<6>":   PN = "10"  !CDS_PN = "10";
"DQ<7>":   PN = "155"  !CDS_PN = "155";
"DQ<8>":   PN = "16"  !CDS_PN = "16";
"DQ<9>":   PN = "161"  !CDS_PN = "161";
"DQ<10>":   PN = "23"  !CDS_PN = "23";
"DQ<11>":   PN = "168"  !CDS_PN = "168";
"DQ<12>":   PN = "14"  !CDS_PN = "14";
"DQ<13>":   PN = "159"  !CDS_PN = "159";
"DQ<14>":   PN = "21"  !CDS_PN = "21";
"DQ<15>":   PN = "166"  !CDS_PN = "166";
"DQ<16>":   PN = "27"  !CDS_PN = "27";
"DQ<17>":   PN = "172"  !CDS_PN = "172";
"DQ<18>":   PN = "34"  !CDS_PN = "34";
"DQ<19>":   PN = "179"  !CDS_PN = "179";
"DQ<20>":   PN = "25"  !CDS_PN = "25";
"DQ<21>":   PN = "170"  !CDS_PN = "170";
"DQ<22>":   PN = "32"  !CDS_PN = "32";
"DQ<23>":   PN = "177"  !CDS_PN = "177";
"DQ<24>":   PN = "38"  !CDS_PN = "38";
"DQ<25>":   PN = "183"  !CDS_PN = "183";
"DQ<26>":   PN = "45"  !CDS_PN = "45";
"DQ<27>":   PN = "190"  !CDS_PN = "190";
"DQ<28>":   PN = "36"  !CDS_PN = "36";
"DQ<29>":   PN = "181"  !CDS_PN = "181";
"DQ<30>":   PN = "43"  !CDS_PN = "43";
"DQ<31>":   PN = "188"  !CDS_PN = "188";
"DQ<32>":   PN = "97"  !CDS_PN = "97";
"DQ<33>":   PN = "242"  !CDS_PN = "242";
"DQ<34>":   PN = "104"  !CDS_PN = "104";
"DQ<35>":   PN = "249"  !CDS_PN = "249";
"DQ<36>":   PN = "95"  !CDS_PN = "95";
"DQ<37>":   PN = "240"  !CDS_PN = "240";
"DQ<38>":   PN = "102"  !CDS_PN = "102";
"DQ<39>":   PN = "247"  !CDS_PN = "247";
"DQ<40>":   PN = "108"  !CDS_PN = "108";
"DQ<41>":   PN = "253"  !CDS_PN = "253";
"DQ<42>":   PN = "115"  !CDS_PN = "115";
"DQ<43>":   PN = "260"  !CDS_PN = "260";
"DQ<44>":   PN = "106"  !CDS_PN = "106";
"DQ<45>":   PN = "251"  !CDS_PN = "251";
"DQ<46>":   PN = "113"  !CDS_PN = "113";
"DQ<47>":   PN = "258"  !CDS_PN = "258";
"DQ<48>":   PN = "119"  !CDS_PN = "119";
"DQ<49>":   PN = "264"  !CDS_PN = "264";
"DQ<50>":   PN = "126"  !CDS_PN = "126";
"DQ<51>":   PN = "271"  !CDS_PN = "271";
"DQ<52>":   PN = "117"  !CDS_PN = "117";
"DQ<53>":   PN = "262"  !CDS_PN = "262";
"DQ<54>":   PN = "124"  !CDS_PN = "124";
"DQ<55>":   PN = "269"  !CDS_PN = "269";
"DQ<56>":   PN = "130"  !CDS_PN = "130";
"DQ<57>":   PN = "275"  !CDS_PN = "275";
"DQ<58>":   PN = "137"  !CDS_PN = "137";
"DQ<59>":   PN = "282"  !CDS_PN = "282";
"DQ<60>":   PN = "128"  !CDS_PN = "128";
"DQ<61>":   PN = "273"  !CDS_PN = "273";
"DQ<62>":   PN = "135"  !CDS_PN = "135";
"DQ<63>":   PN = "280"  !CDS_PN = "280";
"EVENT_N":   PN = "78"  !CDS_PN = "78";
"ODT<0>":   PN = "87"  !CDS_PN = "87";
"ODT<1>":   PN = "91"  !CDS_PN = "91";
"PAR":   PN = "222"  !CDS_PN = "222";
"RESET_N":   PN = "58"  !CDS_PN = "58";
"RFU<0>":   PN = "205"  !CDS_PN = "205";
"RFU<1>":   PN = "227"  !CDS_PN = "227";
"RFU<2>":   PN = "144"  !CDS_PN = "144";
"S0_N":   PN = "84"  !CDS_PN = "84";
"S1_N":   PN = "89"  !CDS_PN = "89";
"S2_N_C<0>":   PN = "93"  !CDS_PN = "93";
"S3_N_C<1>":   PN = "237"  !CDS_PN = "237";
"SA<0>":   PN = "139"  !CDS_PN = "139";
"SA<1>":   PN = "140"  !CDS_PN = "140";
"SA<2>":   PN = "238"  !CDS_PN = "238";
"SAVE_N_NC":   PN = "230"  !CDS_PN = "230";
"SCL":   PN = "141"  !CDS_PN = "141";
"SDA":   PN = "285"  !CDS_PN = "285";
"VDDSPD":   PN = "284"  !CDS_PN = "284";
"VREFCA":   PN = "146"  !CDS_PN = "146";
BODY = "SCONN288_H44441004","I167": #LOCATION = "J1B1" !CDS_LOCATION = "J1B1" #SEC = "4" !CDS_SEC = "4";
"12V<0>":   PN = "145"  !CDS_PN = "145";
"12V<1>":   PN = "1"  !CDS_PN = "1";
"VDD<0>":   PN = "236"  !CDS_PN = "236";
"VDD<1>":   PN = "233"  !CDS_PN = "233";
"VDD<2>":   PN = "231"  !CDS_PN = "231";
"VDD<3>":   PN = "229"  !CDS_PN = "229";
"VDD<4>":   PN = "226"  !CDS_PN = "226";
"VDD<5>":   PN = "223"  !CDS_PN = "223";
"VDD<6>":   PN = "220"  !CDS_PN = "220";
"VDD<7>":   PN = "217"  !CDS_PN = "217";
"VDD<8>":   PN = "215"  !CDS_PN = "215";
"VDD<9>":   PN = "212"  !CDS_PN = "212";
"VDD<10>":   PN = "209"  !CDS_PN = "209";
"VDD<11>":   PN = "206"  !CDS_PN = "206";
"VDD<12>":   PN = "204"  !CDS_PN = "204";
"VDD<13>":   PN = "92"  !CDS_PN = "92";
"VDD<14>":   PN = "90"  !CDS_PN = "90";
"VDD<15>":   PN = "88"  !CDS_PN = "88";
"VDD<16>":   PN = "85"  !CDS_PN = "85";
"VDD<17>":   PN = "83"  !CDS_PN = "83";
"VDD<18>":   PN = "80"  !CDS_PN = "80";
"VDD<19>":   PN = "76"  !CDS_PN = "76";
"VDD<20>":   PN = "73"  !CDS_PN = "73";
"VDD<21>":   PN = "70"  !CDS_PN = "70";
"VDD<22>":   PN = "67"  !CDS_PN = "67";
"VDD<23>":   PN = "64"  !CDS_PN = "64";
"VDD<24>":   PN = "61"  !CDS_PN = "61";
"VDD<25>":   PN = "59"  !CDS_PN = "59";
"VPP<0>":   PN = "287"  !CDS_PN = "287";
"VPP<1>":   PN = "286"  !CDS_PN = "286";
"VPP<2>":   PN = "288"  !CDS_PN = "288";
"VPP<3>":   PN = "143"  !CDS_PN = "143";
"VPP<4>":   PN = "142"  !CDS_PN = "142";
"VTT<0>":   PN = "221"  !CDS_PN = "221";
"VTT<1>":   PN = "77"  !CDS_PN = "77";
BODY = "CAP_A","I176": #LOCATION = "C1B9" !CDS_LOCATION = "C1B9" &SEC = "1" #&CDS_SEC = "1";
"A":   PN = "1"  !CDS_PN = "1";
"B":   PN = "2"  !CDS_PN = "2";
DRAWING = "@baseboard_fab2_lib.baseboard_fab2(sch_1):page84";
BODY = "CAP_A","I4": #LOCATION = "C9M1" !CDS_LOCATION = "C9M1" &SEC = "1" #&CDS_SEC = "1";
"A":   PN = "1"  !CDS_PN = "1";
"B":   PN = "2"  !CDS_PN = "2";
BODY = "SCONN288_H44441003","I14": #LOCATION = "J9M1" !CDS_LOCATION = "J9M1" #SEC = "1" !CDS_SEC = "1";
"A0":   PN = "79"  !CDS_PN = "79";
"A1":   PN = "72"  !CDS_PN = "72";
"A2":   PN = "216"  !CDS_PN = "216";
"A3":   PN = "71"  !CDS_PN = "71";
"A4":   PN = "214"  !CDS_PN = "214";
"A5":   PN = "213"  !CDS_PN = "213";
"A6":   PN = "69"  !CDS_PN = "69";
"A7":   PN = "211"  !CDS_PN = "211";
"A8":   PN = "68"  !CDS_PN = "68";
"A9":   PN = "66"  !CDS_PN = "66";
"A10":   PN = "225"  !CDS_PN = "225";
"A11":   PN = "210"  !CDS_PN = "210";
"A12":   PN = "65"  !CDS_PN = "65";
"A13":   PN = "232"  !CDS_PN = "232";
"A14_WE_N":   PN = "228"  !CDS_PN = "228";
"A15_CAS_N":   PN = "86"  !CDS_PN = "86";
"A16_RAS_N":   PN = "82"  !CDS_PN = "82";
"A17":   PN = "234"  !CDS_PN = "234";
"ACT_N":   PN = "62"  !CDS_PN = "62";
"ALERT_N":   PN = "208"  !CDS_PN = "208";
"BA<0>":   PN = "81"  !CDS_PN = "81";
"BA<1>":   PN = "224"  !CDS_PN = "224";
"BG<0>":   PN = "63"  !CDS_PN = "63";
"BG<1>":   PN = "207"  !CDS_PN = "207";
"C<2>":   PN = "235"  !CDS_PN = "235";
"CB<0>":   PN = "49"  !CDS_PN = "49";
"CB<1>":   PN = "194"  !CDS_PN = "194";
"CB<2>":   PN = "56"  !CDS_PN = "56";
"CB<3>":   PN = "201"  !CDS_PN = "201";
"CB<4>":   PN = "47"  !CDS_PN = "47";
"CB<5>":   PN = "192"  !CDS_PN = "192";
"CB<6>":   PN = "54"  !CDS_PN = "54";
"CB<7>":   PN = "199"  !CDS_PN = "199";
"CK0N":   PN = "75"  !CDS_PN = "75";
"CK0P":   PN = "74"  !CDS_PN = "74";
"CK1N":   PN = "219"  !CDS_PN = "219";
"CK1P":   PN = "218"  !CDS_PN = "218";
"CKE<0>":   PN = "60"  !CDS_PN = "60";
"CKE<1>":   PN = "203"  !CDS_PN = "203";
"DQ<0>":   PN = "5"  !CDS_PN = "5";
"DQ<1>":   PN = "150"  !CDS_PN = "150";
"DQ<2>":   PN = "12"  !CDS_PN = "12";
"DQ<3>":   PN = "157"  !CDS_PN = "157";
"DQ<4>":   PN = "3"  !CDS_PN = "3";
"DQ<5>":   PN = "148"  !CDS_PN = "148";
"DQ<6>":   PN = "10"  !CDS_PN = "10";
"DQ<7>":   PN = "155"  !CDS_PN = "155";
"DQ<8>":   PN = "16"  !CDS_PN = "16";
"DQ<9>":   PN = "161"  !CDS_PN = "161";
"DQ<10>":   PN = "23"  !CDS_PN = "23";
"DQ<11>":   PN = "168"  !CDS_PN = "168";
"DQ<12>":   PN = "14"  !CDS_PN = "14";
"DQ<13>":   PN = "159"  !CDS_PN = "159";
"DQ<14>":   PN = "21"  !CDS_PN = "21";
"DQ<15>":   PN = "166"  !CDS_PN = "166";
"DQ<16>":   PN = "27"  !CDS_PN = "27";
"DQ<17>":   PN = "172"  !CDS_PN = "172";
"DQ<18>":   PN = "34"  !CDS_PN = "34";
"DQ<19>":   PN = "179"  !CDS_PN = "179";
"DQ<20>":   PN = "25"  !CDS_PN = "25";
"DQ<21>":   PN = "170"  !CDS_PN = "170";
"DQ<22>":   PN = "32"  !CDS_PN = "32";
"DQ<23>":   PN = "177"  !CDS_PN = "177";
"DQ<24>":   PN = "38"  !CDS_PN = "38";
"DQ<25>":   PN = "183"  !CDS_PN = "183";
"DQ<26>":   PN = "45"  !CDS_PN = "45";
"DQ<27>":   PN = "190"  !CDS_PN = "190";
"DQ<28>":   PN = "36"  !CDS_PN = "36";
"DQ<29>":   PN = "181"  !CDS_PN = "181";
"DQ<30>":   PN = "43"  !CDS_PN = "43";
"DQ<31>":   PN = "188"  !CDS_PN = "188";
"DQ<32>":   PN = "97"  !CDS_PN = "97";
"DQ<33>":   PN = "242"  !CDS_PN = "242";
"DQ<34>":   PN = "104"  !CDS_PN = "104";
"DQ<35>":   PN = "249"  !CDS_PN = "249";
"DQ<36>":   PN = "95"  !CDS_PN = "95";
"DQ<37>":   PN = "240"  !CDS_PN = "240";
"DQ<38>":   PN = "102"  !CDS_PN = "102";
"DQ<39>":   PN = "247"  !CDS_PN = "247";
"DQ<40>":   PN = "108"  !CDS_PN = "108";
"DQ<41>":   PN = "253"  !CDS_PN = "253";
"DQ<42>":   PN = "115"  !CDS_PN = "115";
"DQ<43>":   PN = "260"  !CDS_PN = "260";
"DQ<44>":   PN = "106"  !CDS_PN = "106";
"DQ<45>":   PN = "251"  !CDS_PN = "251";
"DQ<46>":   PN = "113"  !CDS_PN = "113";
"DQ<47>":   PN = "258"  !CDS_PN = "258";
"DQ<48>":   PN = "119"  !CDS_PN = "119";
"DQ<49>":   PN = "264"  !CDS_PN = "264";
"DQ<50>":   PN = "126"  !CDS_PN = "126";
"DQ<51>":   PN = "271"  !CDS_PN = "271";
"DQ<52>":   PN = "117"  !CDS_PN = "117";
"DQ<53>":   PN = "262"  !CDS_PN = "262";
"DQ<54>":   PN = "124"  !CDS_PN = "124";
"DQ<55>":   PN = "269"  !CDS_PN = "269";
"DQ<56>":   PN = "130"  !CDS_PN = "130";
"DQ<57>":   PN = "275"  !CDS_PN = "275";
"DQ<58>":   PN = "137"  !CDS_PN = "137";
"DQ<59>":   PN = "282"  !CDS_PN = "282";
"DQ<60>":   PN = "128"  !CDS_PN = "128";
"DQ<61>":   PN = "273"  !CDS_PN = "273";
"DQ<62>":   PN = "135"  !CDS_PN = "135";
"DQ<63>":   PN = "280"  !CDS_PN = "280";
"EVENT_N":   PN = "78"  !CDS_PN = "78";
"ODT<0>":   PN = "87"  !CDS_PN = "87";
"ODT<1>":   PN = "91"  !CDS_PN = "91";
"PAR":   PN = "222"  !CDS_PN = "222";
"RESET_N":   PN = "58"  !CDS_PN = "58";
"RFU<0>":   PN = "205"  !CDS_PN = "205";
"RFU<1>":   PN = "227"  !CDS_PN = "227";
"RFU<2>":   PN = "144"  !CDS_PN = "144";
"S0_N":   PN = "84"  !CDS_PN = "84";
"S1_N":   PN = "89"  !CDS_PN = "89";
"S2_N_C<0>":   PN = "93"  !CDS_PN = "93";
"S3_N_C<1>":   PN = "237"  !CDS_PN = "237";
"SA<0>":   PN = "139"  !CDS_PN = "139";
"SA<1>":   PN = "140"  !CDS_PN = "140";
"SA<2>":   PN = "238"  !CDS_PN = "238";
"SAVE_N_NC":   PN = "230"  !CDS_PN = "230";
"SCL":   PN = "141"  !CDS_PN = "141";
"SDA":   PN = "285"  !CDS_PN = "285";
"VDDSPD":   PN = "284"  !CDS_PN = "284";
"VREFCA":   PN = "146"  !CDS_PN = "146";
BODY = "SCONN288_H44441003","I57": #LOCATION = "J9M1" !CDS_LOCATION = "J9M1" #SEC = "4" !CDS_SEC = "4";
"12V<0>":   PN = "145"  !CDS_PN = "145";
"12V<1>":   PN = "1"  !CDS_PN = "1";
"VDD<0>":   PN = "236"  !CDS_PN = "236";
"VDD<1>":   PN = "233"  !CDS_PN = "233";
"VDD<2>":   PN = "231"  !CDS_PN = "231";
"VDD<3>":   PN = "229"  !CDS_PN = "229";
"VDD<4>":   PN = "226"  !CDS_PN = "226";
"VDD<5>":   PN = "223"  !CDS_PN = "223";
"VDD<6>":   PN = "220"  !CDS_PN = "220";
"VDD<7>":   PN = "217"  !CDS_PN = "217";
"VDD<8>":   PN = "215"  !CDS_PN = "215";
"VDD<9>":   PN = "212"  !CDS_PN = "212";
"VDD<10>":   PN = "209"  !CDS_PN = "209";
"VDD<11>":   PN = "206"  !CDS_PN = "206";
"VDD<12>":   PN = "204"  !CDS_PN = "204";
"VDD<13>":   PN = "92"  !CDS_PN = "92";
"VDD<14>":   PN = "90"  !CDS_PN = "90";
"VDD<15>":   PN = "88"  !CDS_PN = "88";
"VDD<16>":   PN = "85"  !CDS_PN = "85";
"VDD<17>":   PN = "83"  !CDS_PN = "83";
"VDD<18>":   PN = "80"  !CDS_PN = "80";
"VDD<19>":   PN = "76"  !CDS_PN = "76";
"VDD<20>":   PN = "73"  !CDS_PN = "73";
"VDD<21>":   PN = "70"  !CDS_PN = "70";
"VDD<22>":   PN = "67"  !CDS_PN = "67";
"VDD<23>":   PN = "64"  !CDS_PN = "64";
"VDD<24>":   PN = "61"  !CDS_PN = "61";
"VDD<25>":   PN = "59"  !CDS_PN = "59";
"VPP<0>":   PN = "287"  !CDS_PN = "287";
"VPP<1>":   PN = "286"  !CDS_PN = "286";
"VPP<2>":   PN = "288"  !CDS_PN = "288";
"VPP<3>":   PN = "143"  !CDS_PN = "143";
"VPP<4>":   PN = "142"  !CDS_PN = "142";
"VTT<0>":   PN = "221"  !CDS_PN = "221";
"VTT<1>":   PN = "77"  !CDS_PN = "77";
BODY = "SCONN288_H44441003","I102": #LOCATION = "J9M1" !CDS_LOCATION = "J9M1" #SEC = "2" !CDS_SEC = "2";
"DQS0N":   PN = "152"  !CDS_PN = "152";
"DQS0P":   PN = "153"  !CDS_PN = "153";
"DQS1N":   PN = "163"  !CDS_PN = "163";
"DQS1P":   PN = "164"  !CDS_PN = "164";
"DQS2N":   PN = "174"  !CDS_PN = "174";
"DQS2P":   PN = "175"  !CDS_PN = "175";
"DQS3N":   PN = "185"  !CDS_PN = "185";
"DQS3P":   PN = "186"  !CDS_PN = "186";
"DQS4N":   PN = "244"  !CDS_PN = "244";
"DQS4P":   PN = "245"  !CDS_PN = "245";
"DQS5N":   PN = "255"  !CDS_PN = "255";
"DQS5P":   PN = "256"  !CDS_PN = "256";
"DQS6N":   PN = "266"  !CDS_PN = "266";
"DQS6P":   PN = "267"  !CDS_PN = "267";
"DQS7N":   PN = "277"  !CDS_PN = "277";
"DQS7P":   PN = "278"  !CDS_PN = "278";
"DQS8N":   PN = "196"  !CDS_PN = "196";
"DQS8P":   PN = "197"  !CDS_PN = "197";
"DQS9N":   PN = "8"  !CDS_PN = "8";
"DQS9P":   PN = "7"  !CDS_PN = "7";
"DQS10N":   PN = "19"  !CDS_PN = "19";
"DQS10P":   PN = "18"  !CDS_PN = "18";
"DQS11N":   PN = "30"  !CDS_PN = "30";
"DQS11P":   PN = "29"  !CDS_PN = "29";
"DQS12N":   PN = "41"  !CDS_PN = "41";
"DQS12P":   PN = "40"  !CDS_PN = "40";
"DQS13N":   PN = "100"  !CDS_PN = "100";
"DQS13P":   PN = "99"  !CDS_PN = "99";
"DQS14N":   PN = "111"  !CDS_PN = "111";
"DQS14P":   PN = "110"  !CDS_PN = "110";
"DQS15N":   PN = "122"  !CDS_PN = "122";
"DQS15P":   PN = "121"  !CDS_PN = "121";
"DQS16N":   PN = "133"  !CDS_PN = "133";
"DQS16P":   PN = "132"  !CDS_PN = "132";
"DQS17N":   PN = "52"  !CDS_PN = "52";
"DQS17P":   PN = "51"  !CDS_PN = "51";
BODY = "SCONN288_H44441003","I138": #LOCATION = "J9M1" !CDS_LOCATION = "J9M1" #SEC = "3" !CDS_SEC = "3";
"VSS<0>":   PN = "283"  !CDS_PN = "283";
"VSS<1>":   PN = "281"  !CDS_PN = "281";
"VSS<2>":   PN = "279"  !CDS_PN = "279";
"VSS<3>":   PN = "276"  !CDS_PN = "276";
"VSS<4>":   PN = "274"  !CDS_PN = "274";
"VSS<5>":   PN = "272"  !CDS_PN = "272";
"VSS<6>":   PN = "270"  !CDS_PN = "270";
"VSS<7>":   PN = "268"  !CDS_PN = "268";
"VSS<8>":   PN = "265"  !CDS_PN = "265";
"VSS<9>":   PN = "263"  !CDS_PN = "263";
"VSS<10>":   PN = "261"  !CDS_PN = "261";
"VSS<11>":   PN = "259"  !CDS_PN = "259";
"VSS<12>":   PN = "257"  !CDS_PN = "257";
"VSS<13>":   PN = "254"  !CDS_PN = "254";
"VSS<14>":   PN = "252"  !CDS_PN = "252";
"VSS<15>":   PN = "250"  !CDS_PN = "250";
"VSS<16>":   PN = "248"  !CDS_PN = "248";
"VSS<17>":   PN = "246"  !CDS_PN = "246";
"VSS<18>":   PN = "243"  !CDS_PN = "243";
"VSS<19>":   PN = "241"  !CDS_PN = "241";
"VSS<20>":   PN = "239"  !CDS_PN = "239";
"VSS<21>":   PN = "202"  !CDS_PN = "202";
"VSS<22>":   PN = "200"  !CDS_PN = "200";
"VSS<23>":   PN = "198"  !CDS_PN = "198";
"VSS<24>":   PN = "195"  !CDS_PN = "195";
"VSS<25>":   PN = "193"  !CDS_PN = "193";
"VSS<26>":   PN = "191"  !CDS_PN = "191";
"VSS<27>":   PN = "189"  !CDS_PN = "189";
"VSS<28>":   PN = "187"  !CDS_PN = "187";
"VSS<29>":   PN = "184"  !CDS_PN = "184";
"VSS<30>":   PN = "182"  !CDS_PN = "182";
"VSS<31>":   PN = "180"  !CDS_PN = "180";
"VSS<32>":   PN = "178"  !CDS_PN = "178";
"VSS<33>":   PN = "176"  !CDS_PN = "176";
"VSS<34>":   PN = "173"  !CDS_PN = "173";
"VSS<35>":   PN = "171"  !CDS_PN = "171";
"VSS<36>":   PN = "169"  !CDS_PN = "169";
"VSS<37>":   PN = "167"  !CDS_PN = "167";
"VSS<38>":   PN = "165"  !CDS_PN = "165";
"VSS<39>":   PN = "162"  !CDS_PN = "162";
"VSS<40>":   PN = "160"  !CDS_PN = "160";
"VSS<41>":   PN = "158"  !CDS_PN = "158";
"VSS<42>":   PN = "156"  !CDS_PN = "156";
"VSS<43>":   PN = "154"  !CDS_PN = "154";
"VSS<44>":   PN = "151"  !CDS_PN = "151";
"VSS<45>":   PN = "149"  !CDS_PN = "149";
"VSS<46>":   PN = "147"  !CDS_PN = "147";
"VSS<47>":   PN = "138"  !CDS_PN = "138";
"VSS<48>":   PN = "136"  !CDS_PN = "136";
"VSS<49>":   PN = "134"  !CDS_PN = "134";
"VSS<50>":   PN = "131"  !CDS_PN = "131";
"VSS<51>":   PN = "129"  !CDS_PN = "129";
"VSS<52>":   PN = "127"  !CDS_PN = "127";
"VSS<53>":   PN = "125"  !CDS_PN = "125";
"VSS<54>":   PN = "123"  !CDS_PN = "123";
"VSS<55>":   PN = "120"  !CDS_PN = "120";
"VSS<56>":   PN = "118"  !CDS_PN = "118";
"VSS<57>":   PN = "116"  !CDS_PN = "116";
"VSS<58>":   PN = "114"  !CDS_PN = "114";
"VSS<59>":   PN = "112"  !CDS_PN = "112";
"VSS<60>":   PN = "109"  !CDS_PN = "109";
"VSS<61>":   PN = "107"  !CDS_PN = "107";
"VSS<62>":   PN = "105"  !CDS_PN = "105";
"VSS<63>":   PN = "103"  !CDS_PN = "103";
"VSS<64>":   PN = "101"  !CDS_PN = "101";
"VSS<65>":   PN = "98"  !CDS_PN = "98";
"VSS<66>":   PN = "96"  !CDS_PN = "96";
"VSS<67>":   PN = "94"  !CDS_PN = "94";
"VSS<68>":   PN = "57"  !CDS_PN = "57";
"VSS<69>":   PN = "55"  !CDS_PN = "55";
"VSS<70>":   PN = "53"  !CDS_PN = "53";
"VSS<71>":   PN = "50"  !CDS_PN = "50";
"VSS<72>":   PN = "48"  !CDS_PN = "48";
"VSS<73>":   PN = "46"  !CDS_PN = "46";
"VSS<74>":   PN = "44"  !CDS_PN = "44";
"VSS<75>":   PN = "42"  !CDS_PN = "42";
"VSS<76>":   PN = "39"  !CDS_PN = "39";
"VSS<77>":   PN = "37"  !CDS_PN = "37";
"VSS<78>":   PN = "35"  !CDS_PN = "35";
"VSS<79>":   PN = "33"  !CDS_PN = "33";
"VSS<80>":   PN = "31"  !CDS_PN = "31";
"VSS<81>":   PN = "28"  !CDS_PN = "28";
"VSS<82>":   PN = "26"  !CDS_PN = "26";
"VSS<83>":   PN = "24"  !CDS_PN = "24";
"VSS<84>":   PN = "22"  !CDS_PN = "22";
"VSS<85>":   PN = "20"  !CDS_PN = "20";
"VSS<86>":   PN = "17"  !CDS_PN = "17";
"VSS<87>":   PN = "15"  !CDS_PN = "15";
"VSS<88>":   PN = "13"  !CDS_PN = "13";
"VSS<89>":   PN = "11"  !CDS_PN = "11";
"VSS<90>":   PN = "9"  !CDS_PN = "9";
"VSS<91>":   PN = "6"  !CDS_PN = "6";
"VSS<92>":   PN = "4"  !CDS_PN = "4";
"VSS<93>":   PN = "2"  !CDS_PN = "2";
DRAWING = "@baseboard_fab2_lib.baseboard_fab2(sch_1):page85";
BODY = "SCONN288_H44441004","I43": #LOCATION = "J1A2" !CDS_LOCATION = "J1A2" #SEC = "3" !CDS_SEC = "3";
"VSS<0>":   PN = "283"  !CDS_PN = "283";
"VSS<1>":   PN = "281"  !CDS_PN = "281";
"VSS<2>":   PN = "279"  !CDS_PN = "279";
"VSS<3>":   PN = "276"  !CDS_PN = "276";
"VSS<4>":   PN = "274"  !CDS_PN = "274";
"VSS<5>":   PN = "272"  !CDS_PN = "272";
"VSS<6>":   PN = "270"  !CDS_PN = "270";
"VSS<7>":   PN = "268"  !CDS_PN = "268";
"VSS<8>":   PN = "265"  !CDS_PN = "265";
"VSS<9>":   PN = "263"  !CDS_PN = "263";
"VSS<10>":   PN = "261"  !CDS_PN = "261";
"VSS<11>":   PN = "259"  !CDS_PN = "259";
"VSS<12>":   PN = "257"  !CDS_PN = "257";
"VSS<13>":   PN = "254"  !CDS_PN = "254";
"VSS<14>":   PN = "252"  !CDS_PN = "252";
"VSS<15>":   PN = "250"  !CDS_PN = "250";
"VSS<16>":   PN = "248"  !CDS_PN = "248";
"VSS<17>":   PN = "246"  !CDS_PN = "246";
"VSS<18>":   PN = "243"  !CDS_PN = "243";
"VSS<19>":   PN = "241"  !CDS_PN = "241";
"VSS<20>":   PN = "239"  !CDS_PN = "239";
"VSS<21>":   PN = "202"  !CDS_PN = "202";
"VSS<22>":   PN = "200"  !CDS_PN = "200";
"VSS<23>":   PN = "198"  !CDS_PN = "198";
"VSS<24>":   PN = "195"  !CDS_PN = "195";
"VSS<25>":   PN = "193"  !CDS_PN = "193";
"VSS<26>":   PN = "191"  !CDS_PN = "191";
"VSS<27>":   PN = "189"  !CDS_PN = "189";
"VSS<28>":   PN = "187"  !CDS_PN = "187";
"VSS<29>":   PN = "184"  !CDS_PN = "184";
"VSS<30>":   PN = "182"  !CDS_PN = "182";
"VSS<31>":   PN = "180"  !CDS_PN = "180";
"VSS<32>":   PN = "178"  !CDS_PN = "178";
"VSS<33>":   PN = "176"  !CDS_PN = "176";
"VSS<34>":   PN = "173"  !CDS_PN = "173";
"VSS<35>":   PN = "171"  !CDS_PN = "171";
"VSS<36>":   PN = "169"  !CDS_PN = "169";
"VSS<37>":   PN = "167"  !CDS_PN = "167";
"VSS<38>":   PN = "165"  !CDS_PN = "165";
"VSS<39>":   PN = "162"  !CDS_PN = "162";
"VSS<40>":   PN = "160"  !CDS_PN = "160";
"VSS<41>":   PN = "158"  !CDS_PN = "158";
"VSS<42>":   PN = "156"  !CDS_PN = "156";
"VSS<43>":   PN = "154"  !CDS_PN = "154";
"VSS<44>":   PN = "151"  !CDS_PN = "151";
"VSS<45>":   PN = "149"  !CDS_PN = "149";
"VSS<46>":   PN = "147"  !CDS_PN = "147";
"VSS<47>":   PN = "138"  !CDS_PN = "138";
"VSS<48>":   PN = "136"  !CDS_PN = "136";
"VSS<49>":   PN = "134"  !CDS_PN = "134";
"VSS<50>":   PN = "131"  !CDS_PN = "131";
"VSS<51>":   PN = "129"  !CDS_PN = "129";
"VSS<52>":   PN = "127"  !CDS_PN = "127";
"VSS<53>":   PN = "125"  !CDS_PN = "125";
"VSS<54>":   PN = "123"  !CDS_PN = "123";
"VSS<55>":   PN = "120"  !CDS_PN = "120";
"VSS<56>":   PN = "118"  !CDS_PN = "118";
"VSS<57>":   PN = "116"  !CDS_PN = "116";
"VSS<58>":   PN = "114"  !CDS_PN = "114";
"VSS<59>":   PN = "112"  !CDS_PN = "112";
"VSS<60>":   PN = "109"  !CDS_PN = "109";
"VSS<61>":   PN = "107"  !CDS_PN = "107";
"VSS<62>":   PN = "105"  !CDS_PN = "105";
"VSS<63>":   PN = "103"  !CDS_PN = "103";
"VSS<64>":   PN = "101"  !CDS_PN = "101";
"VSS<65>":   PN = "98"  !CDS_PN = "98";
"VSS<66>":   PN = "96"  !CDS_PN = "96";
"VSS<67>":   PN = "94"  !CDS_PN = "94";
"VSS<68>":   PN = "57"  !CDS_PN = "57";
"VSS<69>":   PN = "55"  !CDS_PN = "55";
"VSS<70>":   PN = "53"  !CDS_PN = "53";
"VSS<71>":   PN = "50"  !CDS_PN = "50";
"VSS<72>":   PN = "48"  !CDS_PN = "48";
"VSS<73>":   PN = "46"  !CDS_PN = "46";
"VSS<74>":   PN = "44"  !CDS_PN = "44";
"VSS<75>":   PN = "42"  !CDS_PN = "42";
"VSS<76>":   PN = "39"  !CDS_PN = "39";
"VSS<77>":   PN = "37"  !CDS_PN = "37";
"VSS<78>":   PN = "35"  !CDS_PN = "35";
"VSS<79>":   PN = "33"  !CDS_PN = "33";
"VSS<80>":   PN = "31"  !CDS_PN = "31";
"VSS<81>":   PN = "28"  !CDS_PN = "28";
"VSS<82>":   PN = "26"  !CDS_PN = "26";
"VSS<83>":   PN = "24"  !CDS_PN = "24";
"VSS<84>":   PN = "22"  !CDS_PN = "22";
"VSS<85>":   PN = "20"  !CDS_PN = "20";
"VSS<86>":   PN = "17"  !CDS_PN = "17";
"VSS<87>":   PN = "15"  !CDS_PN = "15";
"VSS<88>":   PN = "13"  !CDS_PN = "13";
"VSS<89>":   PN = "11"  !CDS_PN = "11";
"VSS<90>":   PN = "9"  !CDS_PN = "9";
"VSS<91>":   PN = "6"  !CDS_PN = "6";
"VSS<92>":   PN = "4"  !CDS_PN = "4";
"VSS<93>":   PN = "2"  !CDS_PN = "2";
BODY = "SCONN288_H44441004","I66": #LOCATION = "J1A2" !CDS_LOCATION = "J1A2" #SEC = "2" !CDS_SEC = "2";
"DQS0N":   PN = "152"  !CDS_PN = "152";
"DQS0P":   PN = "153"  !CDS_PN = "153";
"DQS1N":   PN = "163"  !CDS_PN = "163";
"DQS1P":   PN = "164"  !CDS_PN = "164";
"DQS2N":   PN = "174"  !CDS_PN = "174";
"DQS2P":   PN = "175"  !CDS_PN = "175";
"DQS3N":   PN = "185"  !CDS_PN = "185";
"DQS3P":   PN = "186"  !CDS_PN = "186";
"DQS4N":   PN = "244"  !CDS_PN = "244";
"DQS4P":   PN = "245"  !CDS_PN = "245";
"DQS5N":   PN = "255"  !CDS_PN = "255";
"DQS5P":   PN = "256"  !CDS_PN = "256";
"DQS6N":   PN = "266"  !CDS_PN = "266";
"DQS6P":   PN = "267"  !CDS_PN = "267";
"DQS7N":   PN = "277"  !CDS_PN = "277";
"DQS7P":   PN = "278"  !CDS_PN = "278";
"DQS8N":   PN = "196"  !CDS_PN = "196";
"DQS8P":   PN = "197"  !CDS_PN = "197";
"DQS9N":   PN = "8"  !CDS_PN = "8";
"DQS9P":   PN = "7"  !CDS_PN = "7";
"DQS10N":   PN = "19"  !CDS_PN = "19";
"DQS10P":   PN = "18"  !CDS_PN = "18";
"DQS11N":   PN = "30"  !CDS_PN = "30";
"DQS11P":   PN = "29"  !CDS_PN = "29";
"DQS12N":   PN = "41"  !CDS_PN = "41";
"DQS12P":   PN = "40"  !CDS_PN = "40";
"DQS13N":   PN = "100"  !CDS_PN = "100";
"DQS13P":   PN = "99"  !CDS_PN = "99";
"DQS14N":   PN = "111"  !CDS_PN = "111";
"DQS14P":   PN = "110"  !CDS_PN = "110";
"DQS15N":   PN = "122"  !CDS_PN = "122";
"DQS15P":   PN = "121"  !CDS_PN = "121";
"DQS16N":   PN = "133"  !CDS_PN = "133";
"DQS16P":   PN = "132"  !CDS_PN = "132";
"DQS17N":   PN = "52"  !CDS_PN = "52";
"DQS17P":   PN = "51"  !CDS_PN = "51";
BODY = "SCONN288_H44441004","I111": #LOCATION = "J1A2" !CDS_LOCATION = "J1A2" #SEC = "1" !CDS_SEC = "1";
"A0":   PN = "79"  !CDS_PN = "79";
"A1":   PN = "72"  !CDS_PN = "72";
"A2":   PN = "216"  !CDS_PN = "216";
"A3":   PN = "71"  !CDS_PN = "71";
"A4":   PN = "214"  !CDS_PN = "214";
"A5":   PN = "213"  !CDS_PN = "213";
"A6":   PN = "69"  !CDS_PN = "69";
"A7":   PN = "211"  !CDS_PN = "211";
"A8":   PN = "68"  !CDS_PN = "68";
"A9":   PN = "66"  !CDS_PN = "66";
"A10":   PN = "225"  !CDS_PN = "225";
"A11":   PN = "210"  !CDS_PN = "210";
"A12":   PN = "65"  !CDS_PN = "65";
"A13":   PN = "232"  !CDS_PN = "232";
"A14_WE_N":   PN = "228"  !CDS_PN = "228";
"A15_CAS_N":   PN = "86"  !CDS_PN = "86";
"A16_RAS_N":   PN = "82"  !CDS_PN = "82";
"A17":   PN = "234"  !CDS_PN = "234";
"ACT_N":   PN = "62"  !CDS_PN = "62";
"ALERT_N":   PN = "208"  !CDS_PN = "208";
"BA<0>":   PN = "81"  !CDS_PN = "81";
"BA<1>":   PN = "224"  !CDS_PN = "224";
"BG<0>":   PN = "63"  !CDS_PN = "63";
"BG<1>":   PN = "207"  !CDS_PN = "207";
"C<2>":   PN = "235"  !CDS_PN = "235";
"CB<0>":   PN = "49"  !CDS_PN = "49";
"CB<1>":   PN = "194"  !CDS_PN = "194";
"CB<2>":   PN = "56"  !CDS_PN = "56";
"CB<3>":   PN = "201"  !CDS_PN = "201";
"CB<4>":   PN = "47"  !CDS_PN = "47";
"CB<5>":   PN = "192"  !CDS_PN = "192";
"CB<6>":   PN = "54"  !CDS_PN = "54";
"CB<7>":   PN = "199"  !CDS_PN = "199";
"CK0N":   PN = "75"  !CDS_PN = "75";
"CK0P":   PN = "74"  !CDS_PN = "74";
"CK1N":   PN = "219"  !CDS_PN = "219";
"CK1P":   PN = "218"  !CDS_PN = "218";
"CKE<0>":   PN = "60"  !CDS_PN = "60";
"CKE<1>":   PN = "203"  !CDS_PN = "203";
"DQ<0>":   PN = "5"  !CDS_PN = "5";
"DQ<1>":   PN = "150"  !CDS_PN = "150";
"DQ<2>":   PN = "12"  !CDS_PN = "12";
"DQ<3>":   PN = "157"  !CDS_PN = "157";
"DQ<4>":   PN = "3"  !CDS_PN = "3";
"DQ<5>":   PN = "148"  !CDS_PN = "148";
"DQ<6>":   PN = "10"  !CDS_PN = "10";
"DQ<7>":   PN = "155"  !CDS_PN = "155";
"DQ<8>":   PN = "16"  !CDS_PN = "16";
"DQ<9>":   PN = "161"  !CDS_PN = "161";
"DQ<10>":   PN = "23"  !CDS_PN = "23";
"DQ<11>":   PN = "168"  !CDS_PN = "168";
"DQ<12>":   PN = "14"  !CDS_PN = "14";
"DQ<13>":   PN = "159"  !CDS_PN = "159";
"DQ<14>":   PN = "21"  !CDS_PN = "21";
"DQ<15>":   PN = "166"  !CDS_PN = "166";
"DQ<16>":   PN = "27"  !CDS_PN = "27";
"DQ<17>":   PN = "172"  !CDS_PN = "172";
"DQ<18>":   PN = "34"  !CDS_PN = "34";
"DQ<19>":   PN = "179"  !CDS_PN = "179";
"DQ<20>":   PN = "25"  !CDS_PN = "25";
"DQ<21>":   PN = "170"  !CDS_PN = "170";
"DQ<22>":   PN = "32"  !CDS_PN = "32";
"DQ<23>":   PN = "177"  !CDS_PN = "177";
"DQ<24>":   PN = "38"  !CDS_PN = "38";
"DQ<25>":   PN = "183"  !CDS_PN = "183";
"DQ<26>":   PN = "45"  !CDS_PN = "45";
"DQ<27>":   PN = "190"  !CDS_PN = "190";
"DQ<28>":   PN = "36"  !CDS_PN = "36";
"DQ<29>":   PN = "181"  !CDS_PN = "181";
"DQ<30>":   PN = "43"  !CDS_PN = "43";
"DQ<31>":   PN = "188"  !CDS_PN = "188";
"DQ<32>":   PN = "97"  !CDS_PN = "97";
"DQ<33>":   PN = "242"  !CDS_PN = "242";
"DQ<34>":   PN = "104"  !CDS_PN = "104";
"DQ<35>":   PN = "249"  !CDS_PN = "249";
"DQ<36>":   PN = "95"  !CDS_PN = "95";
"DQ<37>":   PN = "240"  !CDS_PN = "240";
"DQ<38>":   PN = "102"  !CDS_PN = "102";
"DQ<39>":   PN = "247"  !CDS_PN = "247";
"DQ<40>":   PN = "108"  !CDS_PN = "108";
"DQ<41>":   PN = "253"  !CDS_PN = "253";
"DQ<42>":   PN = "115"  !CDS_PN = "115";
"DQ<43>":   PN = "260"  !CDS_PN = "260";
"DQ<44>":   PN = "106"  !CDS_PN = "106";
"DQ<45>":   PN = "251"  !CDS_PN = "251";
"DQ<46>":   PN = "113"  !CDS_PN = "113";
"DQ<47>":   PN = "258"  !CDS_PN = "258";
"DQ<48>":   PN = "119"  !CDS_PN = "119";
"DQ<49>":   PN = "264"  !CDS_PN = "264";
"DQ<50>":   PN = "126"  !CDS_PN = "126";
"DQ<51>":   PN = "271"  !CDS_PN = "271";
"DQ<52>":   PN = "117"  !CDS_PN = "117";
"DQ<53>":   PN = "262"  !CDS_PN = "262";
"DQ<54>":   PN = "124"  !CDS_PN = "124";
"DQ<55>":   PN = "269"  !CDS_PN = "269";
"DQ<56>":   PN = "130"  !CDS_PN = "130";
"DQ<57>":   PN = "275"  !CDS_PN = "275";
"DQ<58>":   PN = "137"  !CDS_PN = "137";
"DQ<59>":   PN = "282"  !CDS_PN = "282";
"DQ<60>":   PN = "128"  !CDS_PN = "128";
"DQ<61>":   PN = "273"  !CDS_PN = "273";
"DQ<62>":   PN = "135"  !CDS_PN = "135";
"DQ<63>":   PN = "280"  !CDS_PN = "280";
"EVENT_N":   PN = "78"  !CDS_PN = "78";
"ODT<0>":   PN = "87"  !CDS_PN = "87";
"ODT<1>":   PN = "91"  !CDS_PN = "91";
"PAR":   PN = "222"  !CDS_PN = "222";
"RESET_N":   PN = "58"  !CDS_PN = "58";
"RFU<0>":   PN = "205"  !CDS_PN = "205";
"RFU<1>":   PN = "227"  !CDS_PN = "227";
"RFU<2>":   PN = "144"  !CDS_PN = "144";
"S0_N":   PN = "84"  !CDS_PN = "84";
"S1_N":   PN = "89"  !CDS_PN = "89";
"S2_N_C<0>":   PN = "93"  !CDS_PN = "93";
"S3_N_C<1>":   PN = "237"  !CDS_PN = "237";
"SA<0>":   PN = "139"  !CDS_PN = "139";
"SA<1>":   PN = "140"  !CDS_PN = "140";
"SA<2>":   PN = "238"  !CDS_PN = "238";
"SAVE_N_NC":   PN = "230"  !CDS_PN = "230";
"SCL":   PN = "141"  !CDS_PN = "141";
"SDA":   PN = "285"  !CDS_PN = "285";
"VDDSPD":   PN = "284"  !CDS_PN = "284";
"VREFCA":   PN = "146"  !CDS_PN = "146";
BODY = "SCONN288_H44441004","I172": #LOCATION = "J1A2" !CDS_LOCATION = "J1A2" #SEC = "4" !CDS_SEC = "4";
"12V<0>":   PN = "145"  !CDS_PN = "145";
"12V<1>":   PN = "1"  !CDS_PN = "1";
"VDD<0>":   PN = "236"  !CDS_PN = "236";
"VDD<1>":   PN = "233"  !CDS_PN = "233";
"VDD<2>":   PN = "231"  !CDS_PN = "231";
"VDD<3>":   PN = "229"  !CDS_PN = "229";
"VDD<4>":   PN = "226"  !CDS_PN = "226";
"VDD<5>":   PN = "223"  !CDS_PN = "223";
"VDD<6>":   PN = "220"  !CDS_PN = "220";
"VDD<7>":   PN = "217"  !CDS_PN = "217";
"VDD<8>":   PN = "215"  !CDS_PN = "215";
"VDD<9>":   PN = "212"  !CDS_PN = "212";
"VDD<10>":   PN = "209"  !CDS_PN = "209";
"VDD<11>":   PN = "206"  !CDS_PN = "206";
"VDD<12>":   PN = "204"  !CDS_PN = "204";
"VDD<13>":   PN = "92"  !CDS_PN = "92";
"VDD<14>":   PN = "90"  !CDS_PN = "90";
"VDD<15>":   PN = "88"  !CDS_PN = "88";
"VDD<16>":   PN = "85"  !CDS_PN = "85";
"VDD<17>":   PN = "83"  !CDS_PN = "83";
"VDD<18>":   PN = "80"  !CDS_PN = "80";
"VDD<19>":   PN = "76"  !CDS_PN = "76";
"VDD<20>":   PN = "73"  !CDS_PN = "73";
"VDD<21>":   PN = "70"  !CDS_PN = "70";
"VDD<22>":   PN = "67"  !CDS_PN = "67";
"VDD<23>":   PN = "64"  !CDS_PN = "64";
"VDD<24>":   PN = "61"  !CDS_PN = "61";
"VDD<25>":   PN = "59"  !CDS_PN = "59";
"VPP<0>":   PN = "287"  !CDS_PN = "287";
"VPP<1>":   PN = "286"  !CDS_PN = "286";
"VPP<2>":   PN = "288"  !CDS_PN = "288";
"VPP<3>":   PN = "143"  !CDS_PN = "143";
"VPP<4>":   PN = "142"  !CDS_PN = "142";
"VTT<0>":   PN = "221"  !CDS_PN = "221";
"VTT<1>":   PN = "77"  !CDS_PN = "77";
BODY = "CAP_A","I181": #LOCATION = "C9L7" !CDS_LOCATION = "C9L7" &SEC = "1" #&CDS_SEC = "1";
"A":   PN = "1"  !CDS_PN = "1";
"B":   PN = "2"  !CDS_PN = "2";
DRAWING = "@baseboard_fab2_lib.baseboard_fab2(sch_1):page86";
BODY = "SCONN288_H44441003","I12": #LOCATION = "J9L2" !CDS_LOCATION = "J9L2" #SEC = "1" !CDS_SEC = "1";
"A0":   PN = "79"  !CDS_PN = "79";
"A1":   PN = "72"  !CDS_PN = "72";
"A2":   PN = "216"  !CDS_PN = "216";
"A3":   PN = "71"  !CDS_PN = "71";
"A4":   PN = "214"  !CDS_PN = "214";
"A5":   PN = "213"  !CDS_PN = "213";
"A6":   PN = "69"  !CDS_PN = "69";
"A7":   PN = "211"  !CDS_PN = "211";
"A8":   PN = "68"  !CDS_PN = "68";
"A9":   PN = "66"  !CDS_PN = "66";
"A10":   PN = "225"  !CDS_PN = "225";
"A11":   PN = "210"  !CDS_PN = "210";
"A12":   PN = "65"  !CDS_PN = "65";
"A13":   PN = "232"  !CDS_PN = "232";
"A14_WE_N":   PN = "228"  !CDS_PN = "228";
"A15_CAS_N":   PN = "86"  !CDS_PN = "86";
"A16_RAS_N":   PN = "82"  !CDS_PN = "82";
"A17":   PN = "234"  !CDS_PN = "234";
"ACT_N":   PN = "62"  !CDS_PN = "62";
"ALERT_N":   PN = "208"  !CDS_PN = "208";
"BA<0>":   PN = "81"  !CDS_PN = "81";
"BA<1>":   PN = "224"  !CDS_PN = "224";
"BG<0>":   PN = "63"  !CDS_PN = "63";
"BG<1>":   PN = "207"  !CDS_PN = "207";
"C<2>":   PN = "235"  !CDS_PN = "235";
"CB<0>":   PN = "49"  !CDS_PN = "49";
"CB<1>":   PN = "194"  !CDS_PN = "194";
"CB<2>":   PN = "56"  !CDS_PN = "56";
"CB<3>":   PN = "201"  !CDS_PN = "201";
"CB<4>":   PN = "47"  !CDS_PN = "47";
"CB<5>":   PN = "192"  !CDS_PN = "192";
"CB<6>":   PN = "54"  !CDS_PN = "54";
"CB<7>":   PN = "199"  !CDS_PN = "199";
"CK0N":   PN = "75"  !CDS_PN = "75";
"CK0P":   PN = "74"  !CDS_PN = "74";
"CK1N":   PN = "219"  !CDS_PN = "219";
"CK1P":   PN = "218"  !CDS_PN = "218";
"CKE<0>":   PN = "60"  !CDS_PN = "60";
"CKE<1>":   PN = "203"  !CDS_PN = "203";
"DQ<0>":   PN = "5"  !CDS_PN = "5";
"DQ<1>":   PN = "150"  !CDS_PN = "150";
"DQ<2>":   PN = "12"  !CDS_PN = "12";
"DQ<3>":   PN = "157"  !CDS_PN = "157";
"DQ<4>":   PN = "3"  !CDS_PN = "3";
"DQ<5>":   PN = "148"  !CDS_PN = "148";
"DQ<6>":   PN = "10"  !CDS_PN = "10";
"DQ<7>":   PN = "155"  !CDS_PN = "155";
"DQ<8>":   PN = "16"  !CDS_PN = "16";
"DQ<9>":   PN = "161"  !CDS_PN = "161";
"DQ<10>":   PN = "23"  !CDS_PN = "23";
"DQ<11>":   PN = "168"  !CDS_PN = "168";
"DQ<12>":   PN = "14"  !CDS_PN = "14";
"DQ<13>":   PN = "159"  !CDS_PN = "159";
"DQ<14>":   PN = "21"  !CDS_PN = "21";
"DQ<15>":   PN = "166"  !CDS_PN = "166";
"DQ<16>":   PN = "27"  !CDS_PN = "27";
"DQ<17>":   PN = "172"  !CDS_PN = "172";
"DQ<18>":   PN = "34"  !CDS_PN = "34";
"DQ<19>":   PN = "179"  !CDS_PN = "179";
"DQ<20>":   PN = "25"  !CDS_PN = "25";
"DQ<21>":   PN = "170"  !CDS_PN = "170";
"DQ<22>":   PN = "32"  !CDS_PN = "32";
"DQ<23>":   PN = "177"  !CDS_PN = "177";
"DQ<24>":   PN = "38"  !CDS_PN = "38";
"DQ<25>":   PN = "183"  !CDS_PN = "183";
"DQ<26>":   PN = "45"  !CDS_PN = "45";
"DQ<27>":   PN = "190"  !CDS_PN = "190";
"DQ<28>":   PN = "36"  !CDS_PN = "36";
"DQ<29>":   PN = "181"  !CDS_PN = "181";
"DQ<30>":   PN = "43"  !CDS_PN = "43";
"DQ<31>":   PN = "188"  !CDS_PN = "188";
"DQ<32>":   PN = "97"  !CDS_PN = "97";
"DQ<33>":   PN = "242"  !CDS_PN = "242";
"DQ<34>":   PN = "104"  !CDS_PN = "104";
"DQ<35>":   PN = "249"  !CDS_PN = "249";
"DQ<36>":   PN = "95"  !CDS_PN = "95";
"DQ<37>":   PN = "240"  !CDS_PN = "240";
"DQ<38>":   PN = "102"  !CDS_PN = "102";
"DQ<39>":   PN = "247"  !CDS_PN = "247";
"DQ<40>":   PN = "108"  !CDS_PN = "108";
"DQ<41>":   PN = "253"  !CDS_PN = "253";
"DQ<42>":   PN = "115"  !CDS_PN = "115";
"DQ<43>":   PN = "260"  !CDS_PN = "260";
"DQ<44>":   PN = "106"  !CDS_PN = "106";
"DQ<45>":   PN = "251"  !CDS_PN = "251";
"DQ<46>":   PN = "113"  !CDS_PN = "113";
"DQ<47>":   PN = "258"  !CDS_PN = "258";
"DQ<48>":   PN = "119"  !CDS_PN = "119";
"DQ<49>":   PN = "264"  !CDS_PN = "264";
"DQ<50>":   PN = "126"  !CDS_PN = "126";
"DQ<51>":   PN = "271"  !CDS_PN = "271";
"DQ<52>":   PN = "117"  !CDS_PN = "117";
"DQ<53>":   PN = "262"  !CDS_PN = "262";
"DQ<54>":   PN = "124"  !CDS_PN = "124";
"DQ<55>":   PN = "269"  !CDS_PN = "269";
"DQ<56>":   PN = "130"  !CDS_PN = "130";
"DQ<57>":   PN = "275"  !CDS_PN = "275";
"DQ<58>":   PN = "137"  !CDS_PN = "137";
"DQ<59>":   PN = "282"  !CDS_PN = "282";
"DQ<60>":   PN = "128"  !CDS_PN = "128";
"DQ<61>":   PN = "273"  !CDS_PN = "273";
"DQ<62>":   PN = "135"  !CDS_PN = "135";
"DQ<63>":   PN = "280"  !CDS_PN = "280";
"EVENT_N":   PN = "78"  !CDS_PN = "78";
"ODT<0>":   PN = "87"  !CDS_PN = "87";
"ODT<1>":   PN = "91"  !CDS_PN = "91";
"PAR":   PN = "222"  !CDS_PN = "222";
"RESET_N":   PN = "58"  !CDS_PN = "58";
"RFU<0>":   PN = "205"  !CDS_PN = "205";
"RFU<1>":   PN = "227"  !CDS_PN = "227";
"RFU<2>":   PN = "144"  !CDS_PN = "144";
"S0_N":   PN = "84"  !CDS_PN = "84";
"S1_N":   PN = "89"  !CDS_PN = "89";
"S2_N_C<0>":   PN = "93"  !CDS_PN = "93";
"S3_N_C<1>":   PN = "237"  !CDS_PN = "237";
"SA<0>":   PN = "139"  !CDS_PN = "139";
"SA<1>":   PN = "140"  !CDS_PN = "140";
"SA<2>":   PN = "238"  !CDS_PN = "238";
"SAVE_N_NC":   PN = "230"  !CDS_PN = "230";
"SCL":   PN = "141"  !CDS_PN = "141";
"SDA":   PN = "285"  !CDS_PN = "285";
"VDDSPD":   PN = "284"  !CDS_PN = "284";
"VREFCA":   PN = "146"  !CDS_PN = "146";
BODY = "SCONN288_H44441003","I55": #LOCATION = "J9L2" !CDS_LOCATION = "J9L2" #SEC = "4" !CDS_SEC = "4";
"12V<0>":   PN = "145"  !CDS_PN = "145";
"12V<1>":   PN = "1"  !CDS_PN = "1";
"VDD<0>":   PN = "236"  !CDS_PN = "236";
"VDD<1>":   PN = "233"  !CDS_PN = "233";
"VDD<2>":   PN = "231"  !CDS_PN = "231";
"VDD<3>":   PN = "229"  !CDS_PN = "229";
"VDD<4>":   PN = "226"  !CDS_PN = "226";
"VDD<5>":   PN = "223"  !CDS_PN = "223";
"VDD<6>":   PN = "220"  !CDS_PN = "220";
"VDD<7>":   PN = "217"  !CDS_PN = "217";
"VDD<8>":   PN = "215"  !CDS_PN = "215";
"VDD<9>":   PN = "212"  !CDS_PN = "212";
"VDD<10>":   PN = "209"  !CDS_PN = "209";
"VDD<11>":   PN = "206"  !CDS_PN = "206";
"VDD<12>":   PN = "204"  !CDS_PN = "204";
"VDD<13>":   PN = "92"  !CDS_PN = "92";
"VDD<14>":   PN = "90"  !CDS_PN = "90";
"VDD<15>":   PN = "88"  !CDS_PN = "88";
"VDD<16>":   PN = "85"  !CDS_PN = "85";
"VDD<17>":   PN = "83"  !CDS_PN = "83";
"VDD<18>":   PN = "80"  !CDS_PN = "80";
"VDD<19>":   PN = "76"  !CDS_PN = "76";
"VDD<20>":   PN = "73"  !CDS_PN = "73";
"VDD<21>":   PN = "70"  !CDS_PN = "70";
"VDD<22>":   PN = "67"  !CDS_PN = "67";
"VDD<23>":   PN = "64"  !CDS_PN = "64";
"VDD<24>":   PN = "61"  !CDS_PN = "61";
"VDD<25>":   PN = "59"  !CDS_PN = "59";
"VPP<0>":   PN = "287"  !CDS_PN = "287";
"VPP<1>":   PN = "286"  !CDS_PN = "286";
"VPP<2>":   PN = "288"  !CDS_PN = "288";
"VPP<3>":   PN = "143"  !CDS_PN = "143";
"VPP<4>":   PN = "142"  !CDS_PN = "142";
"VTT<0>":   PN = "221"  !CDS_PN = "221";
"VTT<1>":   PN = "77"  !CDS_PN = "77";
BODY = "SCONN288_H44441003","I100": #LOCATION = "J9L2" !CDS_LOCATION = "J9L2" #SEC = "2" !CDS_SEC = "2";
"DQS0N":   PN = "152"  !CDS_PN = "152";
"DQS0P":   PN = "153"  !CDS_PN = "153";
"DQS1N":   PN = "163"  !CDS_PN = "163";
"DQS1P":   PN = "164"  !CDS_PN = "164";
"DQS2N":   PN = "174"  !CDS_PN = "174";
"DQS2P":   PN = "175"  !CDS_PN = "175";
"DQS3N":   PN = "185"  !CDS_PN = "185";
"DQS3P":   PN = "186"  !CDS_PN = "186";
"DQS4N":   PN = "244"  !CDS_PN = "244";
"DQS4P":   PN = "245"  !CDS_PN = "245";
"DQS5N":   PN = "255"  !CDS_PN = "255";
"DQS5P":   PN = "256"  !CDS_PN = "256";
"DQS6N":   PN = "266"  !CDS_PN = "266";
"DQS6P":   PN = "267"  !CDS_PN = "267";
"DQS7N":   PN = "277"  !CDS_PN = "277";
"DQS7P":   PN = "278"  !CDS_PN = "278";
"DQS8N":   PN = "196"  !CDS_PN = "196";
"DQS8P":   PN = "197"  !CDS_PN = "197";
"DQS9N":   PN = "8"  !CDS_PN = "8";
"DQS9P":   PN = "7"  !CDS_PN = "7";
"DQS10N":   PN = "19"  !CDS_PN = "19";
"DQS10P":   PN = "18"  !CDS_PN = "18";
"DQS11N":   PN = "30"  !CDS_PN = "30";
"DQS11P":   PN = "29"  !CDS_PN = "29";
"DQS12N":   PN = "41"  !CDS_PN = "41";
"DQS12P":   PN = "40"  !CDS_PN = "40";
"DQS13N":   PN = "100"  !CDS_PN = "100";
"DQS13P":   PN = "99"  !CDS_PN = "99";
"DQS14N":   PN = "111"  !CDS_PN = "111";
"DQS14P":   PN = "110"  !CDS_PN = "110";
"DQS15N":   PN = "122"  !CDS_PN = "122";
"DQS15P":   PN = "121"  !CDS_PN = "121";
"DQS16N":   PN = "133"  !CDS_PN = "133";
"DQS16P":   PN = "132"  !CDS_PN = "132";
"DQS17N":   PN = "52"  !CDS_PN = "52";
"DQS17P":   PN = "51"  !CDS_PN = "51";
BODY = "SCONN288_H44441003","I138": #LOCATION = "J9L2" !CDS_LOCATION = "J9L2" #SEC = "3" !CDS_SEC = "3";
"VSS<0>":   PN = "283"  !CDS_PN = "283";
"VSS<1>":   PN = "281"  !CDS_PN = "281";
"VSS<2>":   PN = "279"  !CDS_PN = "279";
"VSS<3>":   PN = "276"  !CDS_PN = "276";
"VSS<4>":   PN = "274"  !CDS_PN = "274";
"VSS<5>":   PN = "272"  !CDS_PN = "272";
"VSS<6>":   PN = "270"  !CDS_PN = "270";
"VSS<7>":   PN = "268"  !CDS_PN = "268";
"VSS<8>":   PN = "265"  !CDS_PN = "265";
"VSS<9>":   PN = "263"  !CDS_PN = "263";
"VSS<10>":   PN = "261"  !CDS_PN = "261";
"VSS<11>":   PN = "259"  !CDS_PN = "259";
"VSS<12>":   PN = "257"  !CDS_PN = "257";
"VSS<13>":   PN = "254"  !CDS_PN = "254";
"VSS<14>":   PN = "252"  !CDS_PN = "252";
"VSS<15>":   PN = "250"  !CDS_PN = "250";
"VSS<16>":   PN = "248"  !CDS_PN = "248";
"VSS<17>":   PN = "246"  !CDS_PN = "246";
"VSS<18>":   PN = "243"  !CDS_PN = "243";
"VSS<19>":   PN = "241"  !CDS_PN = "241";
"VSS<20>":   PN = "239"  !CDS_PN = "239";
"VSS<21>":   PN = "202"  !CDS_PN = "202";
"VSS<22>":   PN = "200"  !CDS_PN = "200";
"VSS<23>":   PN = "198"  !CDS_PN = "198";
"VSS<24>":   PN = "195"  !CDS_PN = "195";
"VSS<25>":   PN = "193"  !CDS_PN = "193";
"VSS<26>":   PN = "191"  !CDS_PN = "191";
"VSS<27>":   PN = "189"  !CDS_PN = "189";
"VSS<28>":   PN = "187"  !CDS_PN = "187";
"VSS<29>":   PN = "184"  !CDS_PN = "184";
"VSS<30>":   PN = "182"  !CDS_PN = "182";
"VSS<31>":   PN = "180"  !CDS_PN = "180";
"VSS<32>":   PN = "178"  !CDS_PN = "178";
"VSS<33>":   PN = "176"  !CDS_PN = "176";
"VSS<34>":   PN = "173"  !CDS_PN = "173";
"VSS<35>":   PN = "171"  !CDS_PN = "171";
"VSS<36>":   PN = "169"  !CDS_PN = "169";
"VSS<37>":   PN = "167"  !CDS_PN = "167";
"VSS<38>":   PN = "165"  !CDS_PN = "165";
"VSS<39>":   PN = "162"  !CDS_PN = "162";
"VSS<40>":   PN = "160"  !CDS_PN = "160";
"VSS<41>":   PN = "158"  !CDS_PN = "158";
"VSS<42>":   PN = "156"  !CDS_PN = "156";
"VSS<43>":   PN = "154"  !CDS_PN = "154";
"VSS<44>":   PN = "151"  !CDS_PN = "151";
"VSS<45>":   PN = "149"  !CDS_PN = "149";
"VSS<46>":   PN = "147"  !CDS_PN = "147";
"VSS<47>":   PN = "138"  !CDS_PN = "138";
"VSS<48>":   PN = "136"  !CDS_PN = "136";
"VSS<49>":   PN = "134"  !CDS_PN = "134";
"VSS<50>":   PN = "131"  !CDS_PN = "131";
"VSS<51>":   PN = "129"  !CDS_PN = "129";
"VSS<52>":   PN = "127"  !CDS_PN = "127";
"VSS<53>":   PN = "125"  !CDS_PN = "125";
"VSS<54>":   PN = "123"  !CDS_PN = "123";
"VSS<55>":   PN = "120"  !CDS_PN = "120";
"VSS<56>":   PN = "118"  !CDS_PN = "118";
"VSS<57>":   PN = "116"  !CDS_PN = "116";
"VSS<58>":   PN = "114"  !CDS_PN = "114";
"VSS<59>":   PN = "112"  !CDS_PN = "112";
"VSS<60>":   PN = "109"  !CDS_PN = "109";
"VSS<61>":   PN = "107"  !CDS_PN = "107";
"VSS<62>":   PN = "105"  !CDS_PN = "105";
"VSS<63>":   PN = "103"  !CDS_PN = "103";
"VSS<64>":   PN = "101"  !CDS_PN = "101";
"VSS<65>":   PN = "98"  !CDS_PN = "98";
"VSS<66>":   PN = "96"  !CDS_PN = "96";
"VSS<67>":   PN = "94"  !CDS_PN = "94";
"VSS<68>":   PN = "57"  !CDS_PN = "57";
"VSS<69>":   PN = "55"  !CDS_PN = "55";
"VSS<70>":   PN = "53"  !CDS_PN = "53";
"VSS<71>":   PN = "50"  !CDS_PN = "50";
"VSS<72>":   PN = "48"  !CDS_PN = "48";
"VSS<73>":   PN = "46"  !CDS_PN = "46";
"VSS<74>":   PN = "44"  !CDS_PN = "44";
"VSS<75>":   PN = "42"  !CDS_PN = "42";
"VSS<76>":   PN = "39"  !CDS_PN = "39";
"VSS<77>":   PN = "37"  !CDS_PN = "37";
"VSS<78>":   PN = "35"  !CDS_PN = "35";
"VSS<79>":   PN = "33"  !CDS_PN = "33";
"VSS<80>":   PN = "31"  !CDS_PN = "31";
"VSS<81>":   PN = "28"  !CDS_PN = "28";
"VSS<82>":   PN = "26"  !CDS_PN = "26";
"VSS<83>":   PN = "24"  !CDS_PN = "24";
"VSS<84>":   PN = "22"  !CDS_PN = "22";
"VSS<85>":   PN = "20"  !CDS_PN = "20";
"VSS<86>":   PN = "17"  !CDS_PN = "17";
"VSS<87>":   PN = "15"  !CDS_PN = "15";
"VSS<88>":   PN = "13"  !CDS_PN = "13";
"VSS<89>":   PN = "11"  !CDS_PN = "11";
"VSS<90>":   PN = "9"  !CDS_PN = "9";
"VSS<91>":   PN = "6"  !CDS_PN = "6";
"VSS<92>":   PN = "4"  !CDS_PN = "4";
"VSS<93>":   PN = "2"  !CDS_PN = "2";
BODY = "CAP_A","I182": #LOCATION = "C1A17" !CDS_LOCATION = "C1A17" &SEC = "1" #&CDS_SEC = "1";
"A":   PN = "1"  !CDS_PN = "1";
"B":   PN = "2"  !CDS_PN = "2";
DRAWING = "@baseboard_fab2_lib.baseboard_fab2(sch_1):page87";
BODY = "SCONN288_H44441004","I169": #LOCATION = "J1A1" !CDS_LOCATION = "J1A1" #SEC = "4" !CDS_SEC = "4";
"12V<0>":   PN = "145"  !CDS_PN = "145";
"12V<1>":   PN = "1"  !CDS_PN = "1";
"VDD<0>":   PN = "236"  !CDS_PN = "236";
"VDD<1>":   PN = "233"  !CDS_PN = "233";
"VDD<2>":   PN = "231"  !CDS_PN = "231";
"VDD<3>":   PN = "229"  !CDS_PN = "229";
"VDD<4>":   PN = "226"  !CDS_PN = "226";
"VDD<5>":   PN = "223"  !CDS_PN = "223";
"VDD<6>":   PN = "220"  !CDS_PN = "220";
"VDD<7>":   PN = "217"  !CDS_PN = "217";
"VDD<8>":   PN = "215"  !CDS_PN = "215";
"VDD<9>":   PN = "212"  !CDS_PN = "212";
"VDD<10>":   PN = "209"  !CDS_PN = "209";
"VDD<11>":   PN = "206"  !CDS_PN = "206";
"VDD<12>":   PN = "204"  !CDS_PN = "204";
"VDD<13>":   PN = "92"  !CDS_PN = "92";
"VDD<14>":   PN = "90"  !CDS_PN = "90";
"VDD<15>":   PN = "88"  !CDS_PN = "88";
"VDD<16>":   PN = "85"  !CDS_PN = "85";
"VDD<17>":   PN = "83"  !CDS_PN = "83";
"VDD<18>":   PN = "80"  !CDS_PN = "80";
"VDD<19>":   PN = "76"  !CDS_PN = "76";
"VDD<20>":   PN = "73"  !CDS_PN = "73";
"VDD<21>":   PN = "70"  !CDS_PN = "70";
"VDD<22>":   PN = "67"  !CDS_PN = "67";
"VDD<23>":   PN = "64"  !CDS_PN = "64";
"VDD<24>":   PN = "61"  !CDS_PN = "61";
"VDD<25>":   PN = "59"  !CDS_PN = "59";
"VPP<0>":   PN = "287"  !CDS_PN = "287";
"VPP<1>":   PN = "286"  !CDS_PN = "286";
"VPP<2>":   PN = "288"  !CDS_PN = "288";
"VPP<3>":   PN = "143"  !CDS_PN = "143";
"VPP<4>":   PN = "142"  !CDS_PN = "142";
"VTT<0>":   PN = "221"  !CDS_PN = "221";
"VTT<1>":   PN = "77"  !CDS_PN = "77";
BODY = "CAP_A","I178": #LOCATION = "C1A5" !CDS_LOCATION = "C1A5" #SEC = "1" !CDS_SEC = "1";
"A":   PN = "1"  !CDS_PN = "1";
"B":   PN = "2"  !CDS_PN = "2";
BODY = "SCONN288_H44441004","I185": #LOCATION = "J1A1" !CDS_LOCATION = "J1A1" #SEC = "3" !CDS_SEC = "3";
"VSS<0>":   PN = "283"  !CDS_PN = "283";
"VSS<1>":   PN = "281"  !CDS_PN = "281";
"VSS<2>":   PN = "279"  !CDS_PN = "279";
"VSS<3>":   PN = "276"  !CDS_PN = "276";
"VSS<4>":   PN = "274"  !CDS_PN = "274";
"VSS<5>":   PN = "272"  !CDS_PN = "272";
"VSS<6>":   PN = "270"  !CDS_PN = "270";
"VSS<7>":   PN = "268"  !CDS_PN = "268";
"VSS<8>":   PN = "265"  !CDS_PN = "265";
"VSS<9>":   PN = "263"  !CDS_PN = "263";
"VSS<10>":   PN = "261"  !CDS_PN = "261";
"VSS<11>":   PN = "259"  !CDS_PN = "259";
"VSS<12>":   PN = "257"  !CDS_PN = "257";
"VSS<13>":   PN = "254"  !CDS_PN = "254";
"VSS<14>":   PN = "252"  !CDS_PN = "252";
"VSS<15>":   PN = "250"  !CDS_PN = "250";
"VSS<16>":   PN = "248"  !CDS_PN = "248";
"VSS<17>":   PN = "246"  !CDS_PN = "246";
"VSS<18>":   PN = "243"  !CDS_PN = "243";
"VSS<19>":   PN = "241"  !CDS_PN = "241";
"VSS<20>":   PN = "239"  !CDS_PN = "239";
"VSS<21>":   PN = "202"  !CDS_PN = "202";
"VSS<22>":   PN = "200"  !CDS_PN = "200";
"VSS<23>":   PN = "198"  !CDS_PN = "198";
"VSS<24>":   PN = "195"  !CDS_PN = "195";
"VSS<25>":   PN = "193"  !CDS_PN = "193";
"VSS<26>":   PN = "191"  !CDS_PN = "191";
"VSS<27>":   PN = "189"  !CDS_PN = "189";
"VSS<28>":   PN = "187"  !CDS_PN = "187";
"VSS<29>":   PN = "184"  !CDS_PN = "184";
"VSS<30>":   PN = "182"  !CDS_PN = "182";
"VSS<31>":   PN = "180"  !CDS_PN = "180";
"VSS<32>":   PN = "178"  !CDS_PN = "178";
"VSS<33>":   PN = "176"  !CDS_PN = "176";
"VSS<34>":   PN = "173"  !CDS_PN = "173";
"VSS<35>":   PN = "171"  !CDS_PN = "171";
"VSS<36>":   PN = "169"  !CDS_PN = "169";
"VSS<37>":   PN = "167"  !CDS_PN = "167";
"VSS<38>":   PN = "165"  !CDS_PN = "165";
"VSS<39>":   PN = "162"  !CDS_PN = "162";
"VSS<40>":   PN = "160"  !CDS_PN = "160";
"VSS<41>":   PN = "158"  !CDS_PN = "158";
"VSS<42>":   PN = "156"  !CDS_PN = "156";
"VSS<43>":   PN = "154"  !CDS_PN = "154";
"VSS<44>":   PN = "151"  !CDS_PN = "151";
"VSS<45>":   PN = "149"  !CDS_PN = "149";
"VSS<46>":   PN = "147"  !CDS_PN = "147";
"VSS<47>":   PN = "138"  !CDS_PN = "138";
"VSS<48>":   PN = "136"  !CDS_PN = "136";
"VSS<49>":   PN = "134"  !CDS_PN = "134";
"VSS<50>":   PN = "131"  !CDS_PN = "131";
"VSS<51>":   PN = "129"  !CDS_PN = "129";
"VSS<52>":   PN = "127"  !CDS_PN = "127";
"VSS<53>":   PN = "125"  !CDS_PN = "125";
"VSS<54>":   PN = "123"  !CDS_PN = "123";
"VSS<55>":   PN = "120"  !CDS_PN = "120";
"VSS<56>":   PN = "118"  !CDS_PN = "118";
"VSS<57>":   PN = "116"  !CDS_PN = "116";
"VSS<58>":   PN = "114"  !CDS_PN = "114";
"VSS<59>":   PN = "112"  !CDS_PN = "112";
"VSS<60>":   PN = "109"  !CDS_PN = "109";
"VSS<61>":   PN = "107"  !CDS_PN = "107";
"VSS<62>":   PN = "105"  !CDS_PN = "105";
"VSS<63>":   PN = "103"  !CDS_PN = "103";
"VSS<64>":   PN = "101"  !CDS_PN = "101";
"VSS<65>":   PN = "98"  !CDS_PN = "98";
"VSS<66>":   PN = "96"  !CDS_PN = "96";
"VSS<67>":   PN = "94"  !CDS_PN = "94";
"VSS<68>":   PN = "57"  !CDS_PN = "57";
"VSS<69>":   PN = "55"  !CDS_PN = "55";
"VSS<70>":   PN = "53"  !CDS_PN = "53";
"VSS<71>":   PN = "50"  !CDS_PN = "50";
"VSS<72>":   PN = "48"  !CDS_PN = "48";
"VSS<73>":   PN = "46"  !CDS_PN = "46";
"VSS<74>":   PN = "44"  !CDS_PN = "44";
"VSS<75>":   PN = "42"  !CDS_PN = "42";
"VSS<76>":   PN = "39"  !CDS_PN = "39";
"VSS<77>":   PN = "37"  !CDS_PN = "37";
"VSS<78>":   PN = "35"  !CDS_PN = "35";
"VSS<79>":   PN = "33"  !CDS_PN = "33";
"VSS<80>":   PN = "31"  !CDS_PN = "31";
"VSS<81>":   PN = "28"  !CDS_PN = "28";
"VSS<82>":   PN = "26"  !CDS_PN = "26";
"VSS<83>":   PN = "24"  !CDS_PN = "24";
"VSS<84>":   PN = "22"  !CDS_PN = "22";
"VSS<85>":   PN = "20"  !CDS_PN = "20";
"VSS<86>":   PN = "17"  !CDS_PN = "17";
"VSS<87>":   PN = "15"  !CDS_PN = "15";
"VSS<88>":   PN = "13"  !CDS_PN = "13";
"VSS<89>":   PN = "11"  !CDS_PN = "11";
"VSS<90>":   PN = "9"  !CDS_PN = "9";
"VSS<91>":   PN = "6"  !CDS_PN = "6";
"VSS<92>":   PN = "4"  !CDS_PN = "4";
"VSS<93>":   PN = "2"  !CDS_PN = "2";
BODY = "SCONN288_H44441004","I186": #LOCATION = "J1A1" !CDS_LOCATION = "J1A1" #SEC = "1" !CDS_SEC = "1";
"A0":   PN = "79"  !CDS_PN = "79";
"A1":   PN = "72"  !CDS_PN = "72";
"A2":   PN = "216"  !CDS_PN = "216";
"A3":   PN = "71"  !CDS_PN = "71";
"A4":   PN = "214"  !CDS_PN = "214";
"A5":   PN = "213"  !CDS_PN = "213";
"A6":   PN = "69"  !CDS_PN = "69";
"A7":   PN = "211"  !CDS_PN = "211";
"A8":   PN = "68"  !CDS_PN = "68";
"A9":   PN = "66"  !CDS_PN = "66";
"A10":   PN = "225"  !CDS_PN = "225";
"A11":   PN = "210"  !CDS_PN = "210";
"A12":   PN = "65"  !CDS_PN = "65";
"A13":   PN = "232"  !CDS_PN = "232";
"A14_WE_N":   PN = "228"  !CDS_PN = "228";
"A15_CAS_N":   PN = "86"  !CDS_PN = "86";
"A16_RAS_N":   PN = "82"  !CDS_PN = "82";
"A17":   PN = "234"  !CDS_PN = "234";
"ACT_N":   PN = "62"  !CDS_PN = "62";
"ALERT_N":   PN = "208"  !CDS_PN = "208";
"BA<0>":   PN = "81"  !CDS_PN = "81";
"BA<1>":   PN = "224"  !CDS_PN = "224";
"BG<0>":   PN = "63"  !CDS_PN = "63";
"BG<1>":   PN = "207"  !CDS_PN = "207";
"C<2>":   PN = "235"  !CDS_PN = "235";
"CB<0>":   PN = "49"  !CDS_PN = "49";
"CB<1>":   PN = "194"  !CDS_PN = "194";
"CB<2>":   PN = "56"  !CDS_PN = "56";
"CB<3>":   PN = "201"  !CDS_PN = "201";
"CB<4>":   PN = "47"  !CDS_PN = "47";
"CB<5>":   PN = "192"  !CDS_PN = "192";
"CB<6>":   PN = "54"  !CDS_PN = "54";
"CB<7>":   PN = "199"  !CDS_PN = "199";
"CK0N":   PN = "75"  !CDS_PN = "75";
"CK0P":   PN = "74"  !CDS_PN = "74";
"CK1N":   PN = "219"  !CDS_PN = "219";
"CK1P":   PN = "218"  !CDS_PN = "218";
"CKE<0>":   PN = "60"  !CDS_PN = "60";
"CKE<1>":   PN = "203"  !CDS_PN = "203";
"DQ<0>":   PN = "5"  !CDS_PN = "5";
"DQ<1>":   PN = "150"  !CDS_PN = "150";
"DQ<2>":   PN = "12"  !CDS_PN = "12";
"DQ<3>":   PN = "157"  !CDS_PN = "157";
"DQ<4>":   PN = "3"  !CDS_PN = "3";
"DQ<5>":   PN = "148"  !CDS_PN = "148";
"DQ<6>":   PN = "10"  !CDS_PN = "10";
"DQ<7>":   PN = "155"  !CDS_PN = "155";
"DQ<8>":   PN = "16"  !CDS_PN = "16";
"DQ<9>":   PN = "161"  !CDS_PN = "161";
"DQ<10>":   PN = "23"  !CDS_PN = "23";
"DQ<11>":   PN = "168"  !CDS_PN = "168";
"DQ<12>":   PN = "14"  !CDS_PN = "14";
"DQ<13>":   PN = "159"  !CDS_PN = "159";
"DQ<14>":   PN = "21"  !CDS_PN = "21";
"DQ<15>":   PN = "166"  !CDS_PN = "166";
"DQ<16>":   PN = "27"  !CDS_PN = "27";
"DQ<17>":   PN = "172"  !CDS_PN = "172";
"DQ<18>":   PN = "34"  !CDS_PN = "34";
"DQ<19>":   PN = "179"  !CDS_PN = "179";
"DQ<20>":   PN = "25"  !CDS_PN = "25";
"DQ<21>":   PN = "170"  !CDS_PN = "170";
"DQ<22>":   PN = "32"  !CDS_PN = "32";
"DQ<23>":   PN = "177"  !CDS_PN = "177";
"DQ<24>":   PN = "38"  !CDS_PN = "38";
"DQ<25>":   PN = "183"  !CDS_PN = "183";
"DQ<26>":   PN = "45"  !CDS_PN = "45";
"DQ<27>":   PN = "190"  !CDS_PN = "190";
"DQ<28>":   PN = "36"  !CDS_PN = "36";
"DQ<29>":   PN = "181"  !CDS_PN = "181";
"DQ<30>":   PN = "43"  !CDS_PN = "43";
"DQ<31>":   PN = "188"  !CDS_PN = "188";
"DQ<32>":   PN = "97"  !CDS_PN = "97";
"DQ<33>":   PN = "242"  !CDS_PN = "242";
"DQ<34>":   PN = "104"  !CDS_PN = "104";
"DQ<35>":   PN = "249"  !CDS_PN = "249";
"DQ<36>":   PN = "95"  !CDS_PN = "95";
"DQ<37>":   PN = "240"  !CDS_PN = "240";
"DQ<38>":   PN = "102"  !CDS_PN = "102";
"DQ<39>":   PN = "247"  !CDS_PN = "247";
"DQ<40>":   PN = "108"  !CDS_PN = "108";
"DQ<41>":   PN = "253"  !CDS_PN = "253";
"DQ<42>":   PN = "115"  !CDS_PN = "115";
"DQ<43>":   PN = "260"  !CDS_PN = "260";
"DQ<44>":   PN = "106"  !CDS_PN = "106";
"DQ<45>":   PN = "251"  !CDS_PN = "251";
"DQ<46>":   PN = "113"  !CDS_PN = "113";
"DQ<47>":   PN = "258"  !CDS_PN = "258";
"DQ<48>":   PN = "119"  !CDS_PN = "119";
"DQ<49>":   PN = "264"  !CDS_PN = "264";
"DQ<50>":   PN = "126"  !CDS_PN = "126";
"DQ<51>":   PN = "271"  !CDS_PN = "271";
"DQ<52>":   PN = "117"  !CDS_PN = "117";
"DQ<53>":   PN = "262"  !CDS_PN = "262";
"DQ<54>":   PN = "124"  !CDS_PN = "124";
"DQ<55>":   PN = "269"  !CDS_PN = "269";
"DQ<56>":   PN = "130"  !CDS_PN = "130";
"DQ<57>":   PN = "275"  !CDS_PN = "275";
"DQ<58>":   PN = "137"  !CDS_PN = "137";
"DQ<59>":   PN = "282"  !CDS_PN = "282";
"DQ<60>":   PN = "128"  !CDS_PN = "128";
"DQ<61>":   PN = "273"  !CDS_PN = "273";
"DQ<62>":   PN = "135"  !CDS_PN = "135";
"DQ<63>":   PN = "280"  !CDS_PN = "280";
"EVENT_N":   PN = "78"  !CDS_PN = "78";
"ODT<0>":   PN = "87"  !CDS_PN = "87";
"ODT<1>":   PN = "91"  !CDS_PN = "91";
"PAR":   PN = "222"  !CDS_PN = "222";
"RESET_N":   PN = "58"  !CDS_PN = "58";
"RFU<0>":   PN = "205"  !CDS_PN = "205";
"RFU<1>":   PN = "227"  !CDS_PN = "227";
"RFU<2>":   PN = "144"  !CDS_PN = "144";
"S0_N":   PN = "84"  !CDS_PN = "84";
"S1_N":   PN = "89"  !CDS_PN = "89";
"S2_N_C<0>":   PN = "93"  !CDS_PN = "93";
"S3_N_C<1>":   PN = "237"  !CDS_PN = "237";
"SA<0>":   PN = "139"  !CDS_PN = "139";
"SA<1>":   PN = "140"  !CDS_PN = "140";
"SA<2>":   PN = "238"  !CDS_PN = "238";
"SAVE_N_NC":   PN = "230"  !CDS_PN = "230";
"SCL":   PN = "141"  !CDS_PN = "141";
"SDA":   PN = "285"  !CDS_PN = "285";
"VDDSPD":   PN = "284"  !CDS_PN = "284";
"VREFCA":   PN = "146"  !CDS_PN = "146";
BODY = "SCONN288_H44441004","I187": #LOCATION = "J1A1" !CDS_LOCATION = "J1A1" #SEC = "2" !CDS_SEC = "2";
"DQS0N":   PN = "152"  !CDS_PN = "152";
"DQS0P":   PN = "153"  !CDS_PN = "153";
"DQS1N":   PN = "163"  !CDS_PN = "163";
"DQS1P":   PN = "164"  !CDS_PN = "164";
"DQS2N":   PN = "174"  !CDS_PN = "174";
"DQS2P":   PN = "175"  !CDS_PN = "175";
"DQS3N":   PN = "185"  !CDS_PN = "185";
"DQS3P":   PN = "186"  !CDS_PN = "186";
"DQS4N":   PN = "244"  !CDS_PN = "244";
"DQS4P":   PN = "245"  !CDS_PN = "245";
"DQS5N":   PN = "255"  !CDS_PN = "255";
"DQS5P":   PN = "256"  !CDS_PN = "256";
"DQS6N":   PN = "266"  !CDS_PN = "266";
"DQS6P":   PN = "267"  !CDS_PN = "267";
"DQS7N":   PN = "277"  !CDS_PN = "277";
"DQS7P":   PN = "278"  !CDS_PN = "278";
"DQS8N":   PN = "196"  !CDS_PN = "196";
"DQS8P":   PN = "197"  !CDS_PN = "197";
"DQS9N":   PN = "8"  !CDS_PN = "8";
"DQS9P":   PN = "7"  !CDS_PN = "7";
"DQS10N":   PN = "19"  !CDS_PN = "19";
"DQS10P":   PN = "18"  !CDS_PN = "18";
"DQS11N":   PN = "30"  !CDS_PN = "30";
"DQS11P":   PN = "29"  !CDS_PN = "29";
"DQS12N":   PN = "41"  !CDS_PN = "41";
"DQS12P":   PN = "40"  !CDS_PN = "40";
"DQS13N":   PN = "100"  !CDS_PN = "100";
"DQS13P":   PN = "99"  !CDS_PN = "99";
"DQS14N":   PN = "111"  !CDS_PN = "111";
"DQS14P":   PN = "110"  !CDS_PN = "110";
"DQS15N":   PN = "122"  !CDS_PN = "122";
"DQS15P":   PN = "121"  !CDS_PN = "121";
"DQS16N":   PN = "133"  !CDS_PN = "133";
"DQS16P":   PN = "132"  !CDS_PN = "132";
"DQS17N":   PN = "52"  !CDS_PN = "52";
"DQS17P":   PN = "51"  !CDS_PN = "51";
DRAWING = "@baseboard_fab2_lib.baseboard_fab2(sch_1):page88";
BODY = "SCONN288_H44441003","I25": #LOCATION = "J9L1" !CDS_LOCATION = "J9L1" #SEC = "3" !CDS_SEC = "3";
"VSS<0>":   PN = "283"  !CDS_PN = "283";
"VSS<1>":   PN = "281"  !CDS_PN = "281";
"VSS<2>":   PN = "279"  !CDS_PN = "279";
"VSS<3>":   PN = "276"  !CDS_PN = "276";
"VSS<4>":   PN = "274"  !CDS_PN = "274";
"VSS<5>":   PN = "272"  !CDS_PN = "272";
"VSS<6>":   PN = "270"  !CDS_PN = "270";
"VSS<7>":   PN = "268"  !CDS_PN = "268";
"VSS<8>":   PN = "265"  !CDS_PN = "265";
"VSS<9>":   PN = "263"  !CDS_PN = "263";
"VSS<10>":   PN = "261"  !CDS_PN = "261";
"VSS<11>":   PN = "259"  !CDS_PN = "259";
"VSS<12>":   PN = "257"  !CDS_PN = "257";
"VSS<13>":   PN = "254"  !CDS_PN = "254";
"VSS<14>":   PN = "252"  !CDS_PN = "252";
"VSS<15>":   PN = "250"  !CDS_PN = "250";
"VSS<16>":   PN = "248"  !CDS_PN = "248";
"VSS<17>":   PN = "246"  !CDS_PN = "246";
"VSS<18>":   PN = "243"  !CDS_PN = "243";
"VSS<19>":   PN = "241"  !CDS_PN = "241";
"VSS<20>":   PN = "239"  !CDS_PN = "239";
"VSS<21>":   PN = "202"  !CDS_PN = "202";
"VSS<22>":   PN = "200"  !CDS_PN = "200";
"VSS<23>":   PN = "198"  !CDS_PN = "198";
"VSS<24>":   PN = "195"  !CDS_PN = "195";
"VSS<25>":   PN = "193"  !CDS_PN = "193";
"VSS<26>":   PN = "191"  !CDS_PN = "191";
"VSS<27>":   PN = "189"  !CDS_PN = "189";
"VSS<28>":   PN = "187"  !CDS_PN = "187";
"VSS<29>":   PN = "184"  !CDS_PN = "184";
"VSS<30>":   PN = "182"  !CDS_PN = "182";
"VSS<31>":   PN = "180"  !CDS_PN = "180";
"VSS<32>":   PN = "178"  !CDS_PN = "178";
"VSS<33>":   PN = "176"  !CDS_PN = "176";
"VSS<34>":   PN = "173"  !CDS_PN = "173";
"VSS<35>":   PN = "171"  !CDS_PN = "171";
"VSS<36>":   PN = "169"  !CDS_PN = "169";
"VSS<37>":   PN = "167"  !CDS_PN = "167";
"VSS<38>":   PN = "165"  !CDS_PN = "165";
"VSS<39>":   PN = "162"  !CDS_PN = "162";
"VSS<40>":   PN = "160"  !CDS_PN = "160";
"VSS<41>":   PN = "158"  !CDS_PN = "158";
"VSS<42>":   PN = "156"  !CDS_PN = "156";
"VSS<43>":   PN = "154"  !CDS_PN = "154";
"VSS<44>":   PN = "151"  !CDS_PN = "151";
"VSS<45>":   PN = "149"  !CDS_PN = "149";
"VSS<46>":   PN = "147"  !CDS_PN = "147";
"VSS<47>":   PN = "138"  !CDS_PN = "138";
"VSS<48>":   PN = "136"  !CDS_PN = "136";
"VSS<49>":   PN = "134"  !CDS_PN = "134";
"VSS<50>":   PN = "131"  !CDS_PN = "131";
"VSS<51>":   PN = "129"  !CDS_PN = "129";
"VSS<52>":   PN = "127"  !CDS_PN = "127";
"VSS<53>":   PN = "125"  !CDS_PN = "125";
"VSS<54>":   PN = "123"  !CDS_PN = "123";
"VSS<55>":   PN = "120"  !CDS_PN = "120";
"VSS<56>":   PN = "118"  !CDS_PN = "118";
"VSS<57>":   PN = "116"  !CDS_PN = "116";
"VSS<58>":   PN = "114"  !CDS_PN = "114";
"VSS<59>":   PN = "112"  !CDS_PN = "112";
"VSS<60>":   PN = "109"  !CDS_PN = "109";
"VSS<61>":   PN = "107"  !CDS_PN = "107";
"VSS<62>":   PN = "105"  !CDS_PN = "105";
"VSS<63>":   PN = "103"  !CDS_PN = "103";
"VSS<64>":   PN = "101"  !CDS_PN = "101";
"VSS<65>":   PN = "98"  !CDS_PN = "98";
"VSS<66>":   PN = "96"  !CDS_PN = "96";
"VSS<67>":   PN = "94"  !CDS_PN = "94";
"VSS<68>":   PN = "57"  !CDS_PN = "57";
"VSS<69>":   PN = "55"  !CDS_PN = "55";
"VSS<70>":   PN = "53"  !CDS_PN = "53";
"VSS<71>":   PN = "50"  !CDS_PN = "50";
"VSS<72>":   PN = "48"  !CDS_PN = "48";
"VSS<73>":   PN = "46"  !CDS_PN = "46";
"VSS<74>":   PN = "44"  !CDS_PN = "44";
"VSS<75>":   PN = "42"  !CDS_PN = "42";
"VSS<76>":   PN = "39"  !CDS_PN = "39";
"VSS<77>":   PN = "37"  !CDS_PN = "37";
"VSS<78>":   PN = "35"  !CDS_PN = "35";
"VSS<79>":   PN = "33"  !CDS_PN = "33";
"VSS<80>":   PN = "31"  !CDS_PN = "31";
"VSS<81>":   PN = "28"  !CDS_PN = "28";
"VSS<82>":   PN = "26"  !CDS_PN = "26";
"VSS<83>":   PN = "24"  !CDS_PN = "24";
"VSS<84>":   PN = "22"  !CDS_PN = "22";
"VSS<85>":   PN = "20"  !CDS_PN = "20";
"VSS<86>":   PN = "17"  !CDS_PN = "17";
"VSS<87>":   PN = "15"  !CDS_PN = "15";
"VSS<88>":   PN = "13"  !CDS_PN = "13";
"VSS<89>":   PN = "11"  !CDS_PN = "11";
"VSS<90>":   PN = "9"  !CDS_PN = "9";
"VSS<91>":   PN = "6"  !CDS_PN = "6";
"VSS<92>":   PN = "4"  !CDS_PN = "4";
"VSS<93>":   PN = "2"  !CDS_PN = "2";
BODY = "SCONN288_H44441003","I87": #LOCATION = "J9L1" !CDS_LOCATION = "J9L1" #SEC = "2" !CDS_SEC = "2";
"DQS0N":   PN = "152"  !CDS_PN = "152";
"DQS0P":   PN = "153"  !CDS_PN = "153";
"DQS1N":   PN = "163"  !CDS_PN = "163";
"DQS1P":   PN = "164"  !CDS_PN = "164";
"DQS2N":   PN = "174"  !CDS_PN = "174";
"DQS2P":   PN = "175"  !CDS_PN = "175";
"DQS3N":   PN = "185"  !CDS_PN = "185";
"DQS3P":   PN = "186"  !CDS_PN = "186";
"DQS4N":   PN = "244"  !CDS_PN = "244";
"DQS4P":   PN = "245"  !CDS_PN = "245";
"DQS5N":   PN = "255"  !CDS_PN = "255";
"DQS5P":   PN = "256"  !CDS_PN = "256";
"DQS6N":   PN = "266"  !CDS_PN = "266";
"DQS6P":   PN = "267"  !CDS_PN = "267";
"DQS7N":   PN = "277"  !CDS_PN = "277";
"DQS7P":   PN = "278"  !CDS_PN = "278";
"DQS8N":   PN = "196"  !CDS_PN = "196";
"DQS8P":   PN = "197"  !CDS_PN = "197";
"DQS9N":   PN = "8"  !CDS_PN = "8";
"DQS9P":   PN = "7"  !CDS_PN = "7";
"DQS10N":   PN = "19"  !CDS_PN = "19";
"DQS10P":   PN = "18"  !CDS_PN = "18";
"DQS11N":   PN = "30"  !CDS_PN = "30";
"DQS11P":   PN = "29"  !CDS_PN = "29";
"DQS12N":   PN = "41"  !CDS_PN = "41";
"DQS12P":   PN = "40"  !CDS_PN = "40";
"DQS13N":   PN = "100"  !CDS_PN = "100";
"DQS13P":   PN = "99"  !CDS_PN = "99";
"DQS14N":   PN = "111"  !CDS_PN = "111";
"DQS14P":   PN = "110"  !CDS_PN = "110";
"DQS15N":   PN = "122"  !CDS_PN = "122";
"DQS15P":   PN = "121"  !CDS_PN = "121";
"DQS16N":   PN = "133"  !CDS_PN = "133";
"DQS16P":   PN = "132"  !CDS_PN = "132";
"DQS17N":   PN = "52"  !CDS_PN = "52";
"DQS17P":   PN = "51"  !CDS_PN = "51";
BODY = "SCONN288_H44441003","I111": #LOCATION = "J9L1" !CDS_LOCATION = "J9L1" #SEC = "1" !CDS_SEC = "1";
"A0":   PN = "79"  !CDS_PN = "79";
"A1":   PN = "72"  !CDS_PN = "72";
"A2":   PN = "216"  !CDS_PN = "216";
"A3":   PN = "71"  !CDS_PN = "71";
"A4":   PN = "214"  !CDS_PN = "214";
"A5":   PN = "213"  !CDS_PN = "213";
"A6":   PN = "69"  !CDS_PN = "69";
"A7":   PN = "211"  !CDS_PN = "211";
"A8":   PN = "68"  !CDS_PN = "68";
"A9":   PN = "66"  !CDS_PN = "66";
"A10":   PN = "225"  !CDS_PN = "225";
"A11":   PN = "210"  !CDS_PN = "210";
"A12":   PN = "65"  !CDS_PN = "65";
"A13":   PN = "232"  !CDS_PN = "232";
"A14_WE_N":   PN = "228"  !CDS_PN = "228";
"A15_CAS_N":   PN = "86"  !CDS_PN = "86";
"A16_RAS_N":   PN = "82"  !CDS_PN = "82";
"A17":   PN = "234"  !CDS_PN = "234";
"ACT_N":   PN = "62"  !CDS_PN = "62";
"ALERT_N":   PN = "208"  !CDS_PN = "208";
"BA<0>":   PN = "81"  !CDS_PN = "81";
"BA<1>":   PN = "224"  !CDS_PN = "224";
"BG<0>":   PN = "63"  !CDS_PN = "63";
"BG<1>":   PN = "207"  !CDS_PN = "207";
"C<2>":   PN = "235"  !CDS_PN = "235";
"CB<0>":   PN = "49"  !CDS_PN = "49";
"CB<1>":   PN = "194"  !CDS_PN = "194";
"CB<2>":   PN = "56"  !CDS_PN = "56";
"CB<3>":   PN = "201"  !CDS_PN = "201";
"CB<4>":   PN = "47"  !CDS_PN = "47";
"CB<5>":   PN = "192"  !CDS_PN = "192";
"CB<6>":   PN = "54"  !CDS_PN = "54";
"CB<7>":   PN = "199"  !CDS_PN = "199";
"CK0N":   PN = "75"  !CDS_PN = "75";
"CK0P":   PN = "74"  !CDS_PN = "74";
"CK1N":   PN = "219"  !CDS_PN = "219";
"CK1P":   PN = "218"  !CDS_PN = "218";
"CKE<0>":   PN = "60"  !CDS_PN = "60";
"CKE<1>":   PN = "203"  !CDS_PN = "203";
"DQ<0>":   PN = "5"  !CDS_PN = "5";
"DQ<1>":   PN = "150"  !CDS_PN = "150";
"DQ<2>":   PN = "12"  !CDS_PN = "12";
"DQ<3>":   PN = "157"  !CDS_PN = "157";
"DQ<4>":   PN = "3"  !CDS_PN = "3";
"DQ<5>":   PN = "148"  !CDS_PN = "148";
"DQ<6>":   PN = "10"  !CDS_PN = "10";
"DQ<7>":   PN = "155"  !CDS_PN = "155";
"DQ<8>":   PN = "16"  !CDS_PN = "16";
"DQ<9>":   PN = "161"  !CDS_PN = "161";
"DQ<10>":   PN = "23"  !CDS_PN = "23";
"DQ<11>":   PN = "168"  !CDS_PN = "168";
"DQ<12>":   PN = "14"  !CDS_PN = "14";
"DQ<13>":   PN = "159"  !CDS_PN = "159";
"DQ<14>":   PN = "21"  !CDS_PN = "21";
"DQ<15>":   PN = "166"  !CDS_PN = "166";
"DQ<16>":   PN = "27"  !CDS_PN = "27";
"DQ<17>":   PN = "172"  !CDS_PN = "172";
"DQ<18>":   PN = "34"  !CDS_PN = "34";
"DQ<19>":   PN = "179"  !CDS_PN = "179";
"DQ<20>":   PN = "25"  !CDS_PN = "25";
"DQ<21>":   PN = "170"  !CDS_PN = "170";
"DQ<22>":   PN = "32"  !CDS_PN = "32";
"DQ<23>":   PN = "177"  !CDS_PN = "177";
"DQ<24>":   PN = "38"  !CDS_PN = "38";
"DQ<25>":   PN = "183"  !CDS_PN = "183";
"DQ<26>":   PN = "45"  !CDS_PN = "45";
"DQ<27>":   PN = "190"  !CDS_PN = "190";
"DQ<28>":   PN = "36"  !CDS_PN = "36";
"DQ<29>":   PN = "181"  !CDS_PN = "181";
"DQ<30>":   PN = "43"  !CDS_PN = "43";
"DQ<31>":   PN = "188"  !CDS_PN = "188";
"DQ<32>":   PN = "97"  !CDS_PN = "97";
"DQ<33>":   PN = "242"  !CDS_PN = "242";
"DQ<34>":   PN = "104"  !CDS_PN = "104";
"DQ<35>":   PN = "249"  !CDS_PN = "249";
"DQ<36>":   PN = "95"  !CDS_PN = "95";
"DQ<37>":   PN = "240"  !CDS_PN = "240";
"DQ<38>":   PN = "102"  !CDS_PN = "102";
"DQ<39>":   PN = "247"  !CDS_PN = "247";
"DQ<40>":   PN = "108"  !CDS_PN = "108";
"DQ<41>":   PN = "253"  !CDS_PN = "253";
"DQ<42>":   PN = "115"  !CDS_PN = "115";
"DQ<43>":   PN = "260"  !CDS_PN = "260";
"DQ<44>":   PN = "106"  !CDS_PN = "106";
"DQ<45>":   PN = "251"  !CDS_PN = "251";
"DQ<46>":   PN = "113"  !CDS_PN = "113";
"DQ<47>":   PN = "258"  !CDS_PN = "258";
"DQ<48>":   PN = "119"  !CDS_PN = "119";
"DQ<49>":   PN = "264"  !CDS_PN = "264";
"DQ<50>":   PN = "126"  !CDS_PN = "126";
"DQ<51>":   PN = "271"  !CDS_PN = "271";
"DQ<52>":   PN = "117"  !CDS_PN = "117";
"DQ<53>":   PN = "262"  !CDS_PN = "262";
"DQ<54>":   PN = "124"  !CDS_PN = "124";
"DQ<55>":   PN = "269"  !CDS_PN = "269";
"DQ<56>":   PN = "130"  !CDS_PN = "130";
"DQ<57>":   PN = "275"  !CDS_PN = "275";
"DQ<58>":   PN = "137"  !CDS_PN = "137";
"DQ<59>":   PN = "282"  !CDS_PN = "282";
"DQ<60>":   PN = "128"  !CDS_PN = "128";
"DQ<61>":   PN = "273"  !CDS_PN = "273";
"DQ<62>":   PN = "135"  !CDS_PN = "135";
"DQ<63>":   PN = "280"  !CDS_PN = "280";
"EVENT_N":   PN = "78"  !CDS_PN = "78";
"ODT<0>":   PN = "87"  !CDS_PN = "87";
"ODT<1>":   PN = "91"  !CDS_PN = "91";
"PAR":   PN = "222"  !CDS_PN = "222";
"RESET_N":   PN = "58"  !CDS_PN = "58";
"RFU<0>":   PN = "205"  !CDS_PN = "205";
"RFU<1>":   PN = "227"  !CDS_PN = "227";
"RFU<2>":   PN = "144"  !CDS_PN = "144";
"S0_N":   PN = "84"  !CDS_PN = "84";
"S1_N":   PN = "89"  !CDS_PN = "89";
"S2_N_C<0>":   PN = "93"  !CDS_PN = "93";
"S3_N_C<1>":   PN = "237"  !CDS_PN = "237";
"SA<0>":   PN = "139"  !CDS_PN = "139";
"SA<1>":   PN = "140"  !CDS_PN = "140";
"SA<2>":   PN = "238"  !CDS_PN = "238";
"SAVE_N_NC":   PN = "230"  !CDS_PN = "230";
"SCL":   PN = "141"  !CDS_PN = "141";
"SDA":   PN = "285"  !CDS_PN = "285";
"VDDSPD":   PN = "284"  !CDS_PN = "284";
"VREFCA":   PN = "146"  !CDS_PN = "146";
BODY = "SCONN288_H44441003","I168": #LOCATION = "J9L1" !CDS_LOCATION = "J9L1" #SEC = "4" !CDS_SEC = "4";
"12V<0>":   PN = "145"  !CDS_PN = "145";
"12V<1>":   PN = "1"  !CDS_PN = "1";
"VDD<0>":   PN = "236"  !CDS_PN = "236";
"VDD<1>":   PN = "233"  !CDS_PN = "233";
"VDD<2>":   PN = "231"  !CDS_PN = "231";
"VDD<3>":   PN = "229"  !CDS_PN = "229";
"VDD<4>":   PN = "226"  !CDS_PN = "226";
"VDD<5>":   PN = "223"  !CDS_PN = "223";
"VDD<6>":   PN = "220"  !CDS_PN = "220";
"VDD<7>":   PN = "217"  !CDS_PN = "217";
"VDD<8>":   PN = "215"  !CDS_PN = "215";
"VDD<9>":   PN = "212"  !CDS_PN = "212";
"VDD<10>":   PN = "209"  !CDS_PN = "209";
"VDD<11>":   PN = "206"  !CDS_PN = "206";
"VDD<12>":   PN = "204"  !CDS_PN = "204";
"VDD<13>":   PN = "92"  !CDS_PN = "92";
"VDD<14>":   PN = "90"  !CDS_PN = "90";
"VDD<15>":   PN = "88"  !CDS_PN = "88";
"VDD<16>":   PN = "85"  !CDS_PN = "85";
"VDD<17>":   PN = "83"  !CDS_PN = "83";
"VDD<18>":   PN = "80"  !CDS_PN = "80";
"VDD<19>":   PN = "76"  !CDS_PN = "76";
"VDD<20>":   PN = "73"  !CDS_PN = "73";
"VDD<21>":   PN = "70"  !CDS_PN = "70";
"VDD<22>":   PN = "67"  !CDS_PN = "67";
"VDD<23>":   PN = "64"  !CDS_PN = "64";
"VDD<24>":   PN = "61"  !CDS_PN = "61";
"VDD<25>":   PN = "59"  !CDS_PN = "59";
"VPP<0>":   PN = "287"  !CDS_PN = "287";
"VPP<1>":   PN = "286"  !CDS_PN = "286";
"VPP<2>":   PN = "288"  !CDS_PN = "288";
"VPP<3>":   PN = "143"  !CDS_PN = "143";
"VPP<4>":   PN = "142"  !CDS_PN = "142";
"VTT<0>":   PN = "221"  !CDS_PN = "221";
"VTT<1>":   PN = "77"  !CDS_PN = "77";
BODY = "CAP_A","I177": #LOCATION = "C9L1" !CDS_LOCATION = "C9L1" #SEC = "1" !CDS_SEC = "1";
"A":   PN = "1"  !CDS_PN = "1";
"B":   PN = "2"  !CDS_PN = "2";
DRAWING = "@baseboard_fab2_lib.baseboard_fab2(sch_1):page89";
BODY = "RES","I1": #LOCATION = "R4T2" !CDS_LOCATION = "R4T2" #SEC = "1" !CDS_SEC = "1";
"A":   PN = "1"  !CDS_PN = "1";
"B":   PN = "2"  !CDS_PN = "2";
BODY = "RES","I2": #LOCATION = "R4T1" !CDS_LOCATION = "R4T1" #SEC = "1" !CDS_SEC = "1";
"A":   PN = "1"  !CDS_PN = "1";
"B":   PN = "2"  !CDS_PN = "2";
BODY = "RES","I3": #LOCATION = "R6F4" !CDS_LOCATION = "R6F4" #SEC = "1" !CDS_SEC = "1";
"A":   PN = "1"  !CDS_PN = "1";
"B":   PN = "2"  !CDS_PN = "2";
BODY = "RES","I4": #LOCATION = "R6F1" !CDS_LOCATION = "R6F1" #SEC = "1" !CDS_SEC = "1";
"A":   PN = "1"  !CDS_PN = "1";
"B":   PN = "2"  !CDS_PN = "2";
BODY = "RES","I5": #LOCATION = "R6F5" !CDS_LOCATION = "R6F5" #SEC = "1" !CDS_SEC = "1";
"A":   PN = "1"  !CDS_PN = "1";
"B":   PN = "2"  !CDS_PN = "2";
BODY = "RES","I6": #LOCATION = "R6F2" !CDS_LOCATION = "R6F2" #SEC = "1" !CDS_SEC = "1";
"A":   PN = "1"  !CDS_PN = "1";
"B":   PN = "2"  !CDS_PN = "2";
BODY = "RES","I7": #LOCATION = "R6F3" !CDS_LOCATION = "R6F3" #SEC = "1" !CDS_SEC = "1";
"A":   PN = "1"  !CDS_PN = "1";
"B":   PN = "2"  !CDS_PN = "2";
BODY = "FET_N","I18": #LOCATION = "Q6F1" !CDS_LOCATION = "Q6F1" #SEC = "1" !CDS_SEC = "1";
"DRN":   PN = "3"  !CDS_PN = "3";
"GATE":   PN = "1"  !CDS_PN = "1";
"SRC":   PN = "2"  !CDS_PN = "2";
BODY = "RES","I23": #LOCATION = "R2P12" !CDS_LOCATION = "R2P12" &SEC = "1" #&CDS_SEC = "1";
"A":   PN = "1"  !CDS_PN = "1";
"B":   PN = "2"  !CDS_PN = "2";
BODY = "RES","I26": #LOCATION = "R8D29" !CDS_LOCATION = "R8D29" &SEC = "1" #&CDS_SEC = "1";
"A":   PN = "1"  !CDS_PN = "1";
"B":   PN = "2"  !CDS_PN = "2";
BODY = "RES","I27": #LOCATION = "R8D31" !CDS_LOCATION = "R8D31" &SEC = "1" #&CDS_SEC = "1";
"A":   PN = "1"  !CDS_PN = "1";
"B":   PN = "2"  !CDS_PN = "2";
BODY = "RES","I34": #LOCATION = "R8D30" !CDS_LOCATION = "R8D30" #SEC = "1" !CDS_SEC = "1";
"A":   PN = "1"  !CDS_PN = "1";
"B":   PN = "2"  !CDS_PN = "2";
BODY = "NPN_DUAL","I35": #LOCATION = "Q8D1" !CDS_LOCATION = "Q8D1" #SEC = "1" !CDS_SEC = "1";
"B<0>":   PN = "5"  !CDS_PN = "5";
"C<0>":   PN = "3"  !CDS_PN = "3";
"E<0>":   PN = "4"  !CDS_PN = "4";
BODY = "NPN_DUAL","I36": #LOCATION = "Q8D1" !CDS_LOCATION = "Q8D1" #SEC = "2" !CDS_SEC = "2";
"B<0>":   PN = "2"  !CDS_PN = "2";
"C<0>":   PN = "6"  !CDS_PN = "6";
"E<0>":   PN = "1"  !CDS_PN = "1";
DRAWING = "@baseboard_fab2_lib.baseboard_fab2(sch_1):page90";
BODY = "RES","I3": #LOCATION = "R6D6" !CDS_LOCATION = "R6D6" #SEC = "1" !CDS_SEC = "1";
"A":   PN = "1"  !CDS_PN = "1";
"B":   PN = "2"  !CDS_PN = "2";
BODY = "RES","I4": #LOCATION = "R4P1" !CDS_LOCATION = "R4P1" #SEC = "1" !CDS_SEC = "1";
"A":   PN = "1"  !CDS_PN = "1";
"B":   PN = "2"  !CDS_PN = "2";
BODY = "RES","I11": #LOCATION = "R3D12" !CDS_LOCATION = "R3D12" #SEC = "1" !CDS_SEC = "1";
"A":   PN = "1"  !CDS_PN = "1";
"B":   PN = "2"  !CDS_PN = "2";
BODY = "RES","I12": #LOCATION = "R3D13" !CDS_LOCATION = "R3D13" #SEC = "1" !CDS_SEC = "1";
"A":   PN = "1"  !CDS_PN = "1";
"B":   PN = "2"  !CDS_PN = "2";
BODY = "RES","I17": #LOCATION = "R3D22" !CDS_LOCATION = "R3D22" #SEC = "1" !CDS_SEC = "1";
"A":   PN = "1"  !CDS_PN = "1";
"B":   PN = "2"  !CDS_PN = "2";
BODY = "RES","I24": #LOCATION = "R3D16" !CDS_LOCATION = "R3D16" #SEC = "1" !CDS_SEC = "1";
"A":   PN = "1"  !CDS_PN = "1";
"B":   PN = "2"  !CDS_PN = "2";
BODY = "RES","I25": #LOCATION = "R3D23" !CDS_LOCATION = "R3D23" &SEC = "1" #&CDS_SEC = "1";
"A":   PN = "1"  !CDS_PN = "1";
"B":   PN = "2"  !CDS_PN = "2";
BODY = "RES","I28": #LOCATION = "R3D26" !CDS_LOCATION = "R3D26" #SEC = "1" !CDS_SEC = "1";
"A":   PN = "1"  !CDS_PN = "1";
"B":   PN = "2"  !CDS_PN = "2";
BODY = "RES","I29": #LOCATION = "R5D3" !CDS_LOCATION = "R5D3" #SEC = "1" !CDS_SEC = "1";
"A":   PN = "1"  !CDS_PN = "1";
"B":   PN = "2"  !CDS_PN = "2";
BODY = "RES","I31": #LOCATION = "R6D7" !CDS_LOCATION = "R6D7" #SEC = "1" !CDS_SEC = "1";
"A":   PN = "1"  !CDS_PN = "1";
"B":   PN = "2"  !CDS_PN = "2";
BODY = "RES","I32": #LOCATION = "R5D4" !CDS_LOCATION = "R5D4" #SEC = "1" !CDS_SEC = "1";
"A":   PN = "1"  !CDS_PN = "1";
"B":   PN = "2"  !CDS_PN = "2";
BODY = "RES","I33": #LOCATION = "R6D13" !CDS_LOCATION = "R6D13" #SEC = "1" !CDS_SEC = "1";
"A":   PN = "1"  !CDS_PN = "1";
"B":   PN = "2"  !CDS_PN = "2";
BODY = "RES","I48": #LOCATION = "R6D15" !CDS_LOCATION = "R6D15" #SEC = "1" !CDS_SEC = "1";
"A":   PN = "1"  !CDS_PN = "1";
"B":   PN = "2"  !CDS_PN = "2";
BODY = "RES","I49": #LOCATION = "R6D10" !CDS_LOCATION = "R6D10" #SEC = "1" !CDS_SEC = "1";
"A":   PN = "1"  !CDS_PN = "1";
"B":   PN = "2"  !CDS_PN = "2";
BODY = "RES","I52": #LOCATION = "R6D14" !CDS_LOCATION = "R6D14" #SEC = "1" !CDS_SEC = "1";
"A":   PN = "1"  !CDS_PN = "1";
"B":   PN = "2"  !CDS_PN = "2";
BODY = "RES","I53": #LOCATION = "R4P14" !CDS_LOCATION = "R4P14" #SEC = "1" !CDS_SEC = "1";
"A":   PN = "1"  !CDS_PN = "1";
"B":   PN = "2"  !CDS_PN = "2";
BODY = "RES","I59": #LOCATION = "R3D24" !CDS_LOCATION = "R3D24" &SEC = "1" #&CDS_SEC = "1";
"A":   PN = "1"  !CDS_PN = "1";
"B":   PN = "2"  !CDS_PN = "2";
BODY = "RES","I60": #LOCATION = "R3D17" !CDS_LOCATION = "R3D17" &SEC = "1" #&CDS_SEC = "1";
"A":   PN = "1"  !CDS_PN = "1";
"B":   PN = "2"  !CDS_PN = "2";
BODY = "RES","I66": #LOCATION = "R3D25" !CDS_LOCATION = "R3D25" #SEC = "1" !CDS_SEC = "1";
"A":   PN = "1"  !CDS_PN = "1";
"B":   PN = "2"  !CDS_PN = "2";
BODY = "RES","I68": #LOCATION = "R4P6" !CDS_LOCATION = "R4P6" #SEC = "1" !CDS_SEC = "1";
"A":   PN = "1"  !CDS_PN = "1";
"B":   PN = "2"  !CDS_PN = "2";
BODY = "RES","I70": #LOCATION = "R7P14" !CDS_LOCATION = "R7P14" #SEC = "1" !CDS_SEC = "1";
"A":   PN = "1"  !CDS_PN = "1";
"B":   PN = "2"  !CDS_PN = "2";
BODY = "RES","I72": #LOCATION = "R4P7" !CDS_LOCATION = "R4P7" #SEC = "1" !CDS_SEC = "1";
"A":   PN = "1"  !CDS_PN = "1";
"B":   PN = "2"  !CDS_PN = "2";
BODY = "RES","I74": #LOCATION = "R7P15" !CDS_LOCATION = "R7P15" #SEC = "1" !CDS_SEC = "1";
"A":   PN = "1"  !CDS_PN = "1";
"B":   PN = "2"  !CDS_PN = "2";
BODY = "RES","I76": #LOCATION = "R7P22" !CDS_LOCATION = "R7P22" #SEC = "1" !CDS_SEC = "1";
"A":   PN = "1"  !CDS_PN = "1";
"B":   PN = "2"  !CDS_PN = "2";
BODY = "RES","I79": #LOCATION = "R5P2" !CDS_LOCATION = "R5P2" #SEC = "1" !CDS_SEC = "1";
"A":   PN = "1"  !CDS_PN = "1";
"B":   PN = "2"  !CDS_PN = "2";
BODY = "RES","I80": #LOCATION = "R5P3" !CDS_LOCATION = "R5P3" #SEC = "1" !CDS_SEC = "1";
"A":   PN = "1"  !CDS_PN = "1";
"B":   PN = "2"  !CDS_PN = "2";
BODY = "RES","I81": #LOCATION = "R6D5" !CDS_LOCATION = "R6D5" #SEC = "1" !CDS_SEC = "1";
"A":   PN = "1"  !CDS_PN = "1";
"B":   PN = "2"  !CDS_PN = "2";
BODY = "RES","I85": #LOCATION = "R8P1" !CDS_LOCATION = "R8P1" #SEC = "1" !CDS_SEC = "1";
"A":   PN = "1"  !CDS_PN = "1";
"B":   PN = "2"  !CDS_PN = "2";
BODY = "RES","I86": #LOCATION = "R8P2" !CDS_LOCATION = "R8P2" #SEC = "1" !CDS_SEC = "1";
"A":   PN = "1"  !CDS_PN = "1";
"B":   PN = "2"  !CDS_PN = "2";
BODY = "RES","I88": #LOCATION = "R3D9" !CDS_LOCATION = "R3D9" #SEC = "1" !CDS_SEC = "1";
"A":   PN = "1"  !CDS_PN = "1";
"B":   PN = "2"  !CDS_PN = "2";
DRAWING = "@baseboard_fab2_lib.baseboard_fab2(sch_1):page91";
BODY = "SCONN24_H46321001","I1": #LOCATION = "J8B1" !CDS_LOCATION = "J8B1" &SEC = "1" #&CDS_SEC = "1";
"IO1":   PN = "1"  !CDS_PN = "1";
"IO2":   PN = "2"  !CDS_PN = "2";
"IO3":   PN = "3"  !CDS_PN = "3";
"IO4":   PN = "4"  !CDS_PN = "4";
"IO5":   PN = "5"  !CDS_PN = "5";
"IO6":   PN = "6"  !CDS_PN = "6";
"IO7":   PN = "7"  !CDS_PN = "7";
"IO8":   PN = "8"  !CDS_PN = "8";
"IO9":   PN = "9"  !CDS_PN = "9";
"IO10":   PN = "10"  !CDS_PN = "10";
"IO11":   PN = "11"  !CDS_PN = "11";
"IO12":   PN = "12"  !CDS_PN = "12";
"IO13":   PN = "13"  !CDS_PN = "13";
"IO14":   PN = "14"  !CDS_PN = "14";
"IO15":   PN = "15"  !CDS_PN = "15";
"IO16":   PN = "16"  !CDS_PN = "16";
"IO17":   PN = "17"  !CDS_PN = "17";
"IO18":   PN = "18"  !CDS_PN = "18";
"IO19":   PN = "19"  !CDS_PN = "19";
"IO20":   PN = "20"  !CDS_PN = "20";
"IO21":   PN = "21"  !CDS_PN = "21";
"IO22":   PN = "22"  !CDS_PN = "22";
"IO23":   PN = "23"  !CDS_PN = "23";
"IO24":   PN = "24"  !CDS_PN = "24";
"MP1":   PN = "MP1"  !CDS_PN = "MP1";
"MP2":   PN = "MP2"  !CDS_PN = "MP2";
BODY = "RES","I14": #LOCATION = "R8B8" !CDS_LOCATION = "R8B8" #SEC = "1" !CDS_SEC = "1";
"A":   PN = "1"  !CDS_PN = "1";
"B":   PN = "2"  !CDS_PN = "2";
BODY = "RES","I16": #LOCATION = "R8B10" !CDS_LOCATION = "R8B10" #SEC = "1" !CDS_SEC = "1";
"A":   PN = "1"  !CDS_PN = "1";
"B":   PN = "2"  !CDS_PN = "2";
BODY = "RES","I17": #LOCATION = "R8B16" !CDS_LOCATION = "R8B16" #SEC = "1" !CDS_SEC = "1";
"A":   PN = "1"  !CDS_PN = "1";
"B":   PN = "2"  !CDS_PN = "2";
BODY = "RES","I18": #LOCATION = "R8B17" !CDS_LOCATION = "R8B17" #SEC = "1" !CDS_SEC = "1";
"A":   PN = "1"  !CDS_PN = "1";
"B":   PN = "2"  !CDS_PN = "2";
BODY = "RES","I20": #LOCATION = "R8B18" !CDS_LOCATION = "R8B18" #SEC = "1" !CDS_SEC = "1";
"A":   PN = "1"  !CDS_PN = "1";
"B":   PN = "2"  !CDS_PN = "2";
BODY = "RES","I21": #LOCATION = "R8B19" !CDS_LOCATION = "R8B19" #SEC = "1" !CDS_SEC = "1";
"A":   PN = "1"  !CDS_PN = "1";
"B":   PN = "2"  !CDS_PN = "2";
BODY = "RES","I22": #LOCATION = "R8B5" !CDS_LOCATION = "R8B5" #SEC = "1" !CDS_SEC = "1";
"A":   PN = "1"  !CDS_PN = "1";
"B":   PN = "2"  !CDS_PN = "2";
BODY = "RES","I24": #LOCATION = "R8B3" !CDS_LOCATION = "R8B3" #SEC = "1" !CDS_SEC = "1";
"A":   PN = "1"  !CDS_PN = "1";
"B":   PN = "2"  !CDS_PN = "2";
BODY = "RES","I34": #LOCATION = "R8B13" !CDS_LOCATION = "R8B13" #SEC = "1" !CDS_SEC = "1";
"A":   PN = "1"  !CDS_PN = "1";
"B":   PN = "2"  !CDS_PN = "2";
BODY = "RES","I35": #LOCATION = "R8B11" !CDS_LOCATION = "R8B11" #SEC = "1" !CDS_SEC = "1";
"A":   PN = "1"  !CDS_PN = "1";
"B":   PN = "2"  !CDS_PN = "2";
BODY = "RES","I36": #LOCATION = "R8B7" !CDS_LOCATION = "R8B7" #SEC = "1" !CDS_SEC = "1";
"A":   PN = "1"  !CDS_PN = "1";
"B":   PN = "2"  !CDS_PN = "2";
BODY = "RES","I37": #LOCATION = "R8B6" !CDS_LOCATION = "R8B6" #SEC = "1" !CDS_SEC = "1";
"A":   PN = "1"  !CDS_PN = "1";
"B":   PN = "2"  !CDS_PN = "2";
DRAWING = "@baseboard_fab2_lib.baseboard_fab2(sch_1):page92";
BODY = "GTL2014","I1": #LOCATION = "U3P2" !CDS_LOCATION = "U3P2" #SEC = "1" !CDS_SEC = "1";
"A0":   PN = "13"  !CDS_PN = "13";
"A1":   PN = "12"  !CDS_PN = "12";
"A2":   PN = "10"  !CDS_PN = "10";
"A3":   PN = "9"  !CDS_PN = "9";
"B0":   PN = "2"  !CDS_PN = "2";
"B1":   PN = "3"  !CDS_PN = "3";
"B2":   PN = "5"  !CDS_PN = "5";
"B3":   PN = "6"  !CDS_PN = "6";
"DIR":   PN = "1"  !CDS_PN = "1";
"GND<0>":   PN = "7"  !CDS_PN = "7";
"GND<1>":   PN = "8"  !CDS_PN = "8";
"GND<2>":   PN = "11"  !CDS_PN = "11";
"VCC":   PN = "14"  !CDS_PN = "14";
"VREF":   PN = "4"  !CDS_PN = "4";
BODY = "RES","I9": #LOCATION = "R3P41" !CDS_LOCATION = "R3P41" #SEC = "1" !CDS_SEC = "1";
"A":   PN = "1"  !CDS_PN = "1";
"B":   PN = "2"  !CDS_PN = "2";
BODY = "RES","I12": #LOCATION = "R3P46" !CDS_LOCATION = "R3P46" #SEC = "1" !CDS_SEC = "1";
"A":   PN = "1"  !CDS_PN = "1";
"B":   PN = "2"  !CDS_PN = "2";
BODY = "RES","I13": #LOCATION = "R3P43" !CDS_LOCATION = "R3P43" #SEC = "1" !CDS_SEC = "1";
"A":   PN = "1"  !CDS_PN = "1";
"B":   PN = "2"  !CDS_PN = "2";
BODY = "RES","I14": #LOCATION = "R3P42" !CDS_LOCATION = "R3P42" #SEC = "1" !CDS_SEC = "1";
"A":   PN = "1"  !CDS_PN = "1";
"B":   PN = "2"  !CDS_PN = "2";
BODY = "RES","I19": #LOCATION = "R7E2" !CDS_LOCATION = "R7E2" #SEC = "1" !CDS_SEC = "1";
"A":   PN = "1"  !CDS_PN = "1";
"B":   PN = "2"  !CDS_PN = "2";
BODY = "RES","I24": #LOCATION = "R7D34" !CDS_LOCATION = "R7D34" #SEC = "1" !CDS_SEC = "1";
"A":   PN = "1"  !CDS_PN = "1";
"B":   PN = "2"  !CDS_PN = "2";
BODY = "RES","I29": #LOCATION = "R7D31" !CDS_LOCATION = "R7D31" #SEC = "1" !CDS_SEC = "1";
"A":   PN = "1"  !CDS_PN = "1";
"B":   PN = "2"  !CDS_PN = "2";
BODY = "RES","I30": #LOCATION = "R7D29" !CDS_LOCATION = "R7D29" #SEC = "1" !CDS_SEC = "1";
"A":   PN = "1"  !CDS_PN = "1";
"B":   PN = "2"  !CDS_PN = "2";
BODY = "GTL2014","I32": #LOCATION = "U7D2" !CDS_LOCATION = "U7D2" #SEC = "1" !CDS_SEC = "1";
"A0":   PN = "13"  !CDS_PN = "13";
"A1":   PN = "12"  !CDS_PN = "12";
"A2":   PN = "10"  !CDS_PN = "10";
"A3":   PN = "9"  !CDS_PN = "9";
"B0":   PN = "2"  !CDS_PN = "2";
"B1":   PN = "3"  !CDS_PN = "3";
"B2":   PN = "5"  !CDS_PN = "5";
"B3":   PN = "6"  !CDS_PN = "6";
"DIR":   PN = "1"  !CDS_PN = "1";
"GND<0>":   PN = "7"  !CDS_PN = "7";
"GND<1>":   PN = "8"  !CDS_PN = "8";
"GND<2>":   PN = "11"  !CDS_PN = "11";
"VCC":   PN = "14"  !CDS_PN = "14";
"VREF":   PN = "4"  !CDS_PN = "4";
BODY = "CAP_A","I37": #LOCATION = "C3P49" !CDS_LOCATION = "C3P49" #SEC = "1" !CDS_SEC = "1";
"A":   PN = "1"  !CDS_PN = "1";
"B":   PN = "2"  !CDS_PN = "2";
BODY = "RES","I38": #LOCATION = "R3P49" !CDS_LOCATION = "R3P49" #SEC = "1" !CDS_SEC = "1";
"A":   PN = "1"  !CDS_PN = "1";
"B":   PN = "2"  !CDS_PN = "2";
BODY = "RES","I39": #LOCATION = "R3P45" !CDS_LOCATION = "R3P45" #SEC = "1" !CDS_SEC = "1";
"A":   PN = "1"  !CDS_PN = "1";
"B":   PN = "2"  !CDS_PN = "2";
BODY = "RES","I46": #LOCATION = "R3R1" !CDS_LOCATION = "R3R1" #SEC = "1" !CDS_SEC = "1";
"A":   PN = "1"  !CDS_PN = "1";
"B":   PN = "2"  !CDS_PN = "2";
BODY = "RES","I48": #LOCATION = "R7D32" !CDS_LOCATION = "R7D32" #SEC = "1" !CDS_SEC = "1";
"A":   PN = "1"  !CDS_PN = "1";
"B":   PN = "2"  !CDS_PN = "2";
BODY = "RES","I51": #LOCATION = "R7D33" !CDS_LOCATION = "R7D33" #SEC = "1" !CDS_SEC = "1";
"A":   PN = "1"  !CDS_PN = "1";
"B":   PN = "2"  !CDS_PN = "2";
BODY = "CAP_A","I52": #LOCATION = "C7D5" !CDS_LOCATION = "C7D5" #SEC = "1" !CDS_SEC = "1";
"A":   PN = "1"  !CDS_PN = "1";
"B":   PN = "2"  !CDS_PN = "2";
BODY = "RES","I54": #LOCATION = "R7D26" !CDS_LOCATION = "R7D26" #SEC = "1" !CDS_SEC = "1";
"A":   PN = "1"  !CDS_PN = "1";
"B":   PN = "2"  !CDS_PN = "2";
BODY = "RES","I61": #LOCATION = "R3R3" !CDS_LOCATION = "R3R3" #SEC = "1" !CDS_SEC = "1";
"A":   PN = "1"  !CDS_PN = "1";
"B":   PN = "2"  !CDS_PN = "2";
BODY = "RES","I64": #LOCATION = "R6D9" !CDS_LOCATION = "R6D9" #SEC = "1" !CDS_SEC = "1";
"A":   PN = "1"  !CDS_PN = "1";
"B":   PN = "2"  !CDS_PN = "2";
BODY = "RES","I65": #LOCATION = "R7P27" !CDS_LOCATION = "R7P27" #SEC = "1" !CDS_SEC = "1";
"A":   PN = "1"  !CDS_PN = "1";
"B":   PN = "2"  !CDS_PN = "2";
BODY = "RES","I67": #LOCATION = "R7D28" !CDS_LOCATION = "R7D28" #SEC = "1" !CDS_SEC = "1";
"A":   PN = "1"  !CDS_PN = "1";
"B":   PN = "2"  !CDS_PN = "2";
BODY = "RES","I68": #LOCATION = "R7D27" !CDS_LOCATION = "R7D27" #SEC = "1" !CDS_SEC = "1";
"A":   PN = "1"  !CDS_PN = "1";
"B":   PN = "2"  !CDS_PN = "2";
BODY = "RES","I70": #LOCATION = "R7D25" !CDS_LOCATION = "R7D25" #SEC = "1" !CDS_SEC = "1";
"A":   PN = "1"  !CDS_PN = "1";
"B":   PN = "2"  !CDS_PN = "2";
BODY = "RES","I75": #LOCATION = "R3R2" !CDS_LOCATION = "R3R2" #SEC = "1" !CDS_SEC = "1";
"A":   PN = "1"  !CDS_PN = "1";
"B":   PN = "2"  !CDS_PN = "2";
BODY = "CAP","I79": #LOCATION = "C7D4" !CDS_LOCATION = "C7D4" #SEC = "1" !CDS_SEC = "1";
"A":   PN = "1"  !CDS_PN = "1";
"B":   PN = "2"  !CDS_PN = "2";
BODY = "CAP","I84": #LOCATION = "C3P50" !CDS_LOCATION = "C3P50" #SEC = "1" !CDS_SEC = "1";
"A":   PN = "1"  !CDS_PN = "1";
"B":   PN = "2"  !CDS_PN = "2";
BODY = "RES","I92": #LOCATION = "R2T44" !CDS_LOCATION = "R2T44" &SEC = "1" #&CDS_SEC = "1";
"A":   PN = "1"  !CDS_PN = "1";
"B":   PN = "2"  !CDS_PN = "2";
BODY = "RES","I93": #LOCATION = "R2T40" !CDS_LOCATION = "R2T40" &SEC = "1" #&CDS_SEC = "1";
"A":   PN = "1"  !CDS_PN = "1";
"B":   PN = "2"  !CDS_PN = "2";
BODY = "RES","I94": #LOCATION = "R2T37" !CDS_LOCATION = "R2T37" &SEC = "1" #&CDS_SEC = "1";
"A":   PN = "1"  !CDS_PN = "1";
"B":   PN = "2"  !CDS_PN = "2";
BODY = "RES","I96": #LOCATION = "R2T43" !CDS_LOCATION = "R2T43" &SEC = "1" #&CDS_SEC = "1";
"A":   PN = "1"  !CDS_PN = "1";
"B":   PN = "2"  !CDS_PN = "2";
BODY = "RES","I97": #LOCATION = "R3P59" !CDS_LOCATION = "R3P59" #SEC = "1" !CDS_SEC = "1";
"A":   PN = "1"  !CDS_PN = "1";
"B":   PN = "2"  !CDS_PN = "2";
BODY = "RES","I98": #LOCATION = "R3P58" !CDS_LOCATION = "R3P58" #SEC = "1" !CDS_SEC = "1";
"A":   PN = "1"  !CDS_PN = "1";
"B":   PN = "2"  !CDS_PN = "2";
BODY = "RES","I100": #LOCATION = "R7P18" !CDS_LOCATION = "R7P18" #SEC = "1" !CDS_SEC = "1";
"A":   PN = "1"  !CDS_PN = "1";
"B":   PN = "2"  !CDS_PN = "2";
BODY = "RES","I101": #LOCATION = "R4R2" !CDS_LOCATION = "R4R2" #SEC = "1" !CDS_SEC = "1";
"A":   PN = "1"  !CDS_PN = "1";
"B":   PN = "2"  !CDS_PN = "2";
DRAWING = "@baseboard_fab2_lib.baseboard_fab2(sch_1):page93";
BODY = "RES","I13": #LOCATION = "R2T27" !CDS_LOCATION = "R2T27" #SEC = "1" !CDS_SEC = "1";
"A":   PN = "1"  !CDS_PN = "1";
"B":   PN = "2"  !CDS_PN = "2";
BODY = "RES","I15": #LOCATION = "R2T32" !CDS_LOCATION = "R2T32" #SEC = "1" !CDS_SEC = "1";
"A":   PN = "1"  !CDS_PN = "1";
"B":   PN = "2"  !CDS_PN = "2";
BODY = "RES","I16": #LOCATION = "R2T20" !CDS_LOCATION = "R2T20" #SEC = "1" !CDS_SEC = "1";
"A":   PN = "1"  !CDS_PN = "1";
"B":   PN = "2"  !CDS_PN = "2";
BODY = "RES","I23": #LOCATION = "R2T17" !CDS_LOCATION = "R2T17" #SEC = "1" !CDS_SEC = "1";
"A":   PN = "1"  !CDS_PN = "1";
"B":   PN = "2"  !CDS_PN = "2";
BODY = "GTL2014","I30": #LOCATION = "U2T4" !CDS_LOCATION = "U2T4" #SEC = "1" !CDS_SEC = "1";
"A0":   PN = "13"  !CDS_PN = "13";
"A1":   PN = "12"  !CDS_PN = "12";
"A2":   PN = "10"  !CDS_PN = "10";
"A3":   PN = "9"  !CDS_PN = "9";
"B0":   PN = "2"  !CDS_PN = "2";
"B1":   PN = "3"  !CDS_PN = "3";
"B2":   PN = "5"  !CDS_PN = "5";
"B3":   PN = "6"  !CDS_PN = "6";
"DIR":   PN = "1"  !CDS_PN = "1";
"GND<0>":   PN = "7"  !CDS_PN = "7";
"GND<1>":   PN = "8"  !CDS_PN = "8";
"GND<2>":   PN = "11"  !CDS_PN = "11";
"VCC":   PN = "14"  !CDS_PN = "14";
"VREF":   PN = "4"  !CDS_PN = "4";
BODY = "RES","I39": #LOCATION = "R2T38" !CDS_LOCATION = "R2T38" #SEC = "1" !CDS_SEC = "1";
"A":   PN = "1"  !CDS_PN = "1";
"B":   PN = "2"  !CDS_PN = "2";
BODY = "RES","I40": #LOCATION = "R2T33" !CDS_LOCATION = "R2T33" #SEC = "1" !CDS_SEC = "1";
"A":   PN = "1"  !CDS_PN = "1";
"B":   PN = "2"  !CDS_PN = "2";
BODY = "RES","I42": #LOCATION = "R2T30" !CDS_LOCATION = "R2T30" #SEC = "1" !CDS_SEC = "1";
"A":   PN = "1"  !CDS_PN = "1";
"B":   PN = "2"  !CDS_PN = "2";
BODY = "RES","I62": #LOCATION = "R7D24" !CDS_LOCATION = "R7D24" #SEC = "1" !CDS_SEC = "1";
"A":   PN = "1"  !CDS_PN = "1";
"B":   PN = "2"  !CDS_PN = "2";
BODY = "RES","I63": #LOCATION = "R2T19" !CDS_LOCATION = "R2T19" #SEC = "1" !CDS_SEC = "1";
"A":   PN = "1"  !CDS_PN = "1";
"B":   PN = "2"  !CDS_PN = "2";
BODY = "RES","I67": #LOCATION = "R2T16" !CDS_LOCATION = "R2T16" #SEC = "1" !CDS_SEC = "1";
"A":   PN = "1"  !CDS_PN = "1";
"B":   PN = "2"  !CDS_PN = "2";
BODY = "RES","I68": #LOCATION = "R2T31" !CDS_LOCATION = "R2T31" #SEC = "1" !CDS_SEC = "1";
"A":   PN = "1"  !CDS_PN = "1";
"B":   PN = "2"  !CDS_PN = "2";
BODY = "CAP_A","I72": #LOCATION = "C2T33" !CDS_LOCATION = "C2T33" #SEC = "1" !CDS_SEC = "1";
"A":   PN = "1"  !CDS_PN = "1";
"B":   PN = "2"  !CDS_PN = "2";
BODY = "RES","I79": #LOCATION = "R4R3" !CDS_LOCATION = "R4R3" #SEC = "1" !CDS_SEC = "1";
"A":   PN = "1"  !CDS_PN = "1";
"B":   PN = "2"  !CDS_PN = "2";
BODY = "RES","I87": #LOCATION = "R2T26" !CDS_LOCATION = "R2T26" #SEC = "1" !CDS_SEC = "1";
"A":   PN = "1"  !CDS_PN = "1";
"B":   PN = "2"  !CDS_PN = "2";
BODY = "RES","I88": #LOCATION = "R2T57" !CDS_LOCATION = "R2T57" #SEC = "1" !CDS_SEC = "1";
"A":   PN = "1"  !CDS_PN = "1";
"B":   PN = "2"  !CDS_PN = "2";
BODY = "RES","I89": #LOCATION = "R2T61" !CDS_LOCATION = "R2T61" #SEC = "1" !CDS_SEC = "1";
"A":   PN = "1"  !CDS_PN = "1";
"B":   PN = "2"  !CDS_PN = "2";
BODY = "RES","I93": #LOCATION = "R2T62" !CDS_LOCATION = "R2T62" #SEC = "1" !CDS_SEC = "1";
"A":   PN = "1"  !CDS_PN = "1";
"B":   PN = "2"  !CDS_PN = "2";
BODY = "RES","I94": #LOCATION = "R2T58" !CDS_LOCATION = "R2T58" #SEC = "1" !CDS_SEC = "1";
"A":   PN = "1"  !CDS_PN = "1";
"B":   PN = "2"  !CDS_PN = "2";
BODY = "CAP_A","I95": #LOCATION = "C2T32" !CDS_LOCATION = "C2T32" #SEC = "1" !CDS_SEC = "1";
"A":   PN = "1"  !CDS_PN = "1";
"B":   PN = "2"  !CDS_PN = "2";
BODY = "RES","I97": #LOCATION = "R2T36" !CDS_LOCATION = "R2T36" #SEC = "1" !CDS_SEC = "1";
"A":   PN = "1"  !CDS_PN = "1";
"B":   PN = "2"  !CDS_PN = "2";
BODY = "RES","I98": #LOCATION = "R2T39" !CDS_LOCATION = "R2T39" #SEC = "1" !CDS_SEC = "1";
"A":   PN = "1"  !CDS_PN = "1";
"B":   PN = "2"  !CDS_PN = "2";
BODY = "RES","I102": #LOCATION = "R2T68" !CDS_LOCATION = "R2T68" #SEC = "1" !CDS_SEC = "1";
"A":   PN = "1"  !CDS_PN = "1";
"B":   PN = "2"  !CDS_PN = "2";
BODY = "RES","I103": #LOCATION = "R2T60" !CDS_LOCATION = "R2T60" #SEC = "1" !CDS_SEC = "1";
"A":   PN = "1"  !CDS_PN = "1";
"B":   PN = "2"  !CDS_PN = "2";
BODY = "RES","I106": #LOCATION = "R7P28" !CDS_LOCATION = "R7P28" #SEC = "1" !CDS_SEC = "1";
"A":   PN = "1"  !CDS_PN = "1";
"B":   PN = "2"  !CDS_PN = "2";
BODY = "RES","I107": #LOCATION = "R2T59" !CDS_LOCATION = "R2T59" #SEC = "1" !CDS_SEC = "1";
"A":   PN = "1"  !CDS_PN = "1";
"B":   PN = "2"  !CDS_PN = "2";
BODY = "RES","I108": #LOCATION = "R2T69" !CDS_LOCATION = "R2T69" #SEC = "1" !CDS_SEC = "1";
"A":   PN = "1"  !CDS_PN = "1";
"B":   PN = "2"  !CDS_PN = "2";
BODY = "RES","I109": #LOCATION = "R2T71" !CDS_LOCATION = "R2T71" #SEC = "1" !CDS_SEC = "1";
"A":   PN = "1"  !CDS_PN = "1";
"B":   PN = "2"  !CDS_PN = "2";
BODY = "RES","I110": #LOCATION = "R7D43" !CDS_LOCATION = "R7D43" #SEC = "1" !CDS_SEC = "1";
"A":   PN = "1"  !CDS_PN = "1";
"B":   PN = "2"  !CDS_PN = "2";
BODY = "RES","I111": #LOCATION = "R2T65" !CDS_LOCATION = "R2T65" #SEC = "1" !CDS_SEC = "1";
"A":   PN = "1"  !CDS_PN = "1";
"B":   PN = "2"  !CDS_PN = "2";
BODY = "RES","I112": #LOCATION = "R2T66" !CDS_LOCATION = "R2T66" #SEC = "1" !CDS_SEC = "1";
"A":   PN = "1"  !CDS_PN = "1";
"B":   PN = "2"  !CDS_PN = "2";
BODY = "RES","I113": #LOCATION = "R2T67" !CDS_LOCATION = "R2T67" #SEC = "1" !CDS_SEC = "1";
"A":   PN = "1"  !CDS_PN = "1";
"B":   PN = "2"  !CDS_PN = "2";
BODY = "RES","I114": #LOCATION = "R7D41" !CDS_LOCATION = "R7D41" #SEC = "1" !CDS_SEC = "1";
"A":   PN = "1"  !CDS_PN = "1";
"B":   PN = "2"  !CDS_PN = "2";
BODY = "RES","I119": #LOCATION = "R8F38" !CDS_LOCATION = "R8F38" #SEC = "1" !CDS_SEC = "1";
"A":   PN = "1"  !CDS_PN = "1";
"B":   PN = "2"  !CDS_PN = "2";
BODY = "RES","I121": #LOCATION = "R2T64" !CDS_LOCATION = "R2T64" #SEC = "1" !CDS_SEC = "1";
"A":   PN = "1"  !CDS_PN = "1";
"B":   PN = "2"  !CDS_PN = "2";
BODY = "RES","I122": #LOCATION = "R1T36" !CDS_LOCATION = "R1T36" #SEC = "1" !CDS_SEC = "1";
"A":   PN = "1"  !CDS_PN = "1";
"B":   PN = "2"  !CDS_PN = "2";
BODY = "RES","I123": #LOCATION = "R1T37" !CDS_LOCATION = "R1T37" #SEC = "1" !CDS_SEC = "1";
"A":   PN = "1"  !CDS_PN = "1";
"B":   PN = "2"  !CDS_PN = "2";
BODY = "RES","I127": #LOCATION = "R2T50" !CDS_LOCATION = "R2T50" #SEC = "1" !CDS_SEC = "1";
"A":   PN = "1"  !CDS_PN = "1";
"B":   PN = "2"  !CDS_PN = "2";
BODY = "RES","I131": #LOCATION = "R8F37" !CDS_LOCATION = "R8F37" #SEC = "1" !CDS_SEC = "1";
"A":   PN = "1"  !CDS_PN = "1";
"B":   PN = "2"  !CDS_PN = "2";
BODY = "RES","I133": #LOCATION = "R2T63" !CDS_LOCATION = "R2T63" #SEC = "1" !CDS_SEC = "1";
"A":   PN = "1"  !CDS_PN = "1";
"B":   PN = "2"  !CDS_PN = "2";
BODY = "RES","I135": #LOCATION = "R1T35" !CDS_LOCATION = "R1T35" #SEC = "1" !CDS_SEC = "1";
"A":   PN = "1"  !CDS_PN = "1";
"B":   PN = "2"  !CDS_PN = "2";
BODY = "RES","I137": #LOCATION = "R1T38" !CDS_LOCATION = "R1T38" #SEC = "1" !CDS_SEC = "1";
"A":   PN = "1"  !CDS_PN = "1";
"B":   PN = "2"  !CDS_PN = "2";
BODY = "RES","I143": #LOCATION = "R2T72" !CDS_LOCATION = "R2T72" #SEC = "1" !CDS_SEC = "1";
"A":   PN = "1"  !CDS_PN = "1";
"B":   PN = "2"  !CDS_PN = "2";
BODY = "RES","I144": #LOCATION = "R2T73" !CDS_LOCATION = "R2T73" #SEC = "1" !CDS_SEC = "1";
"A":   PN = "1"  !CDS_PN = "1";
"B":   PN = "2"  !CDS_PN = "2";
DRAWING = "@baseboard_fab2_lib.baseboard_fab2(sch_1):page94";
BODY = "FET_N_DUAL","I49": #LOCATION = "Q3U1" !CDS_LOCATION = "Q3U1" #SEC = "1" !CDS_SEC = "1";
"DRAIN<0>":   PN = "6"  !CDS_PN = "6";
"GATE<0>":   PN = "2"  !CDS_PN = "2";
"SOURCE<0>":   PN = "1"  !CDS_PN = "1";
BODY = "RES","I51": #LOCATION = "R7G7" !CDS_LOCATION = "R7G7" &SEC = "1" #&CDS_SEC = "1";
"A":   PN = "1"  !CDS_PN = "1";
"B":   PN = "2"  !CDS_PN = "2";
BODY = "FET_N_DUAL","I60": #LOCATION = "Q7E1" !CDS_LOCATION = "Q7E1" #SEC = "1" !CDS_SEC = "1";
"DRAIN<0>":   PN = "6"  !CDS_PN = "6";
"GATE<0>":   PN = "2"  !CDS_PN = "2";
"SOURCE<0>":   PN = "1"  !CDS_PN = "1";
BODY = "FET_N_DUAL","I64": #LOCATION = "Q7E1" !CDS_LOCATION = "Q7E1" #SEC = "2" !CDS_SEC = "2";
"DRAIN<0>":   PN = "3"  !CDS_PN = "3";
"GATE<0>":   PN = "5"  !CDS_PN = "5";
"SOURCE<0>":   PN = "4"  !CDS_PN = "4";
BODY = "RES","I66": #LOCATION = "R3R4" !CDS_LOCATION = "R3R4" &SEC = "1" #&CDS_SEC = "1";
"A":   PN = "1"  !CDS_PN = "1";
"B":   PN = "2"  !CDS_PN = "2";
BODY = "FET_N_DUAL","I69": #LOCATION = "Q7E2" !CDS_LOCATION = "Q7E2" #SEC = "1" !CDS_SEC = "1";
"DRAIN<0>":   PN = "6"  !CDS_PN = "6";
"GATE<0>":   PN = "2"  !CDS_PN = "2";
"SOURCE<0>":   PN = "1"  !CDS_PN = "1";
BODY = "FET_N_DUAL","I75": #LOCATION = "Q7E2" !CDS_LOCATION = "Q7E2" #SEC = "2" !CDS_SEC = "2";
"DRAIN<0>":   PN = "3"  !CDS_PN = "3";
"GATE<0>":   PN = "5"  !CDS_PN = "5";
"SOURCE<0>":   PN = "4"  !CDS_PN = "4";
BODY = "FET_N_DUAL","I77": #LOCATION = "Q4B1" !CDS_LOCATION = "Q4B1" #SEC = "2" !CDS_SEC = "2";
"DRAIN<0>":   PN = "3"  !CDS_PN = "3";
"GATE<0>":   PN = "5"  !CDS_PN = "5";
"SOURCE<0>":   PN = "4"  !CDS_PN = "4";
BODY = "RES","I79": #LOCATION = "R3R10" !CDS_LOCATION = "R3R10" &SEC = "1" #&CDS_SEC = "1";
"A":   PN = "1"  !CDS_PN = "1";
"B":   PN = "2"  !CDS_PN = "2";
BODY = "RES","I82": #LOCATION = "R6M4" !CDS_LOCATION = "R6M4" &SEC = "1" #&CDS_SEC = "1";
"A":   PN = "1"  !CDS_PN = "1";
"B":   PN = "2"  !CDS_PN = "2";
BODY = "FET_N_DUAL","I84": #LOCATION = "Q4B1" !CDS_LOCATION = "Q4B1" #SEC = "1" !CDS_SEC = "1";
"DRAIN<0>":   PN = "6"  !CDS_PN = "6";
"GATE<0>":   PN = "2"  !CDS_PN = "2";
"SOURCE<0>":   PN = "1"  !CDS_PN = "1";
BODY = "FET_N_DUAL","I89": #LOCATION = "Q3U1" !CDS_LOCATION = "Q3U1" #SEC = "2" !CDS_SEC = "2";
"DRAIN<0>":   PN = "3"  !CDS_PN = "3";
"GATE<0>":   PN = "5"  !CDS_PN = "5";
"SOURCE<0>":   PN = "4"  !CDS_PN = "4";
BODY = "RES","I91": #LOCATION = "R4U1" !CDS_LOCATION = "R4U1" #SEC = "1" !CDS_SEC = "1";
"A":   PN = "1"  !CDS_PN = "1";
"B":   PN = "2"  !CDS_PN = "2";
BODY = "RES","I94": #LOCATION = "R4U3" !CDS_LOCATION = "R4U3" #SEC = "1" !CDS_SEC = "1";
"A":   PN = "1"  !CDS_PN = "1";
"B":   PN = "2"  !CDS_PN = "2";
BODY = "FET_N_DUAL","I98": #LOCATION = "Q4U1" !CDS_LOCATION = "Q4U1" #SEC = "1" !CDS_SEC = "1";
"DRAIN<0>":   PN = "6"  !CDS_PN = "6";
"GATE<0>":   PN = "2"  !CDS_PN = "2";
"SOURCE<0>":   PN = "1"  !CDS_PN = "1";
BODY = "RES","I100": #LOCATION = "R4U2" !CDS_LOCATION = "R4U2" #SEC = "1" !CDS_SEC = "1";
"A":   PN = "1"  !CDS_PN = "1";
"B":   PN = "2"  !CDS_PN = "2";
BODY = "FET_N_DUAL","I102": #LOCATION = "Q4U1" !CDS_LOCATION = "Q4U1" #SEC = "2" !CDS_SEC = "2";
"DRAIN<0>":   PN = "3"  !CDS_PN = "3";
"GATE<0>":   PN = "5"  !CDS_PN = "5";
"SOURCE<0>":   PN = "4"  !CDS_PN = "4";
BODY = "RES","I104": #LOCATION = "R4U4" !CDS_LOCATION = "R4U4" #SEC = "1" !CDS_SEC = "1";
"A":   PN = "1"  !CDS_PN = "1";
"B":   PN = "2"  !CDS_PN = "2";
DRAWING = "@baseboard_fab2_lib.baseboard_fab2(sch_1):page95";
BODY = "FET_N_DUAL","I28": #LOCATION = "Q2U1" !CDS_LOCATION = "Q2U1" #SEC = "1" !CDS_SEC = "1";
"DRAIN<0>":   PN = "6"  !CDS_PN = "6";
"GATE<0>":   PN = "2"  !CDS_PN = "2";
"SOURCE<0>":   PN = "1"  !CDS_PN = "1";
BODY = "FET_N_DUAL","I32": #LOCATION = "Q4B2" !CDS_LOCATION = "Q4B2" #SEC = "1" !CDS_SEC = "1";
"DRAIN<0>":   PN = "6"  !CDS_PN = "6";
"GATE<0>":   PN = "2"  !CDS_PN = "2";
"SOURCE<0>":   PN = "1"  !CDS_PN = "1";
BODY = "FET_N_DUAL","I33": #LOCATION = "Q4B2" !CDS_LOCATION = "Q4B2" #SEC = "2" !CDS_SEC = "2";
"DRAIN<0>":   PN = "3"  !CDS_PN = "3";
"GATE<0>":   PN = "5"  !CDS_PN = "5";
"SOURCE<0>":   PN = "4"  !CDS_PN = "4";
BODY = "FET_N_DUAL","I51": #LOCATION = "Q7E3" !CDS_LOCATION = "Q7E3" #SEC = "2" !CDS_SEC = "2";
"DRAIN<0>":   PN = "3"  !CDS_PN = "3";
"GATE<0>":   PN = "5"  !CDS_PN = "5";
"SOURCE<0>":   PN = "4"  !CDS_PN = "4";
BODY = "FET_N_DUAL","I52": #LOCATION = "Q7E3" !CDS_LOCATION = "Q7E3" #SEC = "1" !CDS_SEC = "1";
"DRAIN<0>":   PN = "6"  !CDS_PN = "6";
"GATE<0>":   PN = "2"  !CDS_PN = "2";
"SOURCE<0>":   PN = "1"  !CDS_PN = "1";
BODY = "FET_N_DUAL","I59": #LOCATION = "Q7E5" !CDS_LOCATION = "Q7E5" #SEC = "2" !CDS_SEC = "2";
"DRAIN<0>":   PN = "3"  !CDS_PN = "3";
"GATE<0>":   PN = "5"  !CDS_PN = "5";
"SOURCE<0>":   PN = "4"  !CDS_PN = "4";
BODY = "RES","I62": #LOCATION = "R7E10" !CDS_LOCATION = "R7E10" &SEC = "1" #&CDS_SEC = "1";
"A":   PN = "1"  !CDS_PN = "1";
"B":   PN = "2"  !CDS_PN = "2";
BODY = "FET_N_DUAL","I69": #LOCATION = "Q7E6" !CDS_LOCATION = "Q7E6" #SEC = "2" !CDS_SEC = "2";
"DRAIN<0>":   PN = "3"  !CDS_PN = "3";
"GATE<0>":   PN = "5"  !CDS_PN = "5";
"SOURCE<0>":   PN = "4"  !CDS_PN = "4";
BODY = "RES","I72": #LOCATION = "R7E11" !CDS_LOCATION = "R7E11" &SEC = "1" #&CDS_SEC = "1";
"A":   PN = "1"  !CDS_PN = "1";
"B":   PN = "2"  !CDS_PN = "2";
BODY = "CAP_A","I92": #LOCATION = "C7E3" !CDS_LOCATION = "C7E3" #SEC = "1" !CDS_SEC = "1";
"A":   PN = "1"  !CDS_PN = "1";
"B":   PN = "2"  !CDS_PN = "2";
BODY = "FET_N","I104": #LOCATION = "Q7E4" !CDS_LOCATION = "Q7E4" #SEC = "1" !CDS_SEC = "1";
"DRN":   PN = "3"  !CDS_PN = "3";
"GATE":   PN = "1"  !CDS_PN = "1";
"SRC":   PN = "2"  !CDS_PN = "2";
BODY = "RES","I106": #LOCATION = "R7E7" !CDS_LOCATION = "R7E7" #SEC = "1" !CDS_SEC = "1";
"A":   PN = "1"  !CDS_PN = "1";
"B":   PN = "2"  !CDS_PN = "2";
BODY = "RES","I108": #LOCATION = "R7E9" !CDS_LOCATION = "R7E9" #SEC = "1" !CDS_SEC = "1";
"A":   PN = "1"  !CDS_PN = "1";
"B":   PN = "2"  !CDS_PN = "2";
BODY = "FET_N_DUAL","I111": #LOCATION = "Q7E5" !CDS_LOCATION = "Q7E5" #SEC = "1" !CDS_SEC = "1";
"DRAIN<0>":   PN = "6"  !CDS_PN = "6";
"GATE<0>":   PN = "2"  !CDS_PN = "2";
"SOURCE<0>":   PN = "1"  !CDS_PN = "1";
BODY = "FET_N_DUAL","I112": #LOCATION = "Q7E6" !CDS_LOCATION = "Q7E6" #SEC = "1" !CDS_SEC = "1";
"DRAIN<0>":   PN = "6"  !CDS_PN = "6";
"GATE<0>":   PN = "2"  !CDS_PN = "2";
"SOURCE<0>":   PN = "1"  !CDS_PN = "1";
BODY = "FET_N_DUAL","I113": #LOCATION = "Q2U1" !CDS_LOCATION = "Q2U1" #SEC = "2" !CDS_SEC = "2";
"DRAIN<0>":   PN = "3"  !CDS_PN = "3";
"GATE<0>":   PN = "5"  !CDS_PN = "5";
"SOURCE<0>":   PN = "4"  !CDS_PN = "4";
BODY = "CAP_A","I115": #LOCATION = "C7E4" !CDS_LOCATION = "C7E4" #SEC = "1" !CDS_SEC = "1";
"A":   PN = "1"  !CDS_PN = "1";
"B":   PN = "2"  !CDS_PN = "2";
BODY = "TTL1G08","I117": #LOCATION = "U7E2" !CDS_LOCATION = "U7E2" #SEC = "1" !CDS_SEC = "1";
"A<0>":   PN = "1"  !CDS_PN = "1";
"B<0>":   PN = "2"  !CDS_PN = "2";
"Y<0>":   PN = "4"  !CDS_PN = "4";
BODY = "TTL1G08","I118": #LOCATION = "U7E3" !CDS_LOCATION = "U7E3" #SEC = "1" !CDS_SEC = "1";
"A<0>":   PN = "1"  !CDS_PN = "1";
"B<0>":   PN = "2"  !CDS_PN = "2";
"Y<0>":   PN = "4"  !CDS_PN = "4";
BODY = "FET_N","I119": #LOCATION = "Q7E8" !CDS_LOCATION = "Q7E8" #SEC = "1" !CDS_SEC = "1";
"DRN":   PN = "3"  !CDS_PN = "3";
"GATE":   PN = "1"  !CDS_PN = "1";
"SRC":   PN = "2"  !CDS_PN = "2";
DRAWING = "@baseboard_fab2_lib.baseboard_fab2(sch_1):page96";
BODY = "RES","I2": #LOCATION = "R6D12" !CDS_LOCATION = "R6D12" #SEC = "1" !CDS_SEC = "1";
"A":   PN = "1"  !CDS_PN = "1";
"B":   PN = "2"  !CDS_PN = "2";
BODY = "RES","I3": #LOCATION = "R6D8" !CDS_LOCATION = "R6D8" #SEC = "1" !CDS_SEC = "1";
"A":   PN = "1"  !CDS_PN = "1";
"B":   PN = "2"  !CDS_PN = "2";
BODY = "RES","I5": #LOCATION = "R3P29" !CDS_LOCATION = "R3P29" &SEC = "1" #&CDS_SEC = "1";
"A":   PN = "1"  !CDS_PN = "1";
"B":   PN = "2"  !CDS_PN = "2";
BODY = "RES","I7": #LOCATION = "R3P38" !CDS_LOCATION = "R3P38" &SEC = "1" #&CDS_SEC = "1";
"A":   PN = "1"  !CDS_PN = "1";
"B":   PN = "2"  !CDS_PN = "2";
BODY = "RES","I25": #LOCATION = "R3D20" !CDS_LOCATION = "R3D20" #SEC = "1" !CDS_SEC = "1";
"A":   PN = "1"  !CDS_PN = "1";
"B":   PN = "2"  !CDS_PN = "2";
BODY = "RES","I26": #LOCATION = "R3D15" !CDS_LOCATION = "R3D15" #SEC = "1" !CDS_SEC = "1";
"A":   PN = "1"  !CDS_PN = "1";
"B":   PN = "2"  !CDS_PN = "2";
BODY = "RES","I28": #LOCATION = "R7M9" !CDS_LOCATION = "R7M9" &SEC = "1" #&CDS_SEC = "1";
"A":   PN = "1"  !CDS_PN = "1";
"B":   PN = "2"  !CDS_PN = "2";
BODY = "RES","I30": #LOCATION = "R3D21" !CDS_LOCATION = "R3D21" &SEC = "1" #&CDS_SEC = "1";
"A":   PN = "1"  !CDS_PN = "1";
"B":   PN = "2"  !CDS_PN = "2";
BODY = "RES","I36": #LOCATION = "R3P36" !CDS_LOCATION = "R3P36" &SEC = "1" #&CDS_SEC = "1";
"A":   PN = "1"  !CDS_PN = "1";
"B":   PN = "2"  !CDS_PN = "2";
BODY = "GTL2014","I42": #LOCATION = "U3P1" !CDS_LOCATION = "U3P1" &SEC = "1" #&CDS_SEC = "1";
"A0":   PN = "13"  !CDS_PN = "13";
"A1":   PN = "12"  !CDS_PN = "12";
"A2":   PN = "10"  !CDS_PN = "10";
"A3":   PN = "9"  !CDS_PN = "9";
"B0":   PN = "2"  !CDS_PN = "2";
"B1":   PN = "3"  !CDS_PN = "3";
"B2":   PN = "5"  !CDS_PN = "5";
"B3":   PN = "6"  !CDS_PN = "6";
"DIR":   PN = "1"  !CDS_PN = "1";
"GND<0>":   PN = "7"  !CDS_PN = "7";
"GND<1>":   PN = "8"  !CDS_PN = "8";
"GND<2>":   PN = "11"  !CDS_PN = "11";
"VCC":   PN = "14"  !CDS_PN = "14";
"VREF":   PN = "4"  !CDS_PN = "4";
BODY = "GTL2014","I46": #LOCATION = "U4C2" !CDS_LOCATION = "U4C2" &SEC = "1" #&CDS_SEC = "1";
"A0":   PN = "13"  !CDS_PN = "13";
"A1":   PN = "12"  !CDS_PN = "12";
"A2":   PN = "10"  !CDS_PN = "10";
"A3":   PN = "9"  !CDS_PN = "9";
"B0":   PN = "2"  !CDS_PN = "2";
"B1":   PN = "3"  !CDS_PN = "3";
"B2":   PN = "5"  !CDS_PN = "5";
"B3":   PN = "6"  !CDS_PN = "6";
"DIR":   PN = "1"  !CDS_PN = "1";
"GND<0>":   PN = "7"  !CDS_PN = "7";
"GND<1>":   PN = "8"  !CDS_PN = "8";
"GND<2>":   PN = "11"  !CDS_PN = "11";
"VCC":   PN = "14"  !CDS_PN = "14";
"VREF":   PN = "4"  !CDS_PN = "4";
BODY = "RES","I55": #LOCATION = "R4C8" !CDS_LOCATION = "R4C8" &SEC = "1" #&CDS_SEC = "1";
"A":   PN = "1"  !CDS_PN = "1";
"B":   PN = "2"  !CDS_PN = "2";
BODY = "RES","I69": #LOCATION = "R4C9" !CDS_LOCATION = "R4C9" #SEC = "1" !CDS_SEC = "1";
"A":   PN = "1"  !CDS_PN = "1";
"B":   PN = "2"  !CDS_PN = "2";
BODY = "RES","I71": #LOCATION = "R3P32" !CDS_LOCATION = "R3P32" #SEC = "1" !CDS_SEC = "1";
"A":   PN = "1"  !CDS_PN = "1";
"B":   PN = "2"  !CDS_PN = "2";
BODY = "CAP_A","I73": #LOCATION = "C3P42" !CDS_LOCATION = "C3P42" #SEC = "1" !CDS_SEC = "1";
"A":   PN = "1"  !CDS_PN = "1";
"B":   PN = "2"  !CDS_PN = "2";
BODY = "CAP_A","I75": #LOCATION = "C4C3" !CDS_LOCATION = "C4C3" #SEC = "1" !CDS_SEC = "1";
"A":   PN = "1"  !CDS_PN = "1";
"B":   PN = "2"  !CDS_PN = "2";
DRAWING = "@baseboard_fab2_lib.baseboard_fab2(sch_1):page97";
BODY = "RES","I33": #LOCATION = "R3D18" !CDS_LOCATION = "R3D18" &SEC = "1" #&CDS_SEC = "1";
"A":   PN = "1"  !CDS_PN = "1";
"B":   PN = "2"  !CDS_PN = "2";
BODY = "RES","I42": #LOCATION = "R4R4" !CDS_LOCATION = "R4R4" &SEC = "1" #&CDS_SEC = "1";
"A":   PN = "1"  !CDS_PN = "1";
"B":   PN = "2"  !CDS_PN = "2";
BODY = "RES","I44": #LOCATION = "R7P20" !CDS_LOCATION = "R7P20" &SEC = "1" #&CDS_SEC = "1";
"A":   PN = "1"  !CDS_PN = "1";
"B":   PN = "2"  !CDS_PN = "2";
BODY = "RES","I72": #LOCATION = "R4P21" !CDS_LOCATION = "R4P21" #SEC = "1" !CDS_SEC = "1";
"A":   PN = "1"  !CDS_PN = "1";
"B":   PN = "2"  !CDS_PN = "2";
BODY = "RES","I76": #LOCATION = "R4C10" !CDS_LOCATION = "R4C10" #SEC = "1" !CDS_SEC = "1";
"A":   PN = "1"  !CDS_PN = "1";
"B":   PN = "2"  !CDS_PN = "2";
BODY = "RES","I80": #LOCATION = "R4P5" !CDS_LOCATION = "R4P5" #SEC = "1" !CDS_SEC = "1";
"A":   PN = "1"  !CDS_PN = "1";
"B":   PN = "2"  !CDS_PN = "2";
BODY = "RES","I81": #LOCATION = "R7P13" !CDS_LOCATION = "R7P13" #SEC = "1" !CDS_SEC = "1";
"A":   PN = "1"  !CDS_PN = "1";
"B":   PN = "2"  !CDS_PN = "2";
DRAWING = "@baseboard_fab2_lib.baseboard_fab2(sch_1):page98";
BODY = "RES","I4": #LOCATION = "R4F5" !CDS_LOCATION = "R4F5" #SEC = "1" !CDS_SEC = "1";
"A":   PN = "1"  !CDS_PN = "1";
"B":   PN = "2"  !CDS_PN = "2";
BODY = "RES","I5": #LOCATION = "R4F3" !CDS_LOCATION = "R4F3" #SEC = "1" !CDS_SEC = "1";
"A":   PN = "1"  !CDS_PN = "1";
"B":   PN = "2"  !CDS_PN = "2";
BODY = "CAP_A","I7": #LOCATION = "C4F9" !CDS_LOCATION = "C4F9" #SEC = "1" !CDS_SEC = "1";
"A":   PN = "1"  !CDS_PN = "1";
"B":   PN = "2"  !CDS_PN = "2";
BODY = "RES","I9": #LOCATION = "R6M1" !CDS_LOCATION = "R6M1" #SEC = "1" !CDS_SEC = "1";
"A":   PN = "1"  !CDS_PN = "1";
"B":   PN = "2"  !CDS_PN = "2";
BODY = "RES","I12": #LOCATION = "R6L16" !CDS_LOCATION = "R6L16" #SEC = "1" !CDS_SEC = "1";
"A":   PN = "1"  !CDS_PN = "1";
"B":   PN = "2"  !CDS_PN = "2";
BODY = "RES","I14": #LOCATION = "R6M2" !CDS_LOCATION = "R6M2" #SEC = "1" !CDS_SEC = "1";
"A":   PN = "1"  !CDS_PN = "1";
"B":   PN = "2"  !CDS_PN = "2";
BODY = "CAP_A","I33": #LOCATION = "C6M2" !CDS_LOCATION = "C6M2" #SEC = "1" !CDS_SEC = "1";
"A":   PN = "1"  !CDS_PN = "1";
"B":   PN = "2"  !CDS_PN = "2";
BODY = "RES","I36": #LOCATION = "R4F4" !CDS_LOCATION = "R4F4" #SEC = "1" !CDS_SEC = "1";
"A":   PN = "1"  !CDS_PN = "1";
"B":   PN = "2"  !CDS_PN = "2";
BODY = "RES","I38": #LOCATION = "R4G2" !CDS_LOCATION = "R4G2" #SEC = "1" !CDS_SEC = "1";
"A":   PN = "1"  !CDS_PN = "1";
"B":   PN = "2"  !CDS_PN = "2";
BODY = "RES","I40": #LOCATION = "R4G3" !CDS_LOCATION = "R4G3" #SEC = "1" !CDS_SEC = "1";
"A":   PN = "1"  !CDS_PN = "1";
"B":   PN = "2"  !CDS_PN = "2";
BODY = "RES","I42": #LOCATION = "R4G1" !CDS_LOCATION = "R4G1" #SEC = "1" !CDS_SEC = "1";
"A":   PN = "1"  !CDS_PN = "1";
"B":   PN = "2"  !CDS_PN = "2";
BODY = "CAP_A","I43": #LOCATION = "C4G1" !CDS_LOCATION = "C4G1" #SEC = "1" !CDS_SEC = "1";
"A":   PN = "1"  !CDS_PN = "1";
"B":   PN = "2"  !CDS_PN = "2";
BODY = "RES","I46": #LOCATION = "R4G21" !CDS_LOCATION = "R4G21" #SEC = "1" !CDS_SEC = "1";
"A":   PN = "1"  !CDS_PN = "1";
"B":   PN = "2"  !CDS_PN = "2";
BODY = "RES","I48": #LOCATION = "R4G22" !CDS_LOCATION = "R4G22" #SEC = "1" !CDS_SEC = "1";
"A":   PN = "1"  !CDS_PN = "1";
"B":   PN = "2"  !CDS_PN = "2";
BODY = "RES","I50": #LOCATION = "R4G20" !CDS_LOCATION = "R4G20" #SEC = "1" !CDS_SEC = "1";
"A":   PN = "1"  !CDS_PN = "1";
"B":   PN = "2"  !CDS_PN = "2";
BODY = "CAP_A","I51": #LOCATION = "C4G17" !CDS_LOCATION = "C4G17" #SEC = "1" !CDS_SEC = "1";
"A":   PN = "1"  !CDS_PN = "1";
"B":   PN = "2"  !CDS_PN = "2";
BODY = "RES","I54": #LOCATION = "R6L13" !CDS_LOCATION = "R6L13" #SEC = "1" !CDS_SEC = "1";
"A":   PN = "1"  !CDS_PN = "1";
"B":   PN = "2"  !CDS_PN = "2";
BODY = "RES","I56": #LOCATION = "R6L12" !CDS_LOCATION = "R6L12" #SEC = "1" !CDS_SEC = "1";
"A":   PN = "1"  !CDS_PN = "1";
"B":   PN = "2"  !CDS_PN = "2";
BODY = "RES","I58": #LOCATION = "R6L14" !CDS_LOCATION = "R6L14" #SEC = "1" !CDS_SEC = "1";
"A":   PN = "1"  !CDS_PN = "1";
"B":   PN = "2"  !CDS_PN = "2";
BODY = "CAP_A","I59": #LOCATION = "C6L7" !CDS_LOCATION = "C6L7" #SEC = "1" !CDS_SEC = "1";
"A":   PN = "1"  !CDS_PN = "1";
"B":   PN = "2"  !CDS_PN = "2";
BODY = "RES","I62": #LOCATION = "R6L2" !CDS_LOCATION = "R6L2" #SEC = "1" !CDS_SEC = "1";
"A":   PN = "1"  !CDS_PN = "1";
"B":   PN = "2"  !CDS_PN = "2";
BODY = "RES","I64": #LOCATION = "R6L1" !CDS_LOCATION = "R6L1" #SEC = "1" !CDS_SEC = "1";
"A":   PN = "1"  !CDS_PN = "1";
"B":   PN = "2"  !CDS_PN = "2";
BODY = "RES","I66": #LOCATION = "R6L3" !CDS_LOCATION = "R6L3" #SEC = "1" !CDS_SEC = "1";
"A":   PN = "1"  !CDS_PN = "1";
"B":   PN = "2"  !CDS_PN = "2";
BODY = "CAP_A","I67": #LOCATION = "C6L2" !CDS_LOCATION = "C6L2" #SEC = "1" !CDS_SEC = "1";
"A":   PN = "1"  !CDS_PN = "1";
"B":   PN = "2"  !CDS_PN = "2";
DRAWING = "@baseboard_fab2_lib.baseboard_fab2(sch_1):page99";
BODY = "CAP_A","I2": #LOCATION = "C6F2" !CDS_LOCATION = "C6F2" &SEC = "1" #&CDS_SEC = "1";
"A":   PN = "1"  !CDS_PN = "1";
"B":   PN = "2"  !CDS_PN = "2";
BODY = "CAP_A","I7": #LOCATION = "C6F3" !CDS_LOCATION = "C6F3" &SEC = "1" #&CDS_SEC = "1";
"A":   PN = "1"  !CDS_PN = "1";
"B":   PN = "2"  !CDS_PN = "2";
BODY = "RES","I9": #LOCATION = "R4T9" !CDS_LOCATION = "R4T9" &SEC = "1" #&CDS_SEC = "1";
"A":   PN = "1"  !CDS_PN = "1";
"B":   PN = "2"  !CDS_PN = "2";
BODY = "RES","I10": #LOCATION = "R4T10" !CDS_LOCATION = "R4T10" &SEC = "1" #&CDS_SEC = "1";
"A":   PN = "1"  !CDS_PN = "1";
"B":   PN = "2"  !CDS_PN = "2";
BODY = "RES","I11": #LOCATION = "R4T8" !CDS_LOCATION = "R4T8" #SEC = "1" !CDS_SEC = "1";
"A":   PN = "1"  !CDS_PN = "1";
"B":   PN = "2"  !CDS_PN = "2";
BODY = "RES","I13": #LOCATION = "R4T7" !CDS_LOCATION = "R4T7" #SEC = "1" !CDS_SEC = "1";
"A":   PN = "1"  !CDS_PN = "1";
"B":   PN = "2"  !CDS_PN = "2";
BODY = "PCA9617","I15": #LOCATION = "U6F1" !CDS_LOCATION = "U6F1" &SEC = "1" #&CDS_SEC = "1";
"EN":   PN = "5"  !CDS_PN = "5";
"SCLA":   PN = "2"  !CDS_PN = "2";
"SCLB":   PN = "7"  !CDS_PN = "7";
"SDAA":   PN = "3"  !CDS_PN = "3";
"SDAB":   PN = "6"  !CDS_PN = "6";
"VCCA":   PN = "1"  !CDS_PN = "1";
"VCCB":   PN = "8"  !CDS_PN = "8";
BODY = "RES","I17": #LOCATION = "R4T6" !CDS_LOCATION = "R4T6" &SEC = "1" #&CDS_SEC = "1";
"A":   PN = "1"  !CDS_PN = "1";
"B":   PN = "2"  !CDS_PN = "2";
BODY = "RES","I19": #LOCATION = "R4T5" !CDS_LOCATION = "R4T5" &SEC = "1" #&CDS_SEC = "1";
"A":   PN = "1"  !CDS_PN = "1";
"B":   PN = "2"  !CDS_PN = "2";
BODY = "RES","I20": #LOCATION = "R4T4" !CDS_LOCATION = "R4T4" &SEC = "1" #&CDS_SEC = "1";
"A":   PN = "1"  !CDS_PN = "1";
"B":   PN = "2"  !CDS_PN = "2";
BODY = "CAP_A","I23": #LOCATION = "C7E1" !CDS_LOCATION = "C7E1" &SEC = "1" #&CDS_SEC = "1";
"A":   PN = "1"  !CDS_PN = "1";
"B":   PN = "2"  !CDS_PN = "2";
BODY = "CAP_A","I27": #LOCATION = "C4G22" !CDS_LOCATION = "C4G22" &SEC = "1" #&CDS_SEC = "1";
"A":   PN = "1"  !CDS_PN = "1";
"B":   PN = "2"  !CDS_PN = "2";
BODY = "CAP_A","I32": #LOCATION = "C7E2" !CDS_LOCATION = "C7E2" &SEC = "1" #&CDS_SEC = "1";
"A":   PN = "1"  !CDS_PN = "1";
"B":   PN = "2"  !CDS_PN = "2";
BODY = "RES","I34": #LOCATION = "R3R9" !CDS_LOCATION = "R3R9" &SEC = "1" #&CDS_SEC = "1";
"A":   PN = "1"  !CDS_PN = "1";
"B":   PN = "2"  !CDS_PN = "2";
BODY = "RES","I35": #LOCATION = "R3R8" !CDS_LOCATION = "R3R8" &SEC = "1" #&CDS_SEC = "1";
"A":   PN = "1"  !CDS_PN = "1";
"B":   PN = "2"  !CDS_PN = "2";
BODY = "CAP_A","I41": #LOCATION = "C4G25" !CDS_LOCATION = "C4G25" &SEC = "1" #&CDS_SEC = "1";
"A":   PN = "1"  !CDS_PN = "1";
"B":   PN = "2"  !CDS_PN = "2";
BODY = "RES","I42": #LOCATION = "R6U13" !CDS_LOCATION = "R6U13" &SEC = "1" #&CDS_SEC = "1";
"A":   PN = "1"  !CDS_PN = "1";
"B":   PN = "2"  !CDS_PN = "2";
BODY = "RES","I43": #LOCATION = "R6U14" !CDS_LOCATION = "R6U14" &SEC = "1" #&CDS_SEC = "1";
"A":   PN = "1"  !CDS_PN = "1";
"B":   PN = "2"  !CDS_PN = "2";
BODY = "CAP_A","I47": #LOCATION = "C3B4" !CDS_LOCATION = "C3B4" &SEC = "1" #&CDS_SEC = "1";
"A":   PN = "1"  !CDS_PN = "1";
"B":   PN = "2"  !CDS_PN = "2";
BODY = "CAP_A","I53": #LOCATION = "C3B5" !CDS_LOCATION = "C3B5" &SEC = "1" #&CDS_SEC = "1";
"A":   PN = "1"  !CDS_PN = "1";
"B":   PN = "2"  !CDS_PN = "2";
BODY = "RES","I55": #LOCATION = "R7M5" !CDS_LOCATION = "R7M5" &SEC = "1" #&CDS_SEC = "1";
"A":   PN = "1"  !CDS_PN = "1";
"B":   PN = "2"  !CDS_PN = "2";
BODY = "RES","I56": #LOCATION = "R7M4" !CDS_LOCATION = "R7M4" &SEC = "1" #&CDS_SEC = "1";
"A":   PN = "1"  !CDS_PN = "1";
"B":   PN = "2"  !CDS_PN = "2";
BODY = "PCA9617","I61": #LOCATION = "U7E1" !CDS_LOCATION = "U7E1" &SEC = "1" #&CDS_SEC = "1";
"EN":   PN = "5"  !CDS_PN = "5";
"SCLA":   PN = "2"  !CDS_PN = "2";
"SCLB":   PN = "7"  !CDS_PN = "7";
"SDAA":   PN = "3"  !CDS_PN = "3";
"SDAB":   PN = "6"  !CDS_PN = "6";
"VCCA":   PN = "1"  !CDS_PN = "1";
"VCCB":   PN = "8"  !CDS_PN = "8";
BODY = "PCA9617","I63": #LOCATION = "U4G1" !CDS_LOCATION = "U4G1" &SEC = "1" #&CDS_SEC = "1";
"EN":   PN = "5"  !CDS_PN = "5";
"SCLA":   PN = "2"  !CDS_PN = "2";
"SCLB":   PN = "7"  !CDS_PN = "7";
"SDAA":   PN = "3"  !CDS_PN = "3";
"SDAB":   PN = "6"  !CDS_PN = "6";
"VCCA":   PN = "1"  !CDS_PN = "1";
"VCCB":   PN = "8"  !CDS_PN = "8";
BODY = "RES","I65": #LOCATION = "R3R13" !CDS_LOCATION = "R3R13" &SEC = "1" #&CDS_SEC = "1";
"A":   PN = "1"  !CDS_PN = "1";
"B":   PN = "2"  !CDS_PN = "2";
BODY = "RES","I67": #LOCATION = "R3P60" !CDS_LOCATION = "R3P60" &SEC = "1" #&CDS_SEC = "1";
"A":   PN = "1"  !CDS_PN = "1";
"B":   PN = "2"  !CDS_PN = "2";
BODY = "RES","I70": #LOCATION = "R6T1" !CDS_LOCATION = "R6T1" &SEC = "1" #&CDS_SEC = "1";
"A":   PN = "1"  !CDS_PN = "1";
"B":   PN = "2"  !CDS_PN = "2";
BODY = "RES","I72": #LOCATION = "R6T2" !CDS_LOCATION = "R6T2" &SEC = "1" #&CDS_SEC = "1";
"A":   PN = "1"  !CDS_PN = "1";
"B":   PN = "2"  !CDS_PN = "2";
BODY = "PCA9617","I75": #LOCATION = "U3B1" !CDS_LOCATION = "U3B1" &SEC = "1" #&CDS_SEC = "1";
"EN":   PN = "5"  !CDS_PN = "5";
"SCLA":   PN = "2"  !CDS_PN = "2";
"SCLB":   PN = "7"  !CDS_PN = "7";
"SDAA":   PN = "3"  !CDS_PN = "3";
"SDAB":   PN = "6"  !CDS_PN = "6";
"VCCA":   PN = "1"  !CDS_PN = "1";
"VCCB":   PN = "8"  !CDS_PN = "8";
BODY = "RES","I77": #LOCATION = "R7M7" !CDS_LOCATION = "R7M7" &SEC = "1" #&CDS_SEC = "1";
"A":   PN = "1"  !CDS_PN = "1";
"B":   PN = "2"  !CDS_PN = "2";
BODY = "RES","I79": #LOCATION = "R7M2" !CDS_LOCATION = "R7M2" &SEC = "1" #&CDS_SEC = "1";
"A":   PN = "1"  !CDS_PN = "1";
"B":   PN = "2"  !CDS_PN = "2";
BODY = "RES","I83": #LOCATION = "R4T3" !CDS_LOCATION = "R4T3" &SEC = "1" #&CDS_SEC = "1";
"A":   PN = "1"  !CDS_PN = "1";
"B":   PN = "2"  !CDS_PN = "2";
BODY = "RES","I88": #LOCATION = "R3R7" !CDS_LOCATION = "R3R7" &SEC = "1" #&CDS_SEC = "1";
"A":   PN = "1"  !CDS_PN = "1";
"B":   PN = "2"  !CDS_PN = "2";
BODY = "RES","I92": #LOCATION = "R6T3" !CDS_LOCATION = "R6T3" &SEC = "1" #&CDS_SEC = "1";
"A":   PN = "1"  !CDS_PN = "1";
"B":   PN = "2"  !CDS_PN = "2";
BODY = "RES","I98": #LOCATION = "R7M3" !CDS_LOCATION = "R7M3" &SEC = "1" #&CDS_SEC = "1";
"A":   PN = "1"  !CDS_PN = "1";
"B":   PN = "2"  !CDS_PN = "2";
BODY = "RES","I101": #LOCATION = "R3R12" !CDS_LOCATION = "R3R12" #SEC = "1" !CDS_SEC = "1";
"A":   PN = "1"  !CDS_PN = "1";
"B":   PN = "2"  !CDS_PN = "2";
BODY = "RES","I103": #LOCATION = "R3R5" !CDS_LOCATION = "R3R5" #SEC = "1" !CDS_SEC = "1";
"A":   PN = "1"  !CDS_PN = "1";
"B":   PN = "2"  !CDS_PN = "2";
BODY = "RES","I104": #LOCATION = "R6U18" !CDS_LOCATION = "R6U18" #SEC = "1" !CDS_SEC = "1";
"A":   PN = "1"  !CDS_PN = "1";
"B":   PN = "2"  !CDS_PN = "2";
BODY = "RES","I106": #LOCATION = "R6U17" !CDS_LOCATION = "R6U17" #SEC = "1" !CDS_SEC = "1";
"A":   PN = "1"  !CDS_PN = "1";
"B":   PN = "2"  !CDS_PN = "2";
BODY = "RES","I107": #LOCATION = "R7M6" !CDS_LOCATION = "R7M6" #SEC = "1" !CDS_SEC = "1";
"A":   PN = "1"  !CDS_PN = "1";
"B":   PN = "2"  !CDS_PN = "2";
BODY = "RES","I109": #LOCATION = "R7M1" !CDS_LOCATION = "R7M1" #SEC = "1" !CDS_SEC = "1";
"A":   PN = "1"  !CDS_PN = "1";
"B":   PN = "2"  !CDS_PN = "2";
BODY = "RES","I110": #LOCATION = "R3R14" !CDS_LOCATION = "R3R14" &SEC = "1" #&CDS_SEC = "1";
"A":   PN = "1"  !CDS_PN = "1";
"B":   PN = "2"  !CDS_PN = "2";
BODY = "RES","I111": #LOCATION = "R6T4" !CDS_LOCATION = "R6T4" &SEC = "1" #&CDS_SEC = "1";
"A":   PN = "1"  !CDS_PN = "1";
"B":   PN = "2"  !CDS_PN = "2";
BODY = "RES","I112": #LOCATION = "R7M8" !CDS_LOCATION = "R7M8" &SEC = "1" #&CDS_SEC = "1";
"A":   PN = "1"  !CDS_PN = "1";
"B":   PN = "2"  !CDS_PN = "2";
DRAWING = "@baseboard_fab2_lib.baseboard_fab2(sch_1):page100";
BODY = "RES","I2": #LOCATION = "R1F6" !CDS_LOCATION = "R1F6" #SEC = "1" !CDS_SEC = "1";
"A":   PN = "1"  !CDS_PN = "1";
"B":   PN = "2"  !CDS_PN = "2";
BODY = "RES","I4": #LOCATION = "R9L11" !CDS_LOCATION = "R9L11" #SEC = "1" !CDS_SEC = "1";
"A":   PN = "1"  !CDS_PN = "1";
"B":   PN = "2"  !CDS_PN = "2";
BODY = "RES","I6": #LOCATION = "R1F5" !CDS_LOCATION = "R1F5" #SEC = "1" !CDS_SEC = "1";
"A":   PN = "1"  !CDS_PN = "1";
"B":   PN = "2"  !CDS_PN = "2";
BODY = "RES","I7": #LOCATION = "R1F4" !CDS_LOCATION = "R1F4" #SEC = "1" !CDS_SEC = "1";
"A":   PN = "1"  !CDS_PN = "1";
"B":   PN = "2"  !CDS_PN = "2";
BODY = "CAP_A","I8": #LOCATION = "C1F19" !CDS_LOCATION = "C1F19" #SEC = "1" !CDS_SEC = "1";
"A":   PN = "1"  !CDS_PN = "1";
"B":   PN = "2"  !CDS_PN = "2";
BODY = "RES","I11": #LOCATION = "R9M1" !CDS_LOCATION = "R9M1" #SEC = "1" !CDS_SEC = "1";
"A":   PN = "1"  !CDS_PN = "1";
"B":   PN = "2"  !CDS_PN = "2";
BODY = "RES","I13": #LOCATION = "R9M2" !CDS_LOCATION = "R9M2" #SEC = "1" !CDS_SEC = "1";
"A":   PN = "1"  !CDS_PN = "1";
"B":   PN = "2"  !CDS_PN = "2";
BODY = "CAP_A","I15": #LOCATION = "C9M2" !CDS_LOCATION = "C9M2" #SEC = "1" !CDS_SEC = "1";
"A":   PN = "1"  !CDS_PN = "1";
"B":   PN = "2"  !CDS_PN = "2";
BODY = "RES","I19": #LOCATION = "R1G2" !CDS_LOCATION = "R1G2" #SEC = "1" !CDS_SEC = "1";
"A":   PN = "1"  !CDS_PN = "1";
"B":   PN = "2"  !CDS_PN = "2";
BODY = "RES","I20": #LOCATION = "R1G3" !CDS_LOCATION = "R1G3" #SEC = "1" !CDS_SEC = "1";
"A":   PN = "1"  !CDS_PN = "1";
"B":   PN = "2"  !CDS_PN = "2";
BODY = "RES","I22": #LOCATION = "R9L7" !CDS_LOCATION = "R9L7" #SEC = "1" !CDS_SEC = "1";
"A":   PN = "1"  !CDS_PN = "1";
"B":   PN = "2"  !CDS_PN = "2";
BODY = "RES","I24": #LOCATION = "R9L6" !CDS_LOCATION = "R9L6" #SEC = "1" !CDS_SEC = "1";
"A":   PN = "1"  !CDS_PN = "1";
"B":   PN = "2"  !CDS_PN = "2";
BODY = "RES","I25": #LOCATION = "R1G1" !CDS_LOCATION = "R1G1" #SEC = "1" !CDS_SEC = "1";
"A":   PN = "1"  !CDS_PN = "1";
"B":   PN = "2"  !CDS_PN = "2";
BODY = "CAP_A","I26": #LOCATION = "C1G8" !CDS_LOCATION = "C1G8" #SEC = "1" !CDS_SEC = "1";
"A":   PN = "1"  !CDS_PN = "1";
"B":   PN = "2"  !CDS_PN = "2";
BODY = "RES","I29": #LOCATION = "R9L8" !CDS_LOCATION = "R9L8" #SEC = "1" !CDS_SEC = "1";
"A":   PN = "1"  !CDS_PN = "1";
"B":   PN = "2"  !CDS_PN = "2";
BODY = "CAP_A","I30": #LOCATION = "C9L8" !CDS_LOCATION = "C9L8" #SEC = "1" !CDS_SEC = "1";
"A":   PN = "1"  !CDS_PN = "1";
"B":   PN = "2"  !CDS_PN = "2";
BODY = "RES","I35": #LOCATION = "R1G15" !CDS_LOCATION = "R1G15" #SEC = "1" !CDS_SEC = "1";
"A":   PN = "1"  !CDS_PN = "1";
"B":   PN = "2"  !CDS_PN = "2";
BODY = "RES","I36": #LOCATION = "R1G17" !CDS_LOCATION = "R1G17" #SEC = "1" !CDS_SEC = "1";
"A":   PN = "1"  !CDS_PN = "1";
"B":   PN = "2"  !CDS_PN = "2";
BODY = "RES","I38": #LOCATION = "R9L2" !CDS_LOCATION = "R9L2" #SEC = "1" !CDS_SEC = "1";
"A":   PN = "1"  !CDS_PN = "1";
"B":   PN = "2"  !CDS_PN = "2";
BODY = "RES","I40": #LOCATION = "R9L1" !CDS_LOCATION = "R9L1" #SEC = "1" !CDS_SEC = "1";
"A":   PN = "1"  !CDS_PN = "1";
"B":   PN = "2"  !CDS_PN = "2";
BODY = "RES","I41": #LOCATION = "R1G14" !CDS_LOCATION = "R1G14" #SEC = "1" !CDS_SEC = "1";
"A":   PN = "1"  !CDS_PN = "1";
"B":   PN = "2"  !CDS_PN = "2";
BODY = "CAP_A","I42": #LOCATION = "C1G18" !CDS_LOCATION = "C1G18" #SEC = "1" !CDS_SEC = "1";
"A":   PN = "1"  !CDS_PN = "1";
"B":   PN = "2"  !CDS_PN = "2";
BODY = "RES","I45": #LOCATION = "R9L3" !CDS_LOCATION = "R9L3" #SEC = "1" !CDS_SEC = "1";
"A":   PN = "1"  !CDS_PN = "1";
"B":   PN = "2"  !CDS_PN = "2";
BODY = "CAP_A","I46": #LOCATION = "C9L3" !CDS_LOCATION = "C9L3" #SEC = "1" !CDS_SEC = "1";
"A":   PN = "1"  !CDS_PN = "1";
"B":   PN = "2"  !CDS_PN = "2";
DRAWING = "@baseboard_fab2_lib.baseboard_fab2(sch_1):page101";
BODY = "RES","I20": #LOCATION = "R8F29" !CDS_LOCATION = "R8F29" #SEC = "1" !CDS_SEC = "1";
"A":   PN = "1"  !CDS_PN = "1";
"B":   PN = "2"  !CDS_PN = "2";
BODY = "RES","I28": #LOCATION = "R8F25" !CDS_LOCATION = "R8F25" &SEC = "1" #&CDS_SEC = "1";
"A":   PN = "1"  !CDS_PN = "1";
"B":   PN = "2"  !CDS_PN = "2";
BODY = "ICS9FGP204","I34": #LOCATION = "EU8F2" !CDS_LOCATION = "EU8F2" #SEC = "1" !CDS_SEC = "1";
"25MHZ_0":   PN = "16"  !CDS_PN = "16";
"25MHZ_1":   PN = "17"  !CDS_PN = "17";
"32KHZ":   PN = "13"  !CDS_PN = "13";
"33MHZ_SMBADR":   PN = "22"  !CDS_PN = "22";
"CPUCLKC0":   PN = "8"  !CDS_PN = "8";
"CPUCLKT0":   PN = "7"  !CDS_PN = "7";
"DOT96SSC":   PN = "4"  !CDS_PN = "4";
"DOT96SST":   PN = "3"  !CDS_PN = "3";
"GND<0>":   PN = "1"  !CDS_PN = "1";
"GND<1>":   PN = "41"  !CDS_PN = "41";
"GND32K":   PN = "14"  !CDS_PN = "14";
"GND33":   PN = "21"  !CDS_PN = "21";
"GND_RGMII":   PN = "35"  !CDS_PN = "35";
"GNDCPU":   PN = "10"  !CDS_PN = "10";
"GNDREF":   PN = "18"  !CDS_PN = "18";
"GNDRMII<0>":   PN = "27"  !CDS_PN = "27";
"GNDRMII<1>":   PN = "30"  !CDS_PN = "30";
"IREF":   PN = "11"  !CDS_PN = "11";
"OE_96":   PN = "5"  !CDS_PN = "5";
"OE_CPU":   PN = "6"  !CDS_PN = "6";
"RGMII<0>":   PN = "37"  !CDS_PN = "37";
"RGMII<1>":   PN = "36"  !CDS_PN = "36";
"RMII<0>":   PN = "33"  !CDS_PN = "33";
"RMII<1>":   PN = "32"  !CDS_PN = "32";
"RMII<2>":   PN = "29"  !CDS_PN = "29";
"RMII<3>":   PN = "28"  !CDS_PN = "28";
"RMII<4>":   PN = "25"  !CDS_PN = "25";
"RMII<5>":   PN = "24"  !CDS_PN = "24";
"SMBCLK":   PN = "38"  !CDS_PN = "38";
"SMBDAT":   PN = "39"  !CDS_PN = "39";
"VDD32K":   PN = "12"  !CDS_PN = "12";
"VDD33":   PN = "23"  !CDS_PN = "23";
"VDD96":   PN = "2"  !CDS_PN = "2";
"VDD_RGMII":   PN = "34"  !CDS_PN = "34";
"VDDCPU":   PN = "9"  !CDS_PN = "9";
"VDDREF":   PN = "15"  !CDS_PN = "15";
"VDDRMII<0>":   PN = "26"  !CDS_PN = "26";
"VDDRMII<1>":   PN = "31"  !CDS_PN = "31";
"VTTPWR_GD_PD_N":   PN = "40"  !CDS_PN = "40";
"X1_25":   PN = "19"  !CDS_PN = "19";
"X2_25":   PN = "20"  !CDS_PN = "20";
BODY = "RES","I48": #LOCATION = "R2T25" !CDS_LOCATION = "R2T25" #SEC = "1" !CDS_SEC = "1";
"A":   PN = "1"  !CDS_PN = "1";
"B":   PN = "2"  !CDS_PN = "2";
BODY = "CAP","I49": #LOCATION = "C8F18" !CDS_LOCATION = "C8F18" &SEC = "1" #&CDS_SEC = "1";
"A":   PN = "1"  !CDS_PN = "1";
"B":   PN = "2"  !CDS_PN = "2";
BODY = "CRYSTAL","I52": #LOCATION = "Y8F1" !CDS_LOCATION = "Y8F1" &SEC = "1" #&CDS_SEC = "1";
"A":   PN = "1"  !CDS_PN = "1";
"B":   PN = "3"  !CDS_PN = "3";
BODY = "CAP","I53": #LOCATION = "C8F19" !CDS_LOCATION = "C8F19" &SEC = "1" #&CDS_SEC = "1";
"A":   PN = "1"  !CDS_PN = "1";
"B":   PN = "2"  !CDS_PN = "2";
BODY = "CAP_A","I89": #LOCATION = "C2T31" !CDS_LOCATION = "C2T31" &SEC = "1" #&CDS_SEC = "1";
"A":   PN = "1"  !CDS_PN = "1";
"B":   PN = "2"  !CDS_PN = "2";
BODY = "CAP_A","I90": #LOCATION = "C2T27" !CDS_LOCATION = "C2T27" &SEC = "1" #&CDS_SEC = "1";
"A":   PN = "1"  !CDS_PN = "1";
"B":   PN = "2"  !CDS_PN = "2";
BODY = "RES","I94": #LOCATION = "R2T23" !CDS_LOCATION = "R2T23" &SEC = "1" #&CDS_SEC = "1";
"A":   PN = "1"  !CDS_PN = "1";
"B":   PN = "2"  !CDS_PN = "2";
BODY = "RES","I95": #LOCATION = "R2T52" !CDS_LOCATION = "R2T52" &SEC = "1" #&CDS_SEC = "1";
"A":   PN = "1"  !CDS_PN = "1";
"B":   PN = "2"  !CDS_PN = "2";
BODY = "CAP_A","I97": #LOCATION = "C2T38" !CDS_LOCATION = "C2T38" &SEC = "1" #&CDS_SEC = "1";
"A":   PN = "1"  !CDS_PN = "1";
"B":   PN = "2"  !CDS_PN = "2";
BODY = "CAP_A","I99": #LOCATION = "C2T37" !CDS_LOCATION = "C2T37" &SEC = "1" #&CDS_SEC = "1";
"A":   PN = "1"  !CDS_PN = "1";
"B":   PN = "2"  !CDS_PN = "2";
BODY = "CAP_A","I104": #LOCATION = "C2T18" !CDS_LOCATION = "C2T18" &SEC = "1" #&CDS_SEC = "1";
"A":   PN = "1"  !CDS_PN = "1";
"B":   PN = "2"  !CDS_PN = "2";
BODY = "RES","I105": #LOCATION = "R2T21" !CDS_LOCATION = "R2T21" #SEC = "1" !CDS_SEC = "1";
"A":   PN = "1"  !CDS_PN = "1";
"B":   PN = "2"  !CDS_PN = "2";
BODY = "CAP_A","I106": #LOCATION = "C2T19" !CDS_LOCATION = "C2T19" &SEC = "1" #&CDS_SEC = "1";
"A":   PN = "1"  !CDS_PN = "1";
"B":   PN = "2"  !CDS_PN = "2";
BODY = "CAP_A","I109": #LOCATION = "C2T34" !CDS_LOCATION = "C2T34" #SEC = "1" !CDS_SEC = "1";
"A":   PN = "1"  !CDS_PN = "1";
"B":   PN = "2"  !CDS_PN = "2";
BODY = "CAP_A","I110": #LOCATION = "C2T30" !CDS_LOCATION = "C2T30" &SEC = "1" #&CDS_SEC = "1";
"A":   PN = "1"  !CDS_PN = "1";
"B":   PN = "2"  !CDS_PN = "2";
BODY = "CAP_A","I111": #LOCATION = "C2T25" !CDS_LOCATION = "C2T25" &SEC = "1" #&CDS_SEC = "1";
"A":   PN = "1"  !CDS_PN = "1";
"B":   PN = "2"  !CDS_PN = "2";
BODY = "CAP_A","I112": #LOCATION = "C2T17" !CDS_LOCATION = "C2T17" &SEC = "1" #&CDS_SEC = "1";
"A":   PN = "1"  !CDS_PN = "1";
"B":   PN = "2"  !CDS_PN = "2";
BODY = "CAP","I113": #LOCATION = "C2T22" !CDS_LOCATION = "C2T22" #SEC = "1" !CDS_SEC = "1";
"A":   PN = "1"  !CDS_PN = "1";
"B":   PN = "2"  !CDS_PN = "2";
BODY = "FERRITE","I114": #LOCATION = "FB2T2" !CDS_LOCATION = "FB2T2" &SEC = "1" #&CDS_SEC = "1";
"A":   PN = "1"  !CDS_PN = "1";
"B":   PN = "2"  !CDS_PN = "2";
BODY = "CAP_A","I116": #LOCATION = "C2T28" !CDS_LOCATION = "C2T28" &SEC = "1" #&CDS_SEC = "1";
"A":   PN = "1"  !CDS_PN = "1";
"B":   PN = "2"  !CDS_PN = "2";
BODY = "RES","I124": #LOCATION = "R2T42" !CDS_LOCATION = "R2T42" #SEC = "1" !CDS_SEC = "1";
"A":   PN = "1"  !CDS_PN = "1";
"B":   PN = "2"  !CDS_PN = "2";
BODY = "RES","I125": #LOCATION = "R2T46" !CDS_LOCATION = "R2T46" #SEC = "1" !CDS_SEC = "1";
"A":   PN = "1"  !CDS_PN = "1";
"B":   PN = "2"  !CDS_PN = "2";
BODY = "RES","I129": #LOCATION = "R8F27" !CDS_LOCATION = "R8F27" &SEC = "1" #&CDS_SEC = "1";
"A":   PN = "1"  !CDS_PN = "1";
"B":   PN = "2"  !CDS_PN = "2";
BODY = "RES","I130": #LOCATION = "R2T47" !CDS_LOCATION = "R2T47" #SEC = "1" !CDS_SEC = "1";
"A":   PN = "1"  !CDS_PN = "1";
"B":   PN = "2"  !CDS_PN = "2";
BODY = "RES","I131": #LOCATION = "R8G25" !CDS_LOCATION = "R8G25" #SEC = "1" !CDS_SEC = "1";
"A":   PN = "1"  !CDS_PN = "1";
"B":   PN = "2"  !CDS_PN = "2";
BODY = "RES","I132": #LOCATION = "R8G24" !CDS_LOCATION = "R8G24" #SEC = "1" !CDS_SEC = "1";
"A":   PN = "1"  !CDS_PN = "1";
"B":   PN = "2"  !CDS_PN = "2";
BODY = "RES","I133": #LOCATION = "R8G1" !CDS_LOCATION = "R8G1" &SEC = "1" #&CDS_SEC = "1";
"A":   PN = "1"  !CDS_PN = "1";
"B":   PN = "2"  !CDS_PN = "2";
DRAWING = "@baseboard_fab2_lib.baseboard_fab2(sch_1):page102";
BODY = "NB3W1200L","I1": #LOCATION = "EU4D2" !CDS_LOCATION = "EU4D2" #SEC = "1" !CDS_SEC = "1";
"100M_133M_N":   PN = "4"  !CDS_PN = "4";
"CLK_INN":   PN = "10"  !CDS_PN = "10";
"CLK_INP":   PN = "9"  !CDS_PN = "9";
"DIF_0N":   PN = "18"  !CDS_PN = "18";
"DIF_0P":   PN = "17"  !CDS_PN = "17";
"DIF_1N":   PN = "22"  !CDS_PN = "22";
"DIF_1P":   PN = "21"  !CDS_PN = "21";
"DIF_2N":   PN = "27"  !CDS_PN = "27";
"DIF_2P":   PN = "26"  !CDS_PN = "26";
"DIF_3N":   PN = "31"  !CDS_PN = "31";
"DIF_3P":   PN = "30"  !CDS_PN = "30";
"DIF_4N":   PN = "35"  !CDS_PN = "35";
"DIF_4P":   PN = "34"  !CDS_PN = "34";
"DIF_5N":   PN = "39"  !CDS_PN = "39";
"DIF_5P":   PN = "38"  !CDS_PN = "38";
"DIF_6N":   PN = "43"  !CDS_PN = "43";
"DIF_6P":   PN = "42"  !CDS_PN = "42";
"DIF_7N":   PN = "47"  !CDS_PN = "47";
"DIF_7P":   PN = "46"  !CDS_PN = "46";
"DIF_8N":   PN = "51"  !CDS_PN = "51";
"DIF_8P":   PN = "50"  !CDS_PN = "50";
"DIF_9N":   PN = "55"  !CDS_PN = "55";
"DIF_9P":   PN = "54"  !CDS_PN = "54";
"DIF_10N":   PN = "60"  !CDS_PN = "60";
"DIF_10P":   PN = "59"  !CDS_PN = "59";
"DIF_11N":   PN = "64"  !CDS_PN = "64";
"DIF_11P":   PN = "63"  !CDS_PN = "63";
"GND<0>":   PN = "7"  !CDS_PN = "7";
"GND<1>":   PN = "23"  !CDS_PN = "23";
"GND<2>":   PN = "33"  !CDS_PN = "33";
"GND<3>":   PN = "41"  !CDS_PN = "41";
"GND<4>":   PN = "48"  !CDS_PN = "48";
"GND<5>":   PN = "58"  !CDS_PN = "58";
"GNDA":   PN = "2"  !CDS_PN = "2";
"HBW_BYPASS_LOBW_N":   PN = "5"  !CDS_PN = "5";
"NC<0>":   PN = "3"  !CDS_PN = "3";
"NC<1>":   PN = "16"  !CDS_PN = "16";
"NC<2>":   PN = "15"  !CDS_PN = "15";
"OE_0_N":   PN = "19"  !CDS_PN = "19";
"OE_1_N":   PN = "20"  !CDS_PN = "20";
"OE_2_N":   PN = "28"  !CDS_PN = "28";
"OE_3_N":   PN = "29"  !CDS_PN = "29";
"OE_4_N":   PN = "36"  !CDS_PN = "36";
"OE_5_N":   PN = "37"  !CDS_PN = "37";
"OE_6_N":   PN = "44"  !CDS_PN = "44";
"OE_7_N":   PN = "45"  !CDS_PN = "45";
"OE_8_N":   PN = "52"  !CDS_PN = "52";
"OE_9_N":   PN = "53"  !CDS_PN = "53";
"OE_10_N":   PN = "61"  !CDS_PN = "61";
"OE_11_N":   PN = "62"  !CDS_PN = "62";
"PWRGD_PWRDN_N":   PN = "6"  !CDS_PN = "6";
"SA_0":   PN = "11"  !CDS_PN = "11";
"SA_1":   PN = "14"  !CDS_PN = "14";
"SCL":   PN = "13"  !CDS_PN = "13";
"SDA":   PN = "12"  !CDS_PN = "12";
"THPAD":   PN = "65"  !CDS_PN = "65";
"VDD<0>":   PN = "24"  !CDS_PN = "24";
"VDD<1>":   PN = "40"  !CDS_PN = "40";
"VDD<2>":   PN = "57"  !CDS_PN = "57";
"VDDA":   PN = "1"  !CDS_PN = "1";
"VDDIO<0>":   PN = "25"  !CDS_PN = "25";
"VDDIO<1>":   PN = "32"  !CDS_PN = "32";
"VDDIO<2>":   PN = "49"  !CDS_PN = "49";
"VDDIO<3>":   PN = "56"  !CDS_PN = "56";
"VDDR":   PN = "8"  !CDS_PN = "8";
BODY = "FERRITE","I8": #LOCATION = "FB6P1" !CDS_LOCATION = "FB6P1" #SEC = "1" !CDS_SEC = "1";
"A":   PN = "1"  !CDS_PN = "1";
"B":   PN = "2"  !CDS_PN = "2";
BODY = "CAP","I10": #LOCATION = "C3D22" !CDS_LOCATION = "C3D22" #SEC = "1" !CDS_SEC = "1";
"A":   PN = "1"  !CDS_PN = "1";
"B":   PN = "2"  !CDS_PN = "2";
BODY = "CAP_A","I11": #LOCATION = "C6P4" !CDS_LOCATION = "C6P4" #SEC = "1" !CDS_SEC = "1";
"A":   PN = "1"  !CDS_PN = "1";
"B":   PN = "2"  !CDS_PN = "2";
BODY = "CAP_A","I12": #LOCATION = "C6P6" !CDS_LOCATION = "C6P6" #SEC = "1" !CDS_SEC = "1";
"A":   PN = "1"  !CDS_PN = "1";
"B":   PN = "2"  !CDS_PN = "2";
BODY = "CAP_A","I13": #LOCATION = "C6P10" !CDS_LOCATION = "C6P10" #SEC = "1" !CDS_SEC = "1";
"A":   PN = "1"  !CDS_PN = "1";
"B":   PN = "2"  !CDS_PN = "2";
BODY = "CAP_A","I14": #LOCATION = "C6P5" !CDS_LOCATION = "C6P5" #SEC = "1" !CDS_SEC = "1";
"A":   PN = "1"  !CDS_PN = "1";
"B":   PN = "2"  !CDS_PN = "2";
BODY = "CAP_A","I15": #LOCATION = "C6P12" !CDS_LOCATION = "C6P12" #SEC = "1" !CDS_SEC = "1";
"A":   PN = "1"  !CDS_PN = "1";
"B":   PN = "2"  !CDS_PN = "2";
BODY = "CAP_A","I16": #LOCATION = "C6P11" !CDS_LOCATION = "C6P11" #SEC = "1" !CDS_SEC = "1";
"A":   PN = "1"  !CDS_PN = "1";
"B":   PN = "2"  !CDS_PN = "2";
BODY = "CAP_A","I18": #LOCATION = "C4D24" !CDS_LOCATION = "C4D24" #SEC = "1" !CDS_SEC = "1";
"A":   PN = "1"  !CDS_PN = "1";
"B":   PN = "2"  !CDS_PN = "2";
BODY = "CAP_A","I19": #LOCATION = "C4D23" !CDS_LOCATION = "C4D23" #SEC = "1" !CDS_SEC = "1";
"A":   PN = "1"  !CDS_PN = "1";
"B":   PN = "2"  !CDS_PN = "2";
BODY = "RES","I21": #LOCATION = "R3D14" !CDS_LOCATION = "R3D14" #SEC = "1" !CDS_SEC = "1";
"A":   PN = "1"  !CDS_PN = "1";
"B":   PN = "2"  !CDS_PN = "2";
BODY = "RES","I26": #LOCATION = "R6P25" !CDS_LOCATION = "R6P25" #SEC = "1" !CDS_SEC = "1";
"A":   PN = "1"  !CDS_PN = "1";
"B":   PN = "2"  !CDS_PN = "2";
BODY = "CAP_A","I28": #LOCATION = "C4D22" !CDS_LOCATION = "C4D22" #SEC = "1" !CDS_SEC = "1";
"A":   PN = "1"  !CDS_PN = "1";
"B":   PN = "2"  !CDS_PN = "2";
BODY = "CAP_A","I30": #LOCATION = "C4D27" !CDS_LOCATION = "C4D27" #SEC = "1" !CDS_SEC = "1";
"A":   PN = "1"  !CDS_PN = "1";
"B":   PN = "2"  !CDS_PN = "2";
BODY = "RES","I37": #LOCATION = "R4D38" !CDS_LOCATION = "R4D38" #SEC = "1" !CDS_SEC = "1";
"A":   PN = "1"  !CDS_PN = "1";
"B":   PN = "2"  !CDS_PN = "2";
BODY = "RES","I38": #LOCATION = "R4D35" !CDS_LOCATION = "R4D35" #SEC = "1" !CDS_SEC = "1";
"A":   PN = "1"  !CDS_PN = "1";
"B":   PN = "2"  !CDS_PN = "2";
BODY = "RES","I45": #LOCATION = "R4D40" !CDS_LOCATION = "R4D40" #SEC = "1" !CDS_SEC = "1";
"A":   PN = "1"  !CDS_PN = "1";
"B":   PN = "2"  !CDS_PN = "2";
BODY = "RES","I46": #LOCATION = "R6P23" !CDS_LOCATION = "R6P23" #SEC = "1" !CDS_SEC = "1";
"A":   PN = "1"  !CDS_PN = "1";
"B":   PN = "2"  !CDS_PN = "2";
BODY = "RES","I47": #LOCATION = "R6P22" !CDS_LOCATION = "R6P22" #SEC = "1" !CDS_SEC = "1";
"A":   PN = "1"  !CDS_PN = "1";
"B":   PN = "2"  !CDS_PN = "2";
BODY = "RES","I53": #LOCATION = "R4D41" !CDS_LOCATION = "R4D41" #SEC = "1" !CDS_SEC = "1";
"A":   PN = "1"  !CDS_PN = "1";
"B":   PN = "2"  !CDS_PN = "2";
BODY = "CAP_A","I79": #LOCATION = "C6P9" !CDS_LOCATION = "C6P9" #SEC = "1" !CDS_SEC = "1";
"A":   PN = "1"  !CDS_PN = "1";
"B":   PN = "2"  !CDS_PN = "2";
BODY = "RES","I80": #LOCATION = "R6P21" !CDS_LOCATION = "R6P21" #SEC = "1" !CDS_SEC = "1";
"A":   PN = "1"  !CDS_PN = "1";
"B":   PN = "2"  !CDS_PN = "2";
BODY = "RES","I81": #LOCATION = "R6P20" !CDS_LOCATION = "R6P20" #SEC = "1" !CDS_SEC = "1";
"A":   PN = "1"  !CDS_PN = "1";
"B":   PN = "2"  !CDS_PN = "2";
BODY = "RES","I82": #LOCATION = "R4D36" !CDS_LOCATION = "R4D36" &SEC = "1" #&CDS_SEC = "1";
"A":   PN = "1"  !CDS_PN = "1";
"B":   PN = "2"  !CDS_PN = "2";
BODY = "RES","I87": #LOCATION = "R4D37" !CDS_LOCATION = "R4D37" &SEC = "1" #&CDS_SEC = "1";
"A":   PN = "1"  !CDS_PN = "1";
"B":   PN = "2"  !CDS_PN = "2";
BODY = "RES","I91": #LOCATION = "R6P48" !CDS_LOCATION = "R6P48" #SEC = "1" !CDS_SEC = "1";
"A":   PN = "1"  !CDS_PN = "1";
"B":   PN = "2"  !CDS_PN = "2";
BODY = "RES","I93": #LOCATION = "R4D69" !CDS_LOCATION = "R4D69" #SEC = "1" !CDS_SEC = "1";
"A":   PN = "1"  !CDS_PN = "1";
"B":   PN = "2"  !CDS_PN = "2";
BODY = "RES","I94": #LOCATION = "R4D70" !CDS_LOCATION = "R4D70" #SEC = "1" !CDS_SEC = "1";
"A":   PN = "1"  !CDS_PN = "1";
"B":   PN = "2"  !CDS_PN = "2";
DRAWING = "@baseboard_fab2_lib.baseboard_fab2(sch_1):page103";
BODY = "RES","I1": #LOCATION = "R4D25" !CDS_LOCATION = "R4D25" #SEC = "1" !CDS_SEC = "1";
"A":   PN = "1"  !CDS_PN = "1";
"B":   PN = "2"  !CDS_PN = "2";
BODY = "RES","I9": #LOCATION = "R4D23" !CDS_LOCATION = "R4D23" #SEC = "1" !CDS_SEC = "1";
"A":   PN = "1"  !CDS_PN = "1";
"B":   PN = "2"  !CDS_PN = "2";
BODY = "RES","I14": #LOCATION = "R4D28" !CDS_LOCATION = "R4D28" #SEC = "1" !CDS_SEC = "1";
"A":   PN = "1"  !CDS_PN = "1";
"B":   PN = "2"  !CDS_PN = "2";
BODY = "RES","I19": #LOCATION = "R4D19" !CDS_LOCATION = "R4D19" #SEC = "1" !CDS_SEC = "1";
"A":   PN = "1"  !CDS_PN = "1";
"B":   PN = "2"  !CDS_PN = "2";
BODY = "RES","I24": #LOCATION = "R4D21" !CDS_LOCATION = "R4D21" #SEC = "1" !CDS_SEC = "1";
"A":   PN = "1"  !CDS_PN = "1";
"B":   PN = "2"  !CDS_PN = "2";
BODY = "RES","I29": #LOCATION = "R4D13" !CDS_LOCATION = "R4D13" #SEC = "1" !CDS_SEC = "1";
"A":   PN = "1"  !CDS_PN = "1";
"B":   PN = "2"  !CDS_PN = "2";
BODY = "RES","I34": #LOCATION = "R4D16" !CDS_LOCATION = "R4D16" #SEC = "1" !CDS_SEC = "1";
"A":   PN = "1"  !CDS_PN = "1";
"B":   PN = "2"  !CDS_PN = "2";
BODY = "RES","I39": #LOCATION = "R4D9" !CDS_LOCATION = "R4D9" #SEC = "1" !CDS_SEC = "1";
"A":   PN = "1"  !CDS_PN = "1";
"B":   PN = "2"  !CDS_PN = "2";
BODY = "RES","I44": #LOCATION = "R4D11" !CDS_LOCATION = "R4D11" #SEC = "1" !CDS_SEC = "1";
"A":   PN = "1"  !CDS_PN = "1";
"B":   PN = "2"  !CDS_PN = "2";
BODY = "RES","I49": #LOCATION = "R4D2" !CDS_LOCATION = "R4D2" &SEC = "1" #&CDS_SEC = "1";
"A":   PN = "1"  !CDS_PN = "1";
"B":   PN = "2"  !CDS_PN = "2";
BODY = "RES","I54": #LOCATION = "R4D1" !CDS_LOCATION = "R4D1" #SEC = "1" !CDS_SEC = "1";
"A":   PN = "1"  !CDS_PN = "1";
"B":   PN = "2"  !CDS_PN = "2";
BODY = "RES","I59": #LOCATION = "R4D4" !CDS_LOCATION = "R4D4" #SEC = "1" !CDS_SEC = "1";
"A":   PN = "1"  !CDS_PN = "1";
"B":   PN = "2"  !CDS_PN = "2";
BODY = "RES","I64": #LOCATION = "R4D3" !CDS_LOCATION = "R4D3" #SEC = "1" !CDS_SEC = "1";
"A":   PN = "1"  !CDS_PN = "1";
"B":   PN = "2"  !CDS_PN = "2";
BODY = "RES","I69": #LOCATION = "R4D29" !CDS_LOCATION = "R4D29" #SEC = "1" !CDS_SEC = "1";
"A":   PN = "1"  !CDS_PN = "1";
"B":   PN = "2"  !CDS_PN = "2";
BODY = "RES","I74": #LOCATION = "R4D6" !CDS_LOCATION = "R4D6" #SEC = "1" !CDS_SEC = "1";
"A":   PN = "1"  !CDS_PN = "1";
"B":   PN = "2"  !CDS_PN = "2";
BODY = "RES","I79": #LOCATION = "R4D5" !CDS_LOCATION = "R4D5" #SEC = "1" !CDS_SEC = "1";
"A":   PN = "1"  !CDS_PN = "1";
"B":   PN = "2"  !CDS_PN = "2";
BODY = "RES","I84": #LOCATION = "R4D8" !CDS_LOCATION = "R4D8" #SEC = "1" !CDS_SEC = "1";
"A":   PN = "1"  !CDS_PN = "1";
"B":   PN = "2"  !CDS_PN = "2";
BODY = "RES","I89": #LOCATION = "R4D7" !CDS_LOCATION = "R4D7" #SEC = "1" !CDS_SEC = "1";
"A":   PN = "1"  !CDS_PN = "1";
"B":   PN = "2"  !CDS_PN = "2";
BODY = "RES","I94": #LOCATION = "R4D12" !CDS_LOCATION = "R4D12" #SEC = "1" !CDS_SEC = "1";
"A":   PN = "1"  !CDS_PN = "1";
"B":   PN = "2"  !CDS_PN = "2";
BODY = "RES","I99": #LOCATION = "R4D10" !CDS_LOCATION = "R4D10" #SEC = "1" !CDS_SEC = "1";
"A":   PN = "1"  !CDS_PN = "1";
"B":   PN = "2"  !CDS_PN = "2";
BODY = "RES","I104": #LOCATION = "R4D17" !CDS_LOCATION = "R4D17" #SEC = "1" !CDS_SEC = "1";
"A":   PN = "1"  !CDS_PN = "1";
"B":   PN = "2"  !CDS_PN = "2";
BODY = "RES","I109": #LOCATION = "R4D14" !CDS_LOCATION = "R4D14" #SEC = "1" !CDS_SEC = "1";
"A":   PN = "1"  !CDS_PN = "1";
"B":   PN = "2"  !CDS_PN = "2";
BODY = "RES","I114": #LOCATION = "R4D22" !CDS_LOCATION = "R4D22" #SEC = "1" !CDS_SEC = "1";
"A":   PN = "1"  !CDS_PN = "1";
"B":   PN = "2"  !CDS_PN = "2";
BODY = "RES","I119": #LOCATION = "R4D20" !CDS_LOCATION = "R4D20" #SEC = "1" !CDS_SEC = "1";
"A":   PN = "1"  !CDS_PN = "1";
"B":   PN = "2"  !CDS_PN = "2";
BODY = "RES","I121": #LOCATION = "R7P9" !CDS_LOCATION = "R7P9" #SEC = "1" !CDS_SEC = "1";
"A":   PN = "1"  !CDS_PN = "1";
"B":   PN = "2"  !CDS_PN = "2";
BODY = "RES","I123": #LOCATION = "R7P12" !CDS_LOCATION = "R7P12" #SEC = "1" !CDS_SEC = "1";
"A":   PN = "1"  !CDS_PN = "1";
"B":   PN = "2"  !CDS_PN = "2";
BODY = "RES","I125": #LOCATION = "R7P6" !CDS_LOCATION = "R7P6" #SEC = "1" !CDS_SEC = "1";
"A":   PN = "1"  !CDS_PN = "1";
"B":   PN = "2"  !CDS_PN = "2";
BODY = "RES","I127": #LOCATION = "R7P7" !CDS_LOCATION = "R7P7" &SEC = "1" #&CDS_SEC = "1";
"A":   PN = "1"  !CDS_PN = "1";
"B":   PN = "2"  !CDS_PN = "2";
BODY = "RES","I129": #LOCATION = "R7P3" !CDS_LOCATION = "R7P3" #SEC = "1" !CDS_SEC = "1";
"A":   PN = "1"  !CDS_PN = "1";
"B":   PN = "2"  !CDS_PN = "2";
BODY = "RES","I131": #LOCATION = "R7P4" !CDS_LOCATION = "R7P4" #SEC = "1" !CDS_SEC = "1";
"A":   PN = "1"  !CDS_PN = "1";
"B":   PN = "2"  !CDS_PN = "2";
BODY = "RES","I133": #LOCATION = "R7P1" !CDS_LOCATION = "R7P1" #SEC = "1" !CDS_SEC = "1";
"A":   PN = "1"  !CDS_PN = "1";
"B":   PN = "2"  !CDS_PN = "2";
BODY = "RES","I135": #LOCATION = "R7P2" !CDS_LOCATION = "R7P2" #SEC = "1" !CDS_SEC = "1";
"A":   PN = "1"  !CDS_PN = "1";
"B":   PN = "2"  !CDS_PN = "2";
BODY = "RES","I137": #LOCATION = "R6P7" !CDS_LOCATION = "R6P7" #SEC = "1" !CDS_SEC = "1";
"A":   PN = "1"  !CDS_PN = "1";
"B":   PN = "2"  !CDS_PN = "2";
BODY = "RES","I139": #LOCATION = "R6P8" !CDS_LOCATION = "R6P8" #SEC = "1" !CDS_SEC = "1";
"A":   PN = "1"  !CDS_PN = "1";
"B":   PN = "2"  !CDS_PN = "2";
BODY = "RES","I141": #LOCATION = "R6P5" !CDS_LOCATION = "R6P5" #SEC = "1" !CDS_SEC = "1";
"A":   PN = "1"  !CDS_PN = "1";
"B":   PN = "2"  !CDS_PN = "2";
BODY = "RES","I143": #LOCATION = "R6P6" !CDS_LOCATION = "R6P6" #SEC = "1" !CDS_SEC = "1";
"A":   PN = "1"  !CDS_PN = "1";
"B":   PN = "2"  !CDS_PN = "2";
BODY = "RES","I145": #LOCATION = "R6P3" !CDS_LOCATION = "R6P3" #SEC = "1" !CDS_SEC = "1";
"A":   PN = "1"  !CDS_PN = "1";
"B":   PN = "2"  !CDS_PN = "2";
BODY = "RES","I147": #LOCATION = "R6P4" !CDS_LOCATION = "R6P4" #SEC = "1" !CDS_SEC = "1";
"A":   PN = "1"  !CDS_PN = "1";
"B":   PN = "2"  !CDS_PN = "2";
BODY = "RES","I149": #LOCATION = "R6P1" !CDS_LOCATION = "R6P1" #SEC = "1" !CDS_SEC = "1";
"A":   PN = "1"  !CDS_PN = "1";
"B":   PN = "2"  !CDS_PN = "2";
BODY = "RES","I151": #LOCATION = "R6P2" !CDS_LOCATION = "R6P2" #SEC = "1" !CDS_SEC = "1";
"A":   PN = "1"  !CDS_PN = "1";
"B":   PN = "2"  !CDS_PN = "2";
BODY = "RES","I153": #LOCATION = "R6P11" !CDS_LOCATION = "R6P11" #SEC = "1" !CDS_SEC = "1";
"A":   PN = "1"  !CDS_PN = "1";
"B":   PN = "2"  !CDS_PN = "2";
BODY = "RES","I155": #LOCATION = "R6P9" !CDS_LOCATION = "R6P9" #SEC = "1" !CDS_SEC = "1";
"A":   PN = "1"  !CDS_PN = "1";
"B":   PN = "2"  !CDS_PN = "2";
BODY = "RES","I157": #LOCATION = "R6P13" !CDS_LOCATION = "R6P13" #SEC = "1" !CDS_SEC = "1";
"A":   PN = "1"  !CDS_PN = "1";
"B":   PN = "2"  !CDS_PN = "2";
BODY = "RES","I159": #LOCATION = "R6P12" !CDS_LOCATION = "R6P12" #SEC = "1" !CDS_SEC = "1";
"A":   PN = "1"  !CDS_PN = "1";
"B":   PN = "2"  !CDS_PN = "2";
BODY = "RES","I161": #LOCATION = "R4D24" !CDS_LOCATION = "R4D24" #SEC = "1" !CDS_SEC = "1";
"A":   PN = "1"  !CDS_PN = "1";
"B":   PN = "2"  !CDS_PN = "2";
BODY = "RES","I163": #LOCATION = "R4D18" !CDS_LOCATION = "R4D18" #SEC = "1" !CDS_SEC = "1";
"A":   PN = "1"  !CDS_PN = "1";
"B":   PN = "2"  !CDS_PN = "2";
BODY = "RES","I165": #LOCATION = "R6P17" !CDS_LOCATION = "R6P17" #SEC = "1" !CDS_SEC = "1";
"A":   PN = "1"  !CDS_PN = "1";
"B":   PN = "2"  !CDS_PN = "2";
BODY = "RES","I167": #LOCATION = "R6P15" !CDS_LOCATION = "R6P15" #SEC = "1" !CDS_SEC = "1";
"A":   PN = "1"  !CDS_PN = "1";
"B":   PN = "2"  !CDS_PN = "2";
DRAWING = "@baseboard_fab2_lib.baseboard_fab2(sch_1):page104";
BODY = "CAP_A","I25": #LOCATION = "C6F1" !CDS_LOCATION = "C6F1" #SEC = "1" !CDS_SEC = "1";
"A":   PN = "1"  !CDS_PN = "1";
"B":   PN = "2"  !CDS_PN = "2";
BODY = "CAP_A","I34": #LOCATION = "C3F2" !CDS_LOCATION = "C3F2" #SEC = "1" !CDS_SEC = "1";
"A":   PN = "1"  !CDS_PN = "1";
"B":   PN = "2"  !CDS_PN = "2";
BODY = "RES","I37": #LOCATION = "R6F8" !CDS_LOCATION = "R6F8" #SEC = "1" !CDS_SEC = "1";
"A":   PN = "1"  !CDS_PN = "1";
"B":   PN = "2"  !CDS_PN = "2";
BODY = "RES","I41": #LOCATION = "R6F6" !CDS_LOCATION = "R6F6" #SEC = "1" !CDS_SEC = "1";
"A":   PN = "1"  !CDS_PN = "1";
"B":   PN = "2"  !CDS_PN = "2";
BODY = "RES","I51": #LOCATION = "R3F1" !CDS_LOCATION = "R3F1" #SEC = "1" !CDS_SEC = "1";
"A":   PN = "1"  !CDS_PN = "1";
"B":   PN = "2"  !CDS_PN = "2";
BODY = "RES","I53": #LOCATION = "R3F3" !CDS_LOCATION = "R3F3" #SEC = "1" !CDS_SEC = "1";
"A":   PN = "1"  !CDS_PN = "1";
"B":   PN = "2"  !CDS_PN = "2";
BODY = "RES","I67": #LOCATION = "R6F7" !CDS_LOCATION = "R6F7" #SEC = "1" !CDS_SEC = "1";
"A":   PN = "1"  !CDS_PN = "1";
"B":   PN = "2"  !CDS_PN = "2";
BODY = "RES","I68": #LOCATION = "R6F9" !CDS_LOCATION = "R6F9" #SEC = "1" !CDS_SEC = "1";
"A":   PN = "1"  !CDS_PN = "1";
"B":   PN = "2"  !CDS_PN = "2";
BODY = "RES","I69": #LOCATION = "R3F2" !CDS_LOCATION = "R3F2" #SEC = "1" !CDS_SEC = "1";
"A":   PN = "1"  !CDS_PN = "1";
"B":   PN = "2"  !CDS_PN = "2";
BODY = "RES","I70": #LOCATION = "R3F4" !CDS_LOCATION = "R3F4" #SEC = "1" !CDS_SEC = "1";
"A":   PN = "1"  !CDS_PN = "1";
"B":   PN = "2"  !CDS_PN = "2";
BODY = "OSC_C","I71": #LOCATION = "Y6F1" !CDS_LOCATION = "Y6F1" #SEC = "1" !CDS_SEC = "1";
"ENABLE_DISABLE":   PN = "1"  !CDS_PN = "1";
"GND":   PN = "3"  !CDS_PN = "3";
"NC_GND":   PN = "2"  !CDS_PN = "2";
"OUT":   PN = "4"  !CDS_PN = "4";
"OUT_N":   PN = "5"  !CDS_PN = "5";
"VCC":   PN = "6"  !CDS_PN = "6";
BODY = "OSC_C","I72": #LOCATION = "Y3F1" !CDS_LOCATION = "Y3F1" #SEC = "1" !CDS_SEC = "1";
"ENABLE_DISABLE":   PN = "1"  !CDS_PN = "1";
"GND":   PN = "3"  !CDS_PN = "3";
"NC_GND":   PN = "2"  !CDS_PN = "2";
"OUT":   PN = "4"  !CDS_PN = "4";
"OUT_N":   PN = "5"  !CDS_PN = "5";
"VCC":   PN = "6"  !CDS_PN = "6";
BODY = "RES","I78": #LOCATION = "R6F10" !CDS_LOCATION = "R6F10" #SEC = "1" !CDS_SEC = "1";
"A":   PN = "1"  !CDS_PN = "1";
"B":   PN = "2"  !CDS_PN = "2";
BODY = "RES","I79": #LOCATION = "R6F11" !CDS_LOCATION = "R6F11" #SEC = "1" !CDS_SEC = "1";
"A":   PN = "1"  !CDS_PN = "1";
"B":   PN = "2"  !CDS_PN = "2";
BODY = "RES","I84": #LOCATION = "R3F5" !CDS_LOCATION = "R3F5" #SEC = "1" !CDS_SEC = "1";
"A":   PN = "1"  !CDS_PN = "1";
"B":   PN = "2"  !CDS_PN = "2";
BODY = "RES","I88": #LOCATION = "R3F6" !CDS_LOCATION = "R3F6" #SEC = "1" !CDS_SEC = "1";
"A":   PN = "1"  !CDS_PN = "1";
"B":   PN = "2"  !CDS_PN = "2";
BODY = "RES","I93": #LOCATION = "R8D43" !CDS_LOCATION = "R8D43" #SEC = "1" !CDS_SEC = "1";
"A":   PN = "1"  !CDS_PN = "1";
"B":   PN = "2"  !CDS_PN = "2";
BODY = "RES","I94": #LOCATION = "R7D40" !CDS_LOCATION = "R7D40" #SEC = "1" !CDS_SEC = "1";
"A":   PN = "1"  !CDS_PN = "1";
"B":   PN = "2"  !CDS_PN = "2";
BODY = "RES","I95": #LOCATION = "R7D39" !CDS_LOCATION = "R7D39" #SEC = "1" !CDS_SEC = "1";
"A":   PN = "1"  !CDS_PN = "1";
"B":   PN = "2"  !CDS_PN = "2";
BODY = "RES","I96": #LOCATION = "R7D36" !CDS_LOCATION = "R7D36" #SEC = "1" !CDS_SEC = "1";
"A":   PN = "1"  !CDS_PN = "1";
"B":   PN = "2"  !CDS_PN = "2";
BODY = "RES","I97": #LOCATION = "R7D38" !CDS_LOCATION = "R7D38" #SEC = "1" !CDS_SEC = "1";
"A":   PN = "1"  !CDS_PN = "1";
"B":   PN = "2"  !CDS_PN = "2";
BODY = "RES","I98": #LOCATION = "R7D37" !CDS_LOCATION = "R7D37" #SEC = "1" !CDS_SEC = "1";
"A":   PN = "1"  !CDS_PN = "1";
"B":   PN = "2"  !CDS_PN = "2";
DRAWING = "@baseboard_fab2_lib.baseboard_fab2(sch_1):page105";
BODY = "CAP","I1": #LOCATION = "C7G24" !CDS_LOCATION = "C7G24" #SEC = "1" !CDS_SEC = "1";
"A":   PN = "1"  !CDS_PN = "1";
"B":   PN = "2"  !CDS_PN = "2";
BODY = "CAP","I6": #LOCATION = "C7G6" !CDS_LOCATION = "C7G6" &SEC = "1" #&CDS_SEC = "1";
"A":   PN = "1"  !CDS_PN = "1";
"B":   PN = "2"  !CDS_PN = "2";
BODY = "CAP","I7": #LOCATION = "C7G7" !CDS_LOCATION = "C7G7" #SEC = "1" !CDS_SEC = "1";
"A":   PN = "1"  !CDS_PN = "1";
"B":   PN = "2"  !CDS_PN = "2";
BODY = "CAP","I8": #LOCATION = "C7G10" !CDS_LOCATION = "C7G10" #SEC = "1" !CDS_SEC = "1";
"A":   PN = "1"  !CDS_PN = "1";
"B":   PN = "2"  !CDS_PN = "2";
BODY = "CAP","I12": #LOCATION = "C7G12" !CDS_LOCATION = "C7G12" #SEC = "1" !CDS_SEC = "1";
"A":   PN = "1"  !CDS_PN = "1";
"B":   PN = "2"  !CDS_PN = "2";
BODY = "CAP","I13": #LOCATION = "C7G13" !CDS_LOCATION = "C7G13" #SEC = "1" !CDS_SEC = "1";
"A":   PN = "1"  !CDS_PN = "1";
"B":   PN = "2"  !CDS_PN = "2";
BODY = "CAP","I20": #LOCATION = "C7G5" !CDS_LOCATION = "C7G5" #SEC = "1" !CDS_SEC = "1";
"A":   PN = "1"  !CDS_PN = "1";
"B":   PN = "2"  !CDS_PN = "2";
BODY = "CAP","I21": #LOCATION = "C7G9" !CDS_LOCATION = "C7G9" #SEC = "1" !CDS_SEC = "1";
"A":   PN = "1"  !CDS_PN = "1";
"B":   PN = "2"  !CDS_PN = "2";
BODY = "CAP","I22": #LOCATION = "C7G8" !CDS_LOCATION = "C7G8" #SEC = "1" !CDS_SEC = "1";
"A":   PN = "1"  !CDS_PN = "1";
"B":   PN = "2"  !CDS_PN = "2";
BODY = "CAP","I27": #LOCATION = "C7G11" !CDS_LOCATION = "C7G11" #SEC = "1" !CDS_SEC = "1";
"A":   PN = "1"  !CDS_PN = "1";
"B":   PN = "2"  !CDS_PN = "2";
BODY = "CAP","I28": #LOCATION = "C7G14" !CDS_LOCATION = "C7G14" #SEC = "1" !CDS_SEC = "1";
"A":   PN = "1"  !CDS_PN = "1";
"B":   PN = "2"  !CDS_PN = "2";
BODY = "CAP","I31": #LOCATION = "C7G16" !CDS_LOCATION = "C7G16" #SEC = "1" !CDS_SEC = "1";
"A":   PN = "1"  !CDS_PN = "1";
"B":   PN = "2"  !CDS_PN = "2";
BODY = "CAP","I32": #LOCATION = "C7G18" !CDS_LOCATION = "C7G18" #SEC = "1" !CDS_SEC = "1";
"A":   PN = "1"  !CDS_PN = "1";
"B":   PN = "2"  !CDS_PN = "2";
BODY = "CAP","I34": #LOCATION = "C7G20" !CDS_LOCATION = "C7G20" #SEC = "1" !CDS_SEC = "1";
"A":   PN = "1"  !CDS_PN = "1";
"B":   PN = "2"  !CDS_PN = "2";
BODY = "CAP","I37": #LOCATION = "C7G22" !CDS_LOCATION = "C7G22" #SEC = "1" !CDS_SEC = "1";
"A":   PN = "1"  !CDS_PN = "1";
"B":   PN = "2"  !CDS_PN = "2";
BODY = "CAP","I44": #LOCATION = "C7G17" !CDS_LOCATION = "C7G17" #SEC = "1" !CDS_SEC = "1";
"A":   PN = "1"  !CDS_PN = "1";
"B":   PN = "2"  !CDS_PN = "2";
BODY = "CAP","I45": #LOCATION = "C7G15" !CDS_LOCATION = "C7G15" #SEC = "1" !CDS_SEC = "1";
"A":   PN = "1"  !CDS_PN = "1";
"B":   PN = "2"  !CDS_PN = "2";
BODY = "CAP","I46": #LOCATION = "C7G19" !CDS_LOCATION = "C7G19" #SEC = "1" !CDS_SEC = "1";
"A":   PN = "1"  !CDS_PN = "1";
"B":   PN = "2"  !CDS_PN = "2";
BODY = "CAP","I51": #LOCATION = "C7G21" !CDS_LOCATION = "C7G21" #SEC = "1" !CDS_SEC = "1";
"A":   PN = "1"  !CDS_PN = "1";
"B":   PN = "2"  !CDS_PN = "2";
BODY = "CAP","I52": #LOCATION = "C7G23" !CDS_LOCATION = "C7G23" #SEC = "1" !CDS_SEC = "1";
"A":   PN = "1"  !CDS_PN = "1";
"B":   PN = "2"  !CDS_PN = "2";
BODY = "CAP","I55": #LOCATION = "C7G26" !CDS_LOCATION = "C7G26" #SEC = "1" !CDS_SEC = "1";
"A":   PN = "1"  !CDS_PN = "1";
"B":   PN = "2"  !CDS_PN = "2";
BODY = "CAP","I56": #LOCATION = "C8G4" !CDS_LOCATION = "C8G4" #SEC = "1" !CDS_SEC = "1";
"A":   PN = "1"  !CDS_PN = "1";
"B":   PN = "2"  !CDS_PN = "2";
BODY = "CAP","I58": #LOCATION = "C8G2" !CDS_LOCATION = "C8G2" #SEC = "1" !CDS_SEC = "1";
"A":   PN = "1"  !CDS_PN = "1";
"B":   PN = "2"  !CDS_PN = "2";
BODY = "CAP","I61": #LOCATION = "C8G6" !CDS_LOCATION = "C8G6" #SEC = "1" !CDS_SEC = "1";
"A":   PN = "1"  !CDS_PN = "1";
"B":   PN = "2"  !CDS_PN = "2";
BODY = "CAP","I62": #LOCATION = "C8G7" !CDS_LOCATION = "C8G7" #SEC = "1" !CDS_SEC = "1";
"A":   PN = "1"  !CDS_PN = "1";
"B":   PN = "2"  !CDS_PN = "2";
BODY = "CAP","I69": #LOCATION = "C7G25" !CDS_LOCATION = "C7G25" #SEC = "1" !CDS_SEC = "1";
"A":   PN = "1"  !CDS_PN = "1";
"B":   PN = "2"  !CDS_PN = "2";
BODY = "CAP","I70": #LOCATION = "C8G1" !CDS_LOCATION = "C8G1" #SEC = "1" !CDS_SEC = "1";
"A":   PN = "1"  !CDS_PN = "1";
"B":   PN = "2"  !CDS_PN = "2";
BODY = "CAP","I71": #LOCATION = "C8G3" !CDS_LOCATION = "C8G3" #SEC = "1" !CDS_SEC = "1";
"A":   PN = "1"  !CDS_PN = "1";
"B":   PN = "2"  !CDS_PN = "2";
BODY = "CAP","I75": #LOCATION = "C8G5" !CDS_LOCATION = "C8G5" #SEC = "1" !CDS_SEC = "1";
"A":   PN = "1"  !CDS_PN = "1";
"B":   PN = "2"  !CDS_PN = "2";
BODY = "CAP","I76": #LOCATION = "C8G8" !CDS_LOCATION = "C8G8" #SEC = "1" !CDS_SEC = "1";
"A":   PN = "1"  !CDS_PN = "1";
"B":   PN = "2"  !CDS_PN = "2";
BODY = "CAP","I93": #LOCATION = "C8G9" !CDS_LOCATION = "C8G9" #SEC = "1" !CDS_SEC = "1";
"A":   PN = "1"  !CDS_PN = "1";
"B":   PN = "2"  !CDS_PN = "2";
BODY = "CAP","I96": #LOCATION = "C8G10" !CDS_LOCATION = "C8G10" #SEC = "1" !CDS_SEC = "1";
"A":   PN = "1"  !CDS_PN = "1";
"B":   PN = "2"  !CDS_PN = "2";
BODY = "CAP","I153": #LOCATION = "C6B18" !CDS_LOCATION = "C6B18" #SEC = "1" !CDS_SEC = "1";
"A":   PN = "1"  !CDS_PN = "1";
"B":   PN = "2"  !CDS_PN = "2";
BODY = "CAP","I160": #LOCATION = "C6B19" !CDS_LOCATION = "C6B19" #SEC = "1" !CDS_SEC = "1";
"A":   PN = "1"  !CDS_PN = "1";
"B":   PN = "2"  !CDS_PN = "2";
BODY = "CAP","I163": #LOCATION = "C6B15" !CDS_LOCATION = "C6B15" #SEC = "1" !CDS_SEC = "1";
"A":   PN = "1"  !CDS_PN = "1";
"B":   PN = "2"  !CDS_PN = "2";
BODY = "CAP","I166": #LOCATION = "C6B11" !CDS_LOCATION = "C6B11" #SEC = "1" !CDS_SEC = "1";
"A":   PN = "1"  !CDS_PN = "1";
"B":   PN = "2"  !CDS_PN = "2";
BODY = "CAP","I169": #LOCATION = "C6B6" !CDS_LOCATION = "C6B6" #SEC = "1" !CDS_SEC = "1";
"A":   PN = "1"  !CDS_PN = "1";
"B":   PN = "2"  !CDS_PN = "2";
BODY = "CAP","I173": #LOCATION = "C6B20" !CDS_LOCATION = "C6B20" #SEC = "1" !CDS_SEC = "1";
"A":   PN = "1"  !CDS_PN = "1";
"B":   PN = "2"  !CDS_PN = "2";
BODY = "CAP","I175": #LOCATION = "C6B17" !CDS_LOCATION = "C6B17" #SEC = "1" !CDS_SEC = "1";
"A":   PN = "1"  !CDS_PN = "1";
"B":   PN = "2"  !CDS_PN = "2";
BODY = "CAP","I180": #LOCATION = "C6B16" !CDS_LOCATION = "C6B16" #SEC = "1" !CDS_SEC = "1";
"A":   PN = "1"  !CDS_PN = "1";
"B":   PN = "2"  !CDS_PN = "2";
BODY = "CAP","I181": #LOCATION = "C6B14" !CDS_LOCATION = "C6B14" #SEC = "1" !CDS_SEC = "1";
"A":   PN = "1"  !CDS_PN = "1";
"B":   PN = "2"  !CDS_PN = "2";
BODY = "CAP","I185": #LOCATION = "C6B9" !CDS_LOCATION = "C6B9" #SEC = "1" !CDS_SEC = "1";
"A":   PN = "1"  !CDS_PN = "1";
"B":   PN = "2"  !CDS_PN = "2";
BODY = "CAP","I187": #LOCATION = "C6B12" !CDS_LOCATION = "C6B12" #SEC = "1" !CDS_SEC = "1";
"A":   PN = "1"  !CDS_PN = "1";
"B":   PN = "2"  !CDS_PN = "2";
BODY = "CAP","I189": #LOCATION = "C6B13" !CDS_LOCATION = "C6B13" #SEC = "1" !CDS_SEC = "1";
"A":   PN = "1"  !CDS_PN = "1";
"B":   PN = "2"  !CDS_PN = "2";
BODY = "CAP","I193": #LOCATION = "C6B10" !CDS_LOCATION = "C6B10" #SEC = "1" !CDS_SEC = "1";
"A":   PN = "1"  !CDS_PN = "1";
"B":   PN = "2"  !CDS_PN = "2";
BODY = "CAP","I196": #LOCATION = "C6B4" !CDS_LOCATION = "C6B4" #SEC = "1" !CDS_SEC = "1";
"A":   PN = "1"  !CDS_PN = "1";
"B":   PN = "2"  !CDS_PN = "2";
BODY = "CAP","I198": #LOCATION = "C6B8" !CDS_LOCATION = "C6B8" #SEC = "1" !CDS_SEC = "1";
"A":   PN = "1"  !CDS_PN = "1";
"B":   PN = "2"  !CDS_PN = "2";
BODY = "CAP","I201": #LOCATION = "C6B5" !CDS_LOCATION = "C6B5" #SEC = "1" !CDS_SEC = "1";
"A":   PN = "1"  !CDS_PN = "1";
"B":   PN = "2"  !CDS_PN = "2";
BODY = "CAP","I205": #LOCATION = "C3M25" !CDS_LOCATION = "C3M25" &SEC = "1" #&CDS_SEC = "1";
"A":   PN = "1"  !CDS_PN = "1";
"B":   PN = "2"  !CDS_PN = "2";
BODY = "CAP","I206": #LOCATION = "C3M34" !CDS_LOCATION = "C3M34" &SEC = "1" #&CDS_SEC = "1";
"A":   PN = "1"  !CDS_PN = "1";
"B":   PN = "2"  !CDS_PN = "2";
BODY = "CAP","I212": #LOCATION = "C3M28" !CDS_LOCATION = "C3M28" &SEC = "1" #&CDS_SEC = "1";
"A":   PN = "1"  !CDS_PN = "1";
"B":   PN = "2"  !CDS_PN = "2";
BODY = "CAP","I217": #LOCATION = "C3M33" !CDS_LOCATION = "C3M33" &SEC = "1" #&CDS_SEC = "1";
"A":   PN = "1"  !CDS_PN = "1";
"B":   PN = "2"  !CDS_PN = "2";
BODY = "CAP","I218": #LOCATION = "C3M36" !CDS_LOCATION = "C3M36" &SEC = "1" #&CDS_SEC = "1";
"A":   PN = "1"  !CDS_PN = "1";
"B":   PN = "2"  !CDS_PN = "2";
BODY = "CAP","I223": #LOCATION = "C3M32" !CDS_LOCATION = "C3M32" &SEC = "1" #&CDS_SEC = "1";
"A":   PN = "1"  !CDS_PN = "1";
"B":   PN = "2"  !CDS_PN = "2";
BODY = "CAP","I225": #LOCATION = "C3M35" !CDS_LOCATION = "C3M35" &SEC = "1" #&CDS_SEC = "1";
"A":   PN = "1"  !CDS_PN = "1";
"B":   PN = "2"  !CDS_PN = "2";
BODY = "CAP","I229": #LOCATION = "C3M26" !CDS_LOCATION = "C3M26" &SEC = "1" #&CDS_SEC = "1";
"A":   PN = "1"  !CDS_PN = "1";
"B":   PN = "2"  !CDS_PN = "2";
BODY = "CAP","I232": #LOCATION = "C3M3" !CDS_LOCATION = "C3M3" &SEC = "1" #&CDS_SEC = "1";
"A":   PN = "1"  !CDS_PN = "1";
"B":   PN = "2"  !CDS_PN = "2";
BODY = "CAP","I234": #LOCATION = "C3M11" !CDS_LOCATION = "C3M11" &SEC = "1" #&CDS_SEC = "1";
"A":   PN = "1"  !CDS_PN = "1";
"B":   PN = "2"  !CDS_PN = "2";
BODY = "CAP","I239": #LOCATION = "C3M13" !CDS_LOCATION = "C3M13" &SEC = "1" #&CDS_SEC = "1";
"A":   PN = "1"  !CDS_PN = "1";
"B":   PN = "2"  !CDS_PN = "2";
BODY = "CAP","I244": #LOCATION = "C3M4" !CDS_LOCATION = "C3M4" &SEC = "1" #&CDS_SEC = "1";
"A":   PN = "1"  !CDS_PN = "1";
"B":   PN = "2"  !CDS_PN = "2";
BODY = "CAP","I246": #LOCATION = "C3M12" !CDS_LOCATION = "C3M12" &SEC = "1" #&CDS_SEC = "1";
"A":   PN = "1"  !CDS_PN = "1";
"B":   PN = "2"  !CDS_PN = "2";
BODY = "CAP","I247": #LOCATION = "C3M2" !CDS_LOCATION = "C3M2" &SEC = "1" #&CDS_SEC = "1";
"A":   PN = "1"  !CDS_PN = "1";
"B":   PN = "2"  !CDS_PN = "2";
BODY = "CAP","I253": #LOCATION = "C3M14" !CDS_LOCATION = "C3M14" &SEC = "1" #&CDS_SEC = "1";
"A":   PN = "1"  !CDS_PN = "1";
"B":   PN = "2"  !CDS_PN = "2";
BODY = "CAP","I255": #LOCATION = "C3M1" !CDS_LOCATION = "C3M1" &SEC = "1" #&CDS_SEC = "1";
"A":   PN = "1"  !CDS_PN = "1";
"B":   PN = "2"  !CDS_PN = "2";
DRAWING = "@baseboard_fab2_lib.baseboard_fab2(sch_1):page106";
BODY = "CAP","I10": #LOCATION = "C1R2" !CDS_LOCATION = "C1R2" &SEC = "1" #&CDS_SEC = "1";
"A":   PN = "1"  !CDS_PN = "1";
"B":   PN = "2"  !CDS_PN = "2";
BODY = "CAP","I26": #LOCATION = "C1R4" !CDS_LOCATION = "C1R4" &SEC = "1" #&CDS_SEC = "1";
"A":   PN = "1"  !CDS_PN = "1";
"B":   PN = "2"  !CDS_PN = "2";
BODY = "CAP","I29": #LOCATION = "C1R1" !CDS_LOCATION = "C1R1" &SEC = "1" #&CDS_SEC = "1";
"A":   PN = "1"  !CDS_PN = "1";
"B":   PN = "2"  !CDS_PN = "2";
BODY = "CAP","I37": #LOCATION = "C1R3" !CDS_LOCATION = "C1R3" &SEC = "1" #&CDS_SEC = "1";
"A":   PN = "1"  !CDS_PN = "1";
"B":   PN = "2"  !CDS_PN = "2";
BODY = "CAP","I40": #LOCATION = "C1R6" !CDS_LOCATION = "C1R6" &SEC = "1" #&CDS_SEC = "1";
"A":   PN = "1"  !CDS_PN = "1";
"B":   PN = "2"  !CDS_PN = "2";
BODY = "CAP","I55": #LOCATION = "C1R8" !CDS_LOCATION = "C1R8" &SEC = "1" #&CDS_SEC = "1";
"A":   PN = "1"  !CDS_PN = "1";
"B":   PN = "2"  !CDS_PN = "2";
BODY = "CAP","I59": #LOCATION = "C1R5" !CDS_LOCATION = "C1R5" &SEC = "1" #&CDS_SEC = "1";
"A":   PN = "1"  !CDS_PN = "1";
"B":   PN = "2"  !CDS_PN = "2";
BODY = "CAP","I70": #LOCATION = "C1R7" !CDS_LOCATION = "C1R7" &SEC = "1" #&CDS_SEC = "1";
"A":   PN = "1"  !CDS_PN = "1";
"B":   PN = "2"  !CDS_PN = "2";
BODY = "CAP","I76": #LOCATION = "C2M14" !CDS_LOCATION = "C2M14" &SEC = "1" #&CDS_SEC = "1";
"A":   PN = "1"  !CDS_PN = "1";
"B":   PN = "2"  !CDS_PN = "2";
BODY = "CAP","I78": #LOCATION = "C1M18" !CDS_LOCATION = "C1M18" &SEC = "1" #&CDS_SEC = "1";
"A":   PN = "1"  !CDS_PN = "1";
"B":   PN = "2"  !CDS_PN = "2";
BODY = "CAP","I82": #LOCATION = "C1M16" !CDS_LOCATION = "C1M16" &SEC = "1" #&CDS_SEC = "1";
"A":   PN = "1"  !CDS_PN = "1";
"B":   PN = "2"  !CDS_PN = "2";
BODY = "CAP","I85": #LOCATION = "C1M14" !CDS_LOCATION = "C1M14" &SEC = "1" #&CDS_SEC = "1";
"A":   PN = "1"  !CDS_PN = "1";
"B":   PN = "2"  !CDS_PN = "2";
BODY = "CAP","I86": #LOCATION = "C2M15" !CDS_LOCATION = "C2M15" &SEC = "1" #&CDS_SEC = "1";
"A":   PN = "1"  !CDS_PN = "1";
"B":   PN = "2"  !CDS_PN = "2";
BODY = "CAP","I90": #LOCATION = "C1M19" !CDS_LOCATION = "C1M19" &SEC = "1" #&CDS_SEC = "1";
"A":   PN = "1"  !CDS_PN = "1";
"B":   PN = "2"  !CDS_PN = "2";
BODY = "CAP","I92": #LOCATION = "C1M17" !CDS_LOCATION = "C1M17" &SEC = "1" #&CDS_SEC = "1";
"A":   PN = "1"  !CDS_PN = "1";
"B":   PN = "2"  !CDS_PN = "2";
BODY = "CAP","I95": #LOCATION = "C1M15" !CDS_LOCATION = "C1M15" &SEC = "1" #&CDS_SEC = "1";
"A":   PN = "1"  !CDS_PN = "1";
"B":   PN = "2"  !CDS_PN = "2";
BODY = "CAP","I100": #LOCATION = "C1M12" !CDS_LOCATION = "C1M12" &SEC = "1" #&CDS_SEC = "1";
"A":   PN = "1"  !CDS_PN = "1";
"B":   PN = "2"  !CDS_PN = "2";
BODY = "CAP","I102": #LOCATION = "C1M10" !CDS_LOCATION = "C1M10" &SEC = "1" #&CDS_SEC = "1";
"A":   PN = "1"  !CDS_PN = "1";
"B":   PN = "2"  !CDS_PN = "2";
BODY = "CAP","I105": #LOCATION = "C1M8" !CDS_LOCATION = "C1M8" &SEC = "1" #&CDS_SEC = "1";
"A":   PN = "1"  !CDS_PN = "1";
"B":   PN = "2"  !CDS_PN = "2";
BODY = "CAP","I109": #LOCATION = "C1M6" !CDS_LOCATION = "C1M6" &SEC = "1" #&CDS_SEC = "1";
"A":   PN = "1"  !CDS_PN = "1";
"B":   PN = "2"  !CDS_PN = "2";
BODY = "CAP","I111": #LOCATION = "C1M13" !CDS_LOCATION = "C1M13" &SEC = "1" #&CDS_SEC = "1";
"A":   PN = "1"  !CDS_PN = "1";
"B":   PN = "2"  !CDS_PN = "2";
BODY = "CAP","I114": #LOCATION = "C1M9" !CDS_LOCATION = "C1M9" &SEC = "1" #&CDS_SEC = "1";
"A":   PN = "1"  !CDS_PN = "1";
"B":   PN = "2"  !CDS_PN = "2";
BODY = "CAP","I117": #LOCATION = "C1M11" !CDS_LOCATION = "C1M11" &SEC = "1" #&CDS_SEC = "1";
"A":   PN = "1"  !CDS_PN = "1";
"B":   PN = "2"  !CDS_PN = "2";
BODY = "CAP","I122": #LOCATION = "C1M7" !CDS_LOCATION = "C1M7" &SEC = "1" #&CDS_SEC = "1";
"A":   PN = "1"  !CDS_PN = "1";
"B":   PN = "2"  !CDS_PN = "2";
BODY = "CAP","I123": #LOCATION = "C2R7" !CDS_LOCATION = "C2R7" &SEC = "1" #&CDS_SEC = "1";
"A":   PN = "1"  !CDS_PN = "1";
"B":   PN = "2"  !CDS_PN = "2";
BODY = "CAP","I128": #LOCATION = "C1R10" !CDS_LOCATION = "C1R10" &SEC = "1" #&CDS_SEC = "1";
"A":   PN = "1"  !CDS_PN = "1";
"B":   PN = "2"  !CDS_PN = "2";
BODY = "CAP","I130": #LOCATION = "C2R14" !CDS_LOCATION = "C2R14" &SEC = "1" #&CDS_SEC = "1";
"A":   PN = "1"  !CDS_PN = "1";
"B":   PN = "2"  !CDS_PN = "2";
BODY = "CAP","I134": #LOCATION = "C1R9" !CDS_LOCATION = "C1R9" &SEC = "1" #&CDS_SEC = "1";
"A":   PN = "1"  !CDS_PN = "1";
"B":   PN = "2"  !CDS_PN = "2";
BODY = "CAP","I137": #LOCATION = "C2R13" !CDS_LOCATION = "C2R13" &SEC = "1" #&CDS_SEC = "1";
"A":   PN = "1"  !CDS_PN = "1";
"B":   PN = "2"  !CDS_PN = "2";
BODY = "CAP","I141": #LOCATION = "C2R8" !CDS_LOCATION = "C2R8" &SEC = "1" #&CDS_SEC = "1";
"A":   PN = "1"  !CDS_PN = "1";
"B":   PN = "2"  !CDS_PN = "2";
BODY = "CAP","I142": #LOCATION = "C2R10" !CDS_LOCATION = "C2R10" &SEC = "1" #&CDS_SEC = "1";
"A":   PN = "1"  !CDS_PN = "1";
"B":   PN = "2"  !CDS_PN = "2";
BODY = "CAP","I147": #LOCATION = "C2R9" !CDS_LOCATION = "C2R9" &SEC = "1" #&CDS_SEC = "1";
"A":   PN = "1"  !CDS_PN = "1";
"B":   PN = "2"  !CDS_PN = "2";
DRAWING = "@baseboard_fab2_lib.baseboard_fab2(sch_1):page107";
BODY = "CAP","I207": #LOCATION = "C3P13" !CDS_LOCATION = "C3P13" &SEC = "1" #&CDS_SEC = "1";
"A":   PN = "1"  !CDS_PN = "1";
"B":   PN = "2"  !CDS_PN = "2";
BODY = "CAP","I208": #LOCATION = "C3P17" !CDS_LOCATION = "C3P17" &SEC = "1" #&CDS_SEC = "1";
"A":   PN = "1"  !CDS_PN = "1";
"B":   PN = "2"  !CDS_PN = "2";
BODY = "CAP","I212": #LOCATION = "C3P11" !CDS_LOCATION = "C3P11" &SEC = "1" #&CDS_SEC = "1";
"A":   PN = "1"  !CDS_PN = "1";
"B":   PN = "2"  !CDS_PN = "2";
BODY = "CAP","I215": #LOCATION = "C3P20" !CDS_LOCATION = "C3P20" &SEC = "1" #&CDS_SEC = "1";
"A":   PN = "1"  !CDS_PN = "1";
"B":   PN = "2"  !CDS_PN = "2";
BODY = "CAP","I216": #LOCATION = "C3P25" !CDS_LOCATION = "C3P25" &SEC = "1" #&CDS_SEC = "1";
"A":   PN = "1"  !CDS_PN = "1";
"B":   PN = "2"  !CDS_PN = "2";
BODY = "CAP","I219": #LOCATION = "C3P18" !CDS_LOCATION = "C3P18" &SEC = "1" #&CDS_SEC = "1";
"A":   PN = "1"  !CDS_PN = "1";
"B":   PN = "2"  !CDS_PN = "2";
BODY = "CAP","I223": #LOCATION = "C3P27" !CDS_LOCATION = "C3P27" &SEC = "1" #&CDS_SEC = "1";
"A":   PN = "1"  !CDS_PN = "1";
"B":   PN = "2"  !CDS_PN = "2";
BODY = "CAP","I226": #LOCATION = "C3P15" !CDS_LOCATION = "C3P15" &SEC = "1" #&CDS_SEC = "1";
"A":   PN = "1"  !CDS_PN = "1";
"B":   PN = "2"  !CDS_PN = "2";
BODY = "CAP","I229": #LOCATION = "C3P23" !CDS_LOCATION = "C3P23" &SEC = "1" #&CDS_SEC = "1";
"A":   PN = "1"  !CDS_PN = "1";
"B":   PN = "2"  !CDS_PN = "2";
BODY = "CAP","I232": #LOCATION = "C3P28" !CDS_LOCATION = "C3P28" &SEC = "1" #&CDS_SEC = "1";
"A":   PN = "1"  !CDS_PN = "1";
"B":   PN = "2"  !CDS_PN = "2";
BODY = "CAP","I234": #LOCATION = "C3P32" !CDS_LOCATION = "C3P32" &SEC = "1" #&CDS_SEC = "1";
"A":   PN = "1"  !CDS_PN = "1";
"B":   PN = "2"  !CDS_PN = "2";
BODY = "CAP","I235": #LOCATION = "C3P37" !CDS_LOCATION = "C3P37" &SEC = "1" #&CDS_SEC = "1";
"A":   PN = "1"  !CDS_PN = "1";
"B":   PN = "2"  !CDS_PN = "2";
BODY = "CAP","I240": #LOCATION = "C3P35" !CDS_LOCATION = "C3P35" &SEC = "1" #&CDS_SEC = "1";
"A":   PN = "1"  !CDS_PN = "1";
"B":   PN = "2"  !CDS_PN = "2";
BODY = "CAP","I241": #LOCATION = "C3P40" !CDS_LOCATION = "C3P40" &SEC = "1" #&CDS_SEC = "1";
"A":   PN = "1"  !CDS_PN = "1";
"B":   PN = "2"  !CDS_PN = "2";
BODY = "CAP","I245": #LOCATION = "C3P30" !CDS_LOCATION = "C3P30" &SEC = "1" #&CDS_SEC = "1";
"A":   PN = "1"  !CDS_PN = "1";
"B":   PN = "2"  !CDS_PN = "2";
BODY = "CAP","I248": #LOCATION = "C3P39" !CDS_LOCATION = "C3P39" &SEC = "1" #&CDS_SEC = "1";
"A":   PN = "1"  !CDS_PN = "1";
"B":   PN = "2"  !CDS_PN = "2";
BODY = "CAP","I257": #LOCATION = "C2U4" !CDS_LOCATION = "C2U4" #SEC = "1" !CDS_SEC = "1";
"A":   PN = "1"  !CDS_PN = "1";
"B":   PN = "2"  !CDS_PN = "2";
BODY = "CAP","I260": #LOCATION = "C2U6" !CDS_LOCATION = "C2U6" #SEC = "1" !CDS_SEC = "1";
"A":   PN = "1"  !CDS_PN = "1";
"B":   PN = "2"  !CDS_PN = "2";
BODY = "CAP","I264": #LOCATION = "C2U8" !CDS_LOCATION = "C2U8" #SEC = "1" !CDS_SEC = "1";
"A":   PN = "1"  !CDS_PN = "1";
"B":   PN = "2"  !CDS_PN = "2";
BODY = "CAP","I265": #LOCATION = "C2U12" !CDS_LOCATION = "C2U12" #SEC = "1" !CDS_SEC = "1";
"A":   PN = "1"  !CDS_PN = "1";
"B":   PN = "2"  !CDS_PN = "2";
BODY = "CAP","I267": #LOCATION = "C2U10" !CDS_LOCATION = "C2U10" #SEC = "1" !CDS_SEC = "1";
"A":   PN = "1"  !CDS_PN = "1";
"B":   PN = "2"  !CDS_PN = "2";
BODY = "CAP","I272": #LOCATION = "C2U3" !CDS_LOCATION = "C2U3" #SEC = "1" !CDS_SEC = "1";
"A":   PN = "1"  !CDS_PN = "1";
"B":   PN = "2"  !CDS_PN = "2";
BODY = "CAP","I274": #LOCATION = "C2U5" !CDS_LOCATION = "C2U5" #SEC = "1" !CDS_SEC = "1";
"A":   PN = "1"  !CDS_PN = "1";
"B":   PN = "2"  !CDS_PN = "2";
BODY = "CAP","I277": #LOCATION = "C2U7" !CDS_LOCATION = "C2U7" #SEC = "1" !CDS_SEC = "1";
"A":   PN = "1"  !CDS_PN = "1";
"B":   PN = "2"  !CDS_PN = "2";
BODY = "CAP","I278": #LOCATION = "C2U11" !CDS_LOCATION = "C2U11" #SEC = "1" !CDS_SEC = "1";
"A":   PN = "1"  !CDS_PN = "1";
"B":   PN = "2"  !CDS_PN = "2";
BODY = "CAP","I279": #LOCATION = "C2U9" !CDS_LOCATION = "C2U9" #SEC = "1" !CDS_SEC = "1";
"A":   PN = "1"  !CDS_PN = "1";
"B":   PN = "2"  !CDS_PN = "2";
BODY = "CAP","I286": #LOCATION = "C2U16" !CDS_LOCATION = "C2U16" #SEC = "1" !CDS_SEC = "1";
"A":   PN = "1"  !CDS_PN = "1";
"B":   PN = "2"  !CDS_PN = "2";
BODY = "CAP","I287": #LOCATION = "C2U14" !CDS_LOCATION = "C2U14" #SEC = "1" !CDS_SEC = "1";
"A":   PN = "1"  !CDS_PN = "1";
"B":   PN = "2"  !CDS_PN = "2";
BODY = "CAP","I294": #LOCATION = "C2U18" !CDS_LOCATION = "C2U18" #SEC = "1" !CDS_SEC = "1";
"A":   PN = "1"  !CDS_PN = "1";
"B":   PN = "2"  !CDS_PN = "2";
BODY = "CAP","I296": #LOCATION = "C2U15" !CDS_LOCATION = "C2U15" #SEC = "1" !CDS_SEC = "1";
"A":   PN = "1"  !CDS_PN = "1";
"B":   PN = "2"  !CDS_PN = "2";
BODY = "CAP","I297": #LOCATION = "C2U13" !CDS_LOCATION = "C2U13" #SEC = "1" !CDS_SEC = "1";
"A":   PN = "1"  !CDS_PN = "1";
"B":   PN = "2"  !CDS_PN = "2";
BODY = "CAP","I300": #LOCATION = "C2U17" !CDS_LOCATION = "C2U17" #SEC = "1" !CDS_SEC = "1";
"A":   PN = "1"  !CDS_PN = "1";
"B":   PN = "2"  !CDS_PN = "2";
BODY = "CAP","I415": #LOCATION = "C3P12" !CDS_LOCATION = "C3P12" &SEC = "1" #&CDS_SEC = "1";
"A":   PN = "1"  !CDS_PN = "1";
"B":   PN = "2"  !CDS_PN = "2";
BODY = "CAP","I417": #LOCATION = "C3P10" !CDS_LOCATION = "C3P10" &SEC = "1" #&CDS_SEC = "1";
"A":   PN = "1"  !CDS_PN = "1";
"B":   PN = "2"  !CDS_PN = "2";
BODY = "CAP","I422": #LOCATION = "C3P16" !CDS_LOCATION = "C3P16" &SEC = "1" #&CDS_SEC = "1";
"A":   PN = "1"  !CDS_PN = "1";
"B":   PN = "2"  !CDS_PN = "2";
BODY = "CAP","I423": #LOCATION = "C3P21" !CDS_LOCATION = "C3P21" &SEC = "1" #&CDS_SEC = "1";
"A":   PN = "1"  !CDS_PN = "1";
"B":   PN = "2"  !CDS_PN = "2";
BODY = "CAP","I424": #LOCATION = "C3P24" !CDS_LOCATION = "C3P24" &SEC = "1" #&CDS_SEC = "1";
"A":   PN = "1"  !CDS_PN = "1";
"B":   PN = "2"  !CDS_PN = "2";
BODY = "CAP","I427": #LOCATION = "C3P19" !CDS_LOCATION = "C3P19" &SEC = "1" #&CDS_SEC = "1";
"A":   PN = "1"  !CDS_PN = "1";
"B":   PN = "2"  !CDS_PN = "2";
BODY = "CAP","I431": #LOCATION = "C3P14" !CDS_LOCATION = "C3P14" &SEC = "1" #&CDS_SEC = "1";
"A":   PN = "1"  !CDS_PN = "1";
"B":   PN = "2"  !CDS_PN = "2";
BODY = "CAP","I435": #LOCATION = "C3P22" !CDS_LOCATION = "C3P22" &SEC = "1" #&CDS_SEC = "1";
"A":   PN = "1"  !CDS_PN = "1";
"B":   PN = "2"  !CDS_PN = "2";
BODY = "CAP","I437": #LOCATION = "C3P29" !CDS_LOCATION = "C3P29" &SEC = "1" #&CDS_SEC = "1";
"A":   PN = "1"  !CDS_PN = "1";
"B":   PN = "2"  !CDS_PN = "2";
BODY = "CAP","I438": #LOCATION = "C3P36" !CDS_LOCATION = "C3P36" &SEC = "1" #&CDS_SEC = "1";
"A":   PN = "1"  !CDS_PN = "1";
"B":   PN = "2"  !CDS_PN = "2";
BODY = "CAP","I439": #LOCATION = "C3P33" !CDS_LOCATION = "C3P33" &SEC = "1" #&CDS_SEC = "1";
"A":   PN = "1"  !CDS_PN = "1";
"B":   PN = "2"  !CDS_PN = "2";
BODY = "CAP","I444": #LOCATION = "C3P26" !CDS_LOCATION = "C3P26" &SEC = "1" #&CDS_SEC = "1";
"A":   PN = "1"  !CDS_PN = "1";
"B":   PN = "2"  !CDS_PN = "2";
BODY = "CAP","I447": #LOCATION = "C3P34" !CDS_LOCATION = "C3P34" &SEC = "1" #&CDS_SEC = "1";
"A":   PN = "1"  !CDS_PN = "1";
"B":   PN = "2"  !CDS_PN = "2";
BODY = "CAP","I448": #LOCATION = "C3P41" !CDS_LOCATION = "C3P41" &SEC = "1" #&CDS_SEC = "1";
"A":   PN = "1"  !CDS_PN = "1";
"B":   PN = "2"  !CDS_PN = "2";
BODY = "CAP","I452": #LOCATION = "C3P31" !CDS_LOCATION = "C3P31" &SEC = "1" #&CDS_SEC = "1";
"A":   PN = "1"  !CDS_PN = "1";
"B":   PN = "2"  !CDS_PN = "2";
BODY = "CAP","I455": #LOCATION = "C3P38" !CDS_LOCATION = "C3P38" &SEC = "1" #&CDS_SEC = "1";
"A":   PN = "1"  !CDS_PN = "1";
"B":   PN = "2"  !CDS_PN = "2";
BODY = "RES","I458": #LOCATION = "R2U29" !CDS_LOCATION = "R2U29" &SEC = "1" #&CDS_SEC = "1";
"A":   PN = "1"  !CDS_PN = "1";
"B":   PN = "2"  !CDS_PN = "2";
BODY = "RES","I459": #LOCATION = "R2U27" !CDS_LOCATION = "R2U27" &SEC = "1" #&CDS_SEC = "1";
"A":   PN = "1"  !CDS_PN = "1";
"B":   PN = "2"  !CDS_PN = "2";
BODY = "RES","I460": #LOCATION = "R2U25" !CDS_LOCATION = "R2U25" &SEC = "1" #&CDS_SEC = "1";
"A":   PN = "1"  !CDS_PN = "1";
"B":   PN = "2"  !CDS_PN = "2";
BODY = "RES","I461": #LOCATION = "R2U23" !CDS_LOCATION = "R2U23" &SEC = "1" #&CDS_SEC = "1";
"A":   PN = "1"  !CDS_PN = "1";
"B":   PN = "2"  !CDS_PN = "2";
BODY = "RES","I462": #LOCATION = "R2U21" !CDS_LOCATION = "R2U21" &SEC = "1" #&CDS_SEC = "1";
"A":   PN = "1"  !CDS_PN = "1";
"B":   PN = "2"  !CDS_PN = "2";
BODY = "RES","I463": #LOCATION = "R2U19" !CDS_LOCATION = "R2U19" &SEC = "1" #&CDS_SEC = "1";
"A":   PN = "1"  !CDS_PN = "1";
"B":   PN = "2"  !CDS_PN = "2";
BODY = "RES","I464": #LOCATION = "R2U17" !CDS_LOCATION = "R2U17" &SEC = "1" #&CDS_SEC = "1";
"A":   PN = "1"  !CDS_PN = "1";
"B":   PN = "2"  !CDS_PN = "2";
BODY = "RES","I465": #LOCATION = "R2U15" !CDS_LOCATION = "R2U15" &SEC = "1" #&CDS_SEC = "1";
"A":   PN = "1"  !CDS_PN = "1";
"B":   PN = "2"  !CDS_PN = "2";
BODY = "RES","I466": #LOCATION = "R2U14" !CDS_LOCATION = "R2U14" &SEC = "1" #&CDS_SEC = "1";
"A":   PN = "1"  !CDS_PN = "1";
"B":   PN = "2"  !CDS_PN = "2";
BODY = "RES","I467": #LOCATION = "R2U16" !CDS_LOCATION = "R2U16" &SEC = "1" #&CDS_SEC = "1";
"A":   PN = "1"  !CDS_PN = "1";
"B":   PN = "2"  !CDS_PN = "2";
BODY = "RES","I468": #LOCATION = "R2U18" !CDS_LOCATION = "R2U18" &SEC = "1" #&CDS_SEC = "1";
"A":   PN = "1"  !CDS_PN = "1";
"B":   PN = "2"  !CDS_PN = "2";
BODY = "RES","I469": #LOCATION = "R2U20" !CDS_LOCATION = "R2U20" &SEC = "1" #&CDS_SEC = "1";
"A":   PN = "1"  !CDS_PN = "1";
"B":   PN = "2"  !CDS_PN = "2";
BODY = "RES","I470": #LOCATION = "R2U22" !CDS_LOCATION = "R2U22" &SEC = "1" #&CDS_SEC = "1";
"A":   PN = "1"  !CDS_PN = "1";
"B":   PN = "2"  !CDS_PN = "2";
BODY = "RES","I471": #LOCATION = "R2U24" !CDS_LOCATION = "R2U24" &SEC = "1" #&CDS_SEC = "1";
"A":   PN = "1"  !CDS_PN = "1";
"B":   PN = "2"  !CDS_PN = "2";
BODY = "RES","I472": #LOCATION = "R2U26" !CDS_LOCATION = "R2U26" &SEC = "1" #&CDS_SEC = "1";
"A":   PN = "1"  !CDS_PN = "1";
"B":   PN = "2"  !CDS_PN = "2";
BODY = "RES","I473": #LOCATION = "R2U28" !CDS_LOCATION = "R2U28" &SEC = "1" #&CDS_SEC = "1";
"A":   PN = "1"  !CDS_PN = "1";
"B":   PN = "2"  !CDS_PN = "2";
DRAWING = "@baseboard_fab2_lib.baseboard_fab2(sch_1):page108";
BODY = "CAP_A","I1": #LOCATION = "C2U20" !CDS_LOCATION = "C2U20" #SEC = "1" !CDS_SEC = "1";
"A":   PN = "1"  !CDS_PN = "1";
"B":   PN = "2"  !CDS_PN = "2";
BODY = "CAP_A","I2": #LOCATION = "C2U24" !CDS_LOCATION = "C2U24" #SEC = "1" !CDS_SEC = "1";
"A":   PN = "1"  !CDS_PN = "1";
"B":   PN = "2"  !CDS_PN = "2";
BODY = "CAP_A","I5": #LOCATION = "C2U21" !CDS_LOCATION = "C2U21" #SEC = "1" !CDS_SEC = "1";
"A":   PN = "1"  !CDS_PN = "1";
"B":   PN = "2"  !CDS_PN = "2";
BODY = "CAP_A","I7": #LOCATION = "C2U25" !CDS_LOCATION = "C2U25" #SEC = "1" !CDS_SEC = "1";
"A":   PN = "1"  !CDS_PN = "1";
"B":   PN = "2"  !CDS_PN = "2";
BODY = "RES","I173": #LOCATION = "R2U37" !CDS_LOCATION = "R2U37" #SEC = "1" !CDS_SEC = "1";
"A":   PN = "1"  !CDS_PN = "1";
"B":   PN = "2"  !CDS_PN = "2";
BODY = "SCONN200_H68296001","I258": #LOCATION = "J8G1" !CDS_LOCATION = "J8G1" #SEC = "1" !CDS_SEC = "1";
"IO1":   PN = "1"  !CDS_PN = "1";
"IO2":   PN = "2"  !CDS_PN = "2";
"IO3":   PN = "3"  !CDS_PN = "3";
"IO4":   PN = "4"  !CDS_PN = "4";
"IO5":   PN = "5"  !CDS_PN = "5";
"IO6":   PN = "6"  !CDS_PN = "6";
"IO7":   PN = "7"  !CDS_PN = "7";
"IO8":   PN = "8"  !CDS_PN = "8";
"IO9":   PN = "9"  !CDS_PN = "9";
"IO10":   PN = "10"  !CDS_PN = "10";
"IO11":   PN = "11"  !CDS_PN = "11";
"IO12":   PN = "12"  !CDS_PN = "12";
"IO13":   PN = "13"  !CDS_PN = "13";
"IO14":   PN = "14"  !CDS_PN = "14";
"IO15":   PN = "15"  !CDS_PN = "15";
"IO16":   PN = "16"  !CDS_PN = "16";
"IO17":   PN = "17"  !CDS_PN = "17";
"IO18":   PN = "18"  !CDS_PN = "18";
"IO19":   PN = "19"  !CDS_PN = "19";
"IO20":   PN = "20"  !CDS_PN = "20";
"IO21":   PN = "21"  !CDS_PN = "21";
"IO22":   PN = "22"  !CDS_PN = "22";
"IO23":   PN = "23"  !CDS_PN = "23";
"IO24":   PN = "24"  !CDS_PN = "24";
"IO25":   PN = "25"  !CDS_PN = "25";
"IO26":   PN = "26"  !CDS_PN = "26";
"IO27":   PN = "27"  !CDS_PN = "27";
"IO28":   PN = "28"  !CDS_PN = "28";
"IO29":   PN = "29"  !CDS_PN = "29";
"IO30":   PN = "30"  !CDS_PN = "30";
"IO31":   PN = "31"  !CDS_PN = "31";
"IO32":   PN = "32"  !CDS_PN = "32";
"IO33":   PN = "33"  !CDS_PN = "33";
"IO34":   PN = "34"  !CDS_PN = "34";
"IO35":   PN = "35"  !CDS_PN = "35";
"IO36":   PN = "36"  !CDS_PN = "36";
"IO37":   PN = "37"  !CDS_PN = "37";
"IO38":   PN = "38"  !CDS_PN = "38";
"IO39":   PN = "39"  !CDS_PN = "39";
"IO40":   PN = "40"  !CDS_PN = "40";
"IO41":   PN = "41"  !CDS_PN = "41";
"IO42":   PN = "42"  !CDS_PN = "42";
"IO43":   PN = "43"  !CDS_PN = "43";
"IO44":   PN = "44"  !CDS_PN = "44";
"IO45":   PN = "45"  !CDS_PN = "45";
"IO46":   PN = "46"  !CDS_PN = "46";
"IO47":   PN = "47"  !CDS_PN = "47";
"IO48":   PN = "48"  !CDS_PN = "48";
"IO49":   PN = "49"  !CDS_PN = "49";
"IO50":   PN = "50"  !CDS_PN = "50";
"IO51":   PN = "51"  !CDS_PN = "51";
"IO52":   PN = "52"  !CDS_PN = "52";
"IO53":   PN = "53"  !CDS_PN = "53";
"IO54":   PN = "54"  !CDS_PN = "54";
"IO55":   PN = "55"  !CDS_PN = "55";
"IO56":   PN = "56"  !CDS_PN = "56";
"IO57":   PN = "57"  !CDS_PN = "57";
"IO58":   PN = "58"  !CDS_PN = "58";
"IO59":   PN = "59"  !CDS_PN = "59";
"IO60":   PN = "60"  !CDS_PN = "60";
"IO61":   PN = "61"  !CDS_PN = "61";
"IO62":   PN = "62"  !CDS_PN = "62";
"IO63":   PN = "63"  !CDS_PN = "63";
"IO64":   PN = "64"  !CDS_PN = "64";
"IO65":   PN = "65"  !CDS_PN = "65";
"IO66":   PN = "66"  !CDS_PN = "66";
"IO67":   PN = "67"  !CDS_PN = "67";
"IO68":   PN = "68"  !CDS_PN = "68";
"IO69":   PN = "69"  !CDS_PN = "69";
"IO70":   PN = "70"  !CDS_PN = "70";
"IO71":   PN = "71"  !CDS_PN = "71";
"IO72":   PN = "72"  !CDS_PN = "72";
"IO73":   PN = "73"  !CDS_PN = "73";
"IO74":   PN = "74"  !CDS_PN = "74";
"IO75":   PN = "75"  !CDS_PN = "75";
"IO76":   PN = "76"  !CDS_PN = "76";
"IO77":   PN = "77"  !CDS_PN = "77";
"IO78":   PN = "78"  !CDS_PN = "78";
"IO79":   PN = "79"  !CDS_PN = "79";
"IO80":   PN = "80"  !CDS_PN = "80";
"IO81":   PN = "81"  !CDS_PN = "81";
"IO82":   PN = "82"  !CDS_PN = "82";
"IO83":   PN = "83"  !CDS_PN = "83";
"IO84":   PN = "84"  !CDS_PN = "84";
"IO85":   PN = "85"  !CDS_PN = "85";
"IO86":   PN = "86"  !CDS_PN = "86";
"IO87":   PN = "87"  !CDS_PN = "87";
"IO88":   PN = "88"  !CDS_PN = "88";
"IO89":   PN = "89"  !CDS_PN = "89";
"IO90":   PN = "90"  !CDS_PN = "90";
"IO91":   PN = "91"  !CDS_PN = "91";
"IO92":   PN = "92"  !CDS_PN = "92";
"IO93":   PN = "93"  !CDS_PN = "93";
"IO94":   PN = "94"  !CDS_PN = "94";
"IO95":   PN = "95"  !CDS_PN = "95";
"IO96":   PN = "96"  !CDS_PN = "96";
"IO97":   PN = "97"  !CDS_PN = "97";
"IO98":   PN = "98"  !CDS_PN = "98";
"IO99":   PN = "99"  !CDS_PN = "99";
"IO100":   PN = "100"  !CDS_PN = "100";
"MH1":   PN = "MH1"  !CDS_PN = "MH1";
"MH2":   PN = "MH2"  !CDS_PN = "MH2";
BODY = "CAP_A","I315": #LOCATION = "C2U23" !CDS_LOCATION = "C2U23" #SEC = "1" !CDS_SEC = "1";
"A":   PN = "1"  !CDS_PN = "1";
"B":   PN = "2"  !CDS_PN = "2";
BODY = "CAP_A","I318": #LOCATION = "C2U22" !CDS_LOCATION = "C2U22" #SEC = "1" !CDS_SEC = "1";
"A":   PN = "1"  !CDS_PN = "1";
"B":   PN = "2"  !CDS_PN = "2";
BODY = "RES","I320": #LOCATION = "R2U35" !CDS_LOCATION = "R2U35" &SEC = "1" #&CDS_SEC = "1";
"A":   PN = "1"  !CDS_PN = "1";
"B":   PN = "2"  !CDS_PN = "2";
BODY = "RES","I330": #LOCATION = "R2U31" !CDS_LOCATION = "R2U31" &SEC = "1" #&CDS_SEC = "1";
"A":   PN = "1"  !CDS_PN = "1";
"B":   PN = "2"  !CDS_PN = "2";
BODY = "RES","I339": #LOCATION = "R2U32" !CDS_LOCATION = "R2U32" &SEC = "1" #&CDS_SEC = "1";
"A":   PN = "1"  !CDS_PN = "1";
"B":   PN = "2"  !CDS_PN = "2";
BODY = "RES","I340": #LOCATION = "R2U36" !CDS_LOCATION = "R2U36" &SEC = "1" #&CDS_SEC = "1";
"A":   PN = "1"  !CDS_PN = "1";
"B":   PN = "2"  !CDS_PN = "2";
BODY = "RES","I341": #LOCATION = "R7E22" !CDS_LOCATION = "R7E22" #SEC = "1" !CDS_SEC = "1";
"A":   PN = "1"  !CDS_PN = "1";
"B":   PN = "2"  !CDS_PN = "2";
BODY = "RES","I343": #LOCATION = "R7E21" !CDS_LOCATION = "R7E21" #SEC = "1" !CDS_SEC = "1";
"A":   PN = "1"  !CDS_PN = "1";
"B":   PN = "2"  !CDS_PN = "2";
DRAWING = "@baseboard_fab2_lib.baseboard_fab2(sch_1):page110";
BODY = "RCC_DFX1940","I1": #LOCATION = "TC9F1" !CDS_LOCATION = "TC9F1" &SEC = "1" #&CDS_SEC = "1";
"GND":   PN = "1"  !CDS_PN = "1";
"IO1":   PN = "2"  !CDS_PN = "2";
"IO2":   PN = "3"  !CDS_PN = "3";
BODY = "RCC_DFX1940","I3": #LOCATION = "TC1G1" !CDS_LOCATION = "TC1G1" &SEC = "1" #&CDS_SEC = "1";
"GND":   PN = "1"  !CDS_PN = "1";
"IO1":   PN = "2"  !CDS_PN = "2";
"IO2":   PN = "3"  !CDS_PN = "3";
BODY = "RCC_DFX1940","I7": #LOCATION = "TC1A1" !CDS_LOCATION = "TC1A1" &SEC = "1" #&CDS_SEC = "1";
"GND":   PN = "1"  !CDS_PN = "1";
"IO1":   PN = "2"  !CDS_PN = "2";
"IO2":   PN = "3"  !CDS_PN = "3";
BODY = "RCC_DFX1940","I9": #LOCATION = "TC9A1" !CDS_LOCATION = "TC9A1" &SEC = "1" #&CDS_SEC = "1";
"GND":   PN = "1"  !CDS_PN = "1";
"IO1":   PN = "2"  !CDS_PN = "2";
"IO2":   PN = "3"  !CDS_PN = "3";
BODY = "SNLABEL_A","I11": #LOCATION = "LB2F1" !CDS_LOCATION = "LB2F1";
BODY = "SNLABEL_A","I12": #LOCATION = "LB5F1" !CDS_LOCATION = "LB5F1";
BODY = "SNLABEL_A","I13": #LOCATION = "LB2B1" !CDS_LOCATION = "LB2B1";
BODY = "SNLABEL_A","I14": #LOCATION = "LB5B1" !CDS_LOCATION = "LB5B1";
BODY = "SNLABEL_A","I15": #LOCATION = "LB6T1" !CDS_LOCATION = "LB6T1";
DRAWING = "@baseboard_fab2_lib.baseboard_fab2(sch_1):page111";
BODY = "RES","I6": #LOCATION = "R1L13" !CDS_LOCATION = "R1L13" #SEC = "1" !CDS_SEC = "1";
"A":   PN = "1"  !CDS_PN = "1";
"B":   PN = "2"  !CDS_PN = "2";
BODY = "CAP_A","I10": #LOCATION = "C9A2" !CDS_LOCATION = "C9A2" #SEC = "1" !CDS_SEC = "1";
"A":   PN = "1"  !CDS_PN = "1";
"B":   PN = "2"  !CDS_PN = "2";
BODY = "RES","I11": #LOCATION = "R9A14" !CDS_LOCATION = "R9A14" #SEC = "1" !CDS_SEC = "1";
"A":   PN = "1"  !CDS_PN = "1";
"B":   PN = "2"  !CDS_PN = "2";
BODY = "CAP_A","I12": #LOCATION = "C9A5" !CDS_LOCATION = "C9A5" #SEC = "1" !CDS_SEC = "1";
"A":   PN = "1"  !CDS_PN = "1";
"B":   PN = "2"  !CDS_PN = "2";
BODY = "RES","I13": #LOCATION = "R1L23" !CDS_LOCATION = "R1L23" #SEC = "1" !CDS_SEC = "1";
"A":   PN = "1"  !CDS_PN = "1";
"B":   PN = "2"  !CDS_PN = "2";
BODY = "CAP_A","I14": #LOCATION = "C1L8" !CDS_LOCATION = "C1L8" #SEC = "1" !CDS_SEC = "1";
"A":   PN = "1"  !CDS_PN = "1";
"B":   PN = "2"  !CDS_PN = "2";
BODY = "CAP_A","I25": #LOCATION = "C9A6" !CDS_LOCATION = "C9A6" &SEC = "1" #&CDS_SEC = "1";
"A":   PN = "1"  !CDS_PN = "1";
"B":   PN = "2"  !CDS_PN = "2";
BODY = "SCONN60_C21100002","I26": #LOCATION = "J9A3" !CDS_LOCATION = "J9A3" #SEC = "1" !CDS_SEC = "1";
"IO1":   PN = "1"  !CDS_PN = "1";
"IO2":   PN = "2"  !CDS_PN = "2";
"IO3":   PN = "3"  !CDS_PN = "3";
"IO4":   PN = "4"  !CDS_PN = "4";
"IO5":   PN = "5"  !CDS_PN = "5";
"IO6":   PN = "6"  !CDS_PN = "6";
"IO7":   PN = "7"  !CDS_PN = "7";
"IO8":   PN = "8"  !CDS_PN = "8";
"IO9":   PN = "9"  !CDS_PN = "9";
"IO10":   PN = "10"  !CDS_PN = "10";
"IO11":   PN = "11"  !CDS_PN = "11";
"IO12":   PN = "12"  !CDS_PN = "12";
"IO13":   PN = "13"  !CDS_PN = "13";
"IO14":   PN = "14"  !CDS_PN = "14";
"IO15":   PN = "15"  !CDS_PN = "15";
"IO16":   PN = "16"  !CDS_PN = "16";
"IO17":   PN = "17"  !CDS_PN = "17";
"IO18":   PN = "18"  !CDS_PN = "18";
"IO19":   PN = "19"  !CDS_PN = "19";
"IO20":   PN = "20"  !CDS_PN = "20";
"IO21":   PN = "21"  !CDS_PN = "21";
"IO22":   PN = "22"  !CDS_PN = "22";
"IO23":   PN = "23"  !CDS_PN = "23";
"IO24":   PN = "24"  !CDS_PN = "24";
"IO25":   PN = "25"  !CDS_PN = "25";
"IO26":   PN = "26"  !CDS_PN = "26";
"IO27":   PN = "27"  !CDS_PN = "27";
"IO28":   PN = "28"  !CDS_PN = "28";
"IO29":   PN = "29"  !CDS_PN = "29";
"IO30":   PN = "30"  !CDS_PN = "30";
"IO31":   PN = "31"  !CDS_PN = "31";
"IO32":   PN = "32"  !CDS_PN = "32";
"IO33":   PN = "33"  !CDS_PN = "33";
"IO34":   PN = "34"  !CDS_PN = "34";
"IO35":   PN = "35"  !CDS_PN = "35";
"IO36":   PN = "36"  !CDS_PN = "36";
"IO37":   PN = "37"  !CDS_PN = "37";
"IO38":   PN = "38"  !CDS_PN = "38";
"IO39":   PN = "39"  !CDS_PN = "39";
"IO40":   PN = "40"  !CDS_PN = "40";
"IO41":   PN = "41"  !CDS_PN = "41";
"IO42":   PN = "42"  !CDS_PN = "42";
"IO43":   PN = "43"  !CDS_PN = "43";
"IO44":   PN = "44"  !CDS_PN = "44";
"IO45":   PN = "45"  !CDS_PN = "45";
"IO46":   PN = "46"  !CDS_PN = "46";
"IO47":   PN = "47"  !CDS_PN = "47";
"IO48":   PN = "48"  !CDS_PN = "48";
"IO49":   PN = "49"  !CDS_PN = "49";
"IO50":   PN = "50"  !CDS_PN = "50";
"IO51":   PN = "51"  !CDS_PN = "51";
"IO52":   PN = "52"  !CDS_PN = "52";
"IO53":   PN = "53"  !CDS_PN = "53";
"IO54":   PN = "54"  !CDS_PN = "54";
"IO55":   PN = "55"  !CDS_PN = "55";
"IO56":   PN = "56"  !CDS_PN = "56";
"IO57":   PN = "57"  !CDS_PN = "57";
"IO58":   PN = "58"  !CDS_PN = "58";
"IO59":   PN = "59"  !CDS_PN = "59";
"IO60":   PN = "60"  !CDS_PN = "60";
BODY = "CAP_A","I30": #LOCATION = "C1L5" !CDS_LOCATION = "C1L5" &SEC = "1" #&CDS_SEC = "1";
"A":   PN = "1"  !CDS_PN = "1";
"B":   PN = "2"  !CDS_PN = "2";
BODY = "RES","I37": #LOCATION = "R2P2" !CDS_LOCATION = "R2P2" #SEC = "1" !CDS_SEC = "1";
"A":   PN = "1"  !CDS_PN = "1";
"B":   PN = "2"  !CDS_PN = "2";
BODY = "RES","I55": #LOCATION = "R9A4" !CDS_LOCATION = "R9A4" #SEC = "1" !CDS_SEC = "1";
"A":   PN = "1"  !CDS_PN = "1";
"B":   PN = "2"  !CDS_PN = "2";
BODY = "RES","I56": #LOCATION = "R1L17" !CDS_LOCATION = "R1L17" #SEC = "1" !CDS_SEC = "1";
"A":   PN = "1"  !CDS_PN = "1";
"B":   PN = "2"  !CDS_PN = "2";
BODY = "RES","I57": #LOCATION = "R9A17" !CDS_LOCATION = "R9A17" #SEC = "1" !CDS_SEC = "1";
"A":   PN = "1"  !CDS_PN = "1";
"B":   PN = "2"  !CDS_PN = "2";
BODY = "CAP_A","I59": #LOCATION = "C9A4" !CDS_LOCATION = "C9A4" #SEC = "1" !CDS_SEC = "1";
"A":   PN = "1"  !CDS_PN = "1";
"B":   PN = "2"  !CDS_PN = "2";
BODY = "RES","I60": #LOCATION = "R9A15" !CDS_LOCATION = "R9A15" #SEC = "1" !CDS_SEC = "1";
"A":   PN = "1"  !CDS_PN = "1";
"B":   PN = "2"  !CDS_PN = "2";
BODY = "RES","I66": #LOCATION = "R1L28" !CDS_LOCATION = "R1L28" #SEC = "1" !CDS_SEC = "1";
"A":   PN = "1"  !CDS_PN = "1";
"B":   PN = "2"  !CDS_PN = "2";
BODY = "RES","I68": #LOCATION = "R1L29" !CDS_LOCATION = "R1L29" #SEC = "1" !CDS_SEC = "1";
"A":   PN = "1"  !CDS_PN = "1";
"B":   PN = "2"  !CDS_PN = "2";
BODY = "RES","I74": #LOCATION = "R9A3" !CDS_LOCATION = "R9A3" #SEC = "1" !CDS_SEC = "1";
"A":   PN = "1"  !CDS_PN = "1";
"B":   PN = "2"  !CDS_PN = "2";
BODY = "RES","I83": #LOCATION = "R9A2" !CDS_LOCATION = "R9A2" #SEC = "1" !CDS_SEC = "1";
"A":   PN = "1"  !CDS_PN = "1";
"B":   PN = "2"  !CDS_PN = "2";
BODY = "TTL1G07_A","I85": #LOCATION = "U1L4" !CDS_LOCATION = "U1L4" #SEC = "1" !CDS_SEC = "1";
"A":   PN = "2"  !CDS_PN = "2";
"Y":   PN = "4"  !CDS_PN = "4";
BODY = "CAP_A","I87": #LOCATION = "C1L11" !CDS_LOCATION = "C1L11" #SEC = "1" !CDS_SEC = "1";
"A":   PN = "1"  !CDS_PN = "1";
"B":   PN = "2"  !CDS_PN = "2";
BODY = "RES","I89": #LOCATION = "R8E2" !CDS_LOCATION = "R8E2" #SEC = "1" !CDS_SEC = "1";
"A":   PN = "1"  !CDS_PN = "1";
"B":   PN = "2"  !CDS_PN = "2";
BODY = "NPN_DUAL","I93": #LOCATION = "Q9A1" !CDS_LOCATION = "Q9A1" #SEC = "2" !CDS_SEC = "2";
"B<0>":   PN = "2"  !CDS_PN = "2";
"C<0>":   PN = "6"  !CDS_PN = "6";
"E<0>":   PN = "1"  !CDS_PN = "1";
BODY = "NPN_DUAL","I94": #LOCATION = "Q9A1" !CDS_LOCATION = "Q9A1" #SEC = "1" !CDS_SEC = "1";
"B<0>":   PN = "5"  !CDS_PN = "5";
"C<0>":   PN = "3"  !CDS_PN = "3";
"E<0>":   PN = "4"  !CDS_PN = "4";
BODY = "RES","I95": #LOCATION = "R9A1" !CDS_LOCATION = "R9A1" #SEC = "1" !CDS_SEC = "1";
"A":   PN = "1"  !CDS_PN = "1";
"B":   PN = "2"  !CDS_PN = "2";
DRAWING = "@baseboard_fab2_lib.baseboard_fab2(sch_1):page112";
BODY = "NC7SB3157","I40": #LOCATION = "U1M7" !CDS_LOCATION = "U1M7" &SEC = "1" #&CDS_SEC = "1";
"A":   PN = "4"  !CDS_PN = "4";
"B0":   PN = "3"  !CDS_PN = "3";
"B1":   PN = "1"  !CDS_PN = "1";
"GND":   PN = "2"  !CDS_PN = "2";
"S":   PN = "6"  !CDS_PN = "6";
"VCC":   PN = "5"  !CDS_PN = "5";
BODY = "CAP_A","I42": #LOCATION = "C1M36" !CDS_LOCATION = "C1M36" #SEC = "1" !CDS_SEC = "1";
"A":   PN = "1"  !CDS_PN = "1";
"B":   PN = "2"  !CDS_PN = "2";
BODY = "CAP_A","I47": #LOCATION = "C1M37" !CDS_LOCATION = "C1M37" &SEC = "1" #&CDS_SEC = "1";
"A":   PN = "1"  !CDS_PN = "1";
"B":   PN = "2"  !CDS_PN = "2";
BODY = "RES","I49": #LOCATION = "R6P46" !CDS_LOCATION = "R6P46" #SEC = "1" !CDS_SEC = "1";
"A":   PN = "1"  !CDS_PN = "1";
"B":   PN = "2"  !CDS_PN = "2";
BODY = "RES","I50": #LOCATION = "R7P30" !CDS_LOCATION = "R7P30" #SEC = "1" !CDS_SEC = "1";
"A":   PN = "1"  !CDS_PN = "1";
"B":   PN = "2"  !CDS_PN = "2";
BODY = "RES","I51": #LOCATION = "R1M3" !CDS_LOCATION = "R1M3" #SEC = "1" !CDS_SEC = "1";
"A":   PN = "1"  !CDS_PN = "1";
"B":   PN = "2"  !CDS_PN = "2";
BODY = "RES","I53": #LOCATION = "R4P15" !CDS_LOCATION = "R4P15" #SEC = "1" !CDS_SEC = "1";
"A":   PN = "1"  !CDS_PN = "1";
"B":   PN = "2"  !CDS_PN = "2";
BODY = "RES","I54": #LOCATION = "R1M4" !CDS_LOCATION = "R1M4" #SEC = "1" !CDS_SEC = "1";
"A":   PN = "1"  !CDS_PN = "1";
"B":   PN = "2"  !CDS_PN = "2";
BODY = "RES","I55": #LOCATION = "R6T7" !CDS_LOCATION = "R6T7" #SEC = "1" !CDS_SEC = "1";
"A":   PN = "1"  !CDS_PN = "1";
"B":   PN = "2"  !CDS_PN = "2";
BODY = "RES","I56": #LOCATION = "R6T6" !CDS_LOCATION = "R6T6" #SEC = "1" !CDS_SEC = "1";
"A":   PN = "1"  !CDS_PN = "1";
"B":   PN = "2"  !CDS_PN = "2";
BODY = "RES","I57": #LOCATION = "R4P12" !CDS_LOCATION = "R4P12" #SEC = "1" !CDS_SEC = "1";
"A":   PN = "1"  !CDS_PN = "1";
"B":   PN = "2"  !CDS_PN = "2";
BODY = "RES","I58": #LOCATION = "R4P23" !CDS_LOCATION = "R4P23" #SEC = "1" !CDS_SEC = "1";
"A":   PN = "1"  !CDS_PN = "1";
"B":   PN = "2"  !CDS_PN = "2";
BODY = "RES","I59": #LOCATION = "R4P24" !CDS_LOCATION = "R4P24" #SEC = "1" !CDS_SEC = "1";
"A":   PN = "1"  !CDS_PN = "1";
"B":   PN = "2"  !CDS_PN = "2";
BODY = "RES","I60": #LOCATION = "R1L15" !CDS_LOCATION = "R1L15" #SEC = "1" !CDS_SEC = "1";
"A":   PN = "1"  !CDS_PN = "1";
"B":   PN = "2"  !CDS_PN = "2";
BODY = "RES","I61": #LOCATION = "R7P29" !CDS_LOCATION = "R7P29" &SEC = "1" #&CDS_SEC = "1";
"A":   PN = "1"  !CDS_PN = "1";
"B":   PN = "2"  !CDS_PN = "2";
BODY = "RES","I62": #LOCATION = "R6T5" !CDS_LOCATION = "R6T5" #SEC = "1" !CDS_SEC = "1";
"A":   PN = "1"  !CDS_PN = "1";
"B":   PN = "2"  !CDS_PN = "2";
BODY = "RES","I76": #LOCATION = "R1L39" !CDS_LOCATION = "R1L39" #SEC = "1" !CDS_SEC = "1";
"A":   PN = "1"  !CDS_PN = "1";
"B":   PN = "2"  !CDS_PN = "2";
BODY = "RES","I77": #LOCATION = "R1L41" !CDS_LOCATION = "R1L41" #SEC = "1" !CDS_SEC = "1";
"A":   PN = "1"  !CDS_PN = "1";
"B":   PN = "2"  !CDS_PN = "2";
BODY = "RES","I78": #LOCATION = "R9A11" !CDS_LOCATION = "R9A11" #SEC = "1" !CDS_SEC = "1";
"A":   PN = "1"  !CDS_PN = "1";
"B":   PN = "2"  !CDS_PN = "2";
BODY = "RES","I79": #LOCATION = "R8A13" !CDS_LOCATION = "R8A13" #SEC = "1" !CDS_SEC = "1";
"A":   PN = "1"  !CDS_PN = "1";
"B":   PN = "2"  !CDS_PN = "2";
BODY = "RES","I80": #LOCATION = "R8A14" !CDS_LOCATION = "R8A14" #SEC = "1" !CDS_SEC = "1";
"A":   PN = "1"  !CDS_PN = "1";
"B":   PN = "2"  !CDS_PN = "2";
BODY = "RES","I85": #LOCATION = "R3M10" !CDS_LOCATION = "R3M10" #SEC = "1" !CDS_SEC = "1";
"A":   PN = "1"  !CDS_PN = "1";
"B":   PN = "2"  !CDS_PN = "2";
BODY = "RES","I94": #LOCATION = "R8B2" !CDS_LOCATION = "R8B2" #SEC = "1" !CDS_SEC = "1";
"A":   PN = "1"  !CDS_PN = "1";
"B":   PN = "2"  !CDS_PN = "2";
BODY = "RES","I95": #LOCATION = "R8B1" !CDS_LOCATION = "R8B1" &SEC = "1" #&CDS_SEC = "1";
"A":   PN = "1"  !CDS_PN = "1";
"B":   PN = "2"  !CDS_PN = "2";
BODY = "TTL3126","I108": #LOCATION = "U1L1" !CDS_LOCATION = "U1L1";
"A<0>":   PN = "12"  !CDS_PN = "12";
"A<1>":   PN = "9"  !CDS_PN = "9";
"A<2>":   PN = "5"  !CDS_PN = "5";
"A<3>":   PN = "2"  !CDS_PN = "2";
"B<0>":   PN = "11"  !CDS_PN = "11";
"B<1>":   PN = "8"  !CDS_PN = "8";
"B<2>":   PN = "6"  !CDS_PN = "6";
"B<3>":   PN = "3"  !CDS_PN = "3";
"OE<0>":   PN = "13"  !CDS_PN = "13";
"OE<1>":   PN = "10"  !CDS_PN = "10";
"OE<2>":   PN = "4"  !CDS_PN = "4";
"OE<3>":   PN = "1"  !CDS_PN = "1";
BODY = "TTL3126","I109": #LOCATION = "U1L5" !CDS_LOCATION = "U1L5";
"A<0>":   PN = "12"  !CDS_PN = "12";
"A<1>":   PN = "9"  !CDS_PN = "9";
"A<2>":   PN = "5"  !CDS_PN = "5";
"A<3>":   PN = "2"  !CDS_PN = "2";
"B<0>":   PN = "11"  !CDS_PN = "11";
"B<1>":   PN = "8"  !CDS_PN = "8";
"B<2>":   PN = "6"  !CDS_PN = "6";
"B<3>":   PN = "3"  !CDS_PN = "3";
"OE<0>":   PN = "13"  !CDS_PN = "13";
"OE<1>":   PN = "10"  !CDS_PN = "10";
"OE<2>":   PN = "4"  !CDS_PN = "4";
"OE<3>":   PN = "1"  !CDS_PN = "1";
BODY = "RES","I120": #LOCATION = "R6T9" !CDS_LOCATION = "R6T9" #SEC = "1" !CDS_SEC = "1";
"A":   PN = "1"  !CDS_PN = "1";
"B":   PN = "2"  !CDS_PN = "2";
BODY = "RES","I121": #LOCATION = "R6T8" !CDS_LOCATION = "R6T8" #SEC = "1" !CDS_SEC = "1";
"A":   PN = "1"  !CDS_PN = "1";
"B":   PN = "2"  !CDS_PN = "2";
BODY = "74CBTLV1G125","I127": #LOCATION = "U1M4" !CDS_LOCATION = "U1M4" #SEC = "1" !CDS_SEC = "1";
"A":   PN = "2"  !CDS_PN = "2";
"B":   PN = "4"  !CDS_PN = "4";
"OE_N":   PN = "1"  !CDS_PN = "1";
BODY = "CAP_A","I131": #LOCATION = "C1M30" !CDS_LOCATION = "C1M30" #SEC = "1" !CDS_SEC = "1";
"A":   PN = "1"  !CDS_PN = "1";
"B":   PN = "2"  !CDS_PN = "2";
BODY = "CAP","I136": #LOCATION = "C1L1" !CDS_LOCATION = "C1L1" #SEC = "1" !CDS_SEC = "1";
"A":   PN = "1"  !CDS_PN = "1";
"B":   PN = "2"  !CDS_PN = "2";
BODY = "CAP","I140": #LOCATION = "C1L19" !CDS_LOCATION = "C1L19" #SEC = "1" !CDS_SEC = "1";
"A":   PN = "1"  !CDS_PN = "1";
"B":   PN = "2"  !CDS_PN = "2";
DRAWING = "@baseboard_fab2_lib.baseboard_fab2(sch_1):page113";
BODY = "NC7SB3157","I107": #LOCATION = "U1M2" !CDS_LOCATION = "U1M2" #SEC = "1" !CDS_SEC = "1";
"A":   PN = "4"  !CDS_PN = "4";
"B0":   PN = "3"  !CDS_PN = "3";
"B1":   PN = "1"  !CDS_PN = "1";
"GND":   PN = "2"  !CDS_PN = "2";
"S":   PN = "6"  !CDS_PN = "6";
"VCC":   PN = "5"  !CDS_PN = "5";
BODY = "CAP_A","I116": #LOCATION = "C1M31" !CDS_LOCATION = "C1M31" #SEC = "1" !CDS_SEC = "1";
"A":   PN = "1"  !CDS_PN = "1";
"B":   PN = "2"  !CDS_PN = "2";
BODY = "CAP_A","I117": #LOCATION = "C1M32" !CDS_LOCATION = "C1M32" #SEC = "1" !CDS_SEC = "1";
"A":   PN = "1"  !CDS_PN = "1";
"B":   PN = "2"  !CDS_PN = "2";
BODY = "CAP_A","I119": #LOCATION = "C1M28" !CDS_LOCATION = "C1M28" #SEC = "1" !CDS_SEC = "1";
"A":   PN = "1"  !CDS_PN = "1";
"B":   PN = "2"  !CDS_PN = "2";
BODY = "74CBTLV1G125","I127": #LOCATION = "U1M6" !CDS_LOCATION = "U1M6" #SEC = "1" !CDS_SEC = "1";
"A":   PN = "2"  !CDS_PN = "2";
"B":   PN = "4"  !CDS_PN = "4";
"OE_N":   PN = "1"  !CDS_PN = "1";
BODY = "RES","I134": #LOCATION = "R4R6" !CDS_LOCATION = "R4R6" #SEC = "1" !CDS_SEC = "1";
"A":   PN = "1"  !CDS_PN = "1";
"B":   PN = "2"  !CDS_PN = "2";
BODY = "CAP_A","I147": #LOCATION = "C1M29" !CDS_LOCATION = "C1M29" &SEC = "1" #&CDS_SEC = "1";
"A":   PN = "1"  !CDS_PN = "1";
"B":   PN = "2"  !CDS_PN = "2";
BODY = "RES","I168": #LOCATION = "R9B14" !CDS_LOCATION = "R9B14" #SEC = "1" !CDS_SEC = "1";
"A":   PN = "1"  !CDS_PN = "1";
"B":   PN = "2"  !CDS_PN = "2";
BODY = "SCONN10_C12536004","I175": #LOCATION = "J9B4" !CDS_LOCATION = "J9B4" #SEC = "1" !CDS_SEC = "1";
"IO1":   PN = "1"  !CDS_PN = "1";
"IO2":   PN = "2"  !CDS_PN = "2";
"IO3":   PN = "3"  !CDS_PN = "3";
"IO4":   PN = "4"  !CDS_PN = "4";
"IO5":   PN = "5"  !CDS_PN = "5";
"IO6":   PN = "6"  !CDS_PN = "6";
"IO7":   PN = "7"  !CDS_PN = "7";
"IO8":   PN = "8"  !CDS_PN = "8";
"IO9":   PN = "9"  !CDS_PN = "9";
"IO10":   PN = "10"  !CDS_PN = "10";
BODY = "RES","I179": #LOCATION = "R9B9" !CDS_LOCATION = "R9B9" #SEC = "1" !CDS_SEC = "1";
"A":   PN = "1"  !CDS_PN = "1";
"B":   PN = "2"  !CDS_PN = "2";
BODY = "RES","I180": #LOCATION = "R9B10" !CDS_LOCATION = "R9B10" #SEC = "1" !CDS_SEC = "1";
"A":   PN = "1"  !CDS_PN = "1";
"B":   PN = "2"  !CDS_PN = "2";
BODY = "74CBTLV1G125","I185": #LOCATION = "U9A5" !CDS_LOCATION = "U9A5" #SEC = "1" !CDS_SEC = "1";
"A":   PN = "2"  !CDS_PN = "2";
"B":   PN = "4"  !CDS_PN = "4";
"OE_N":   PN = "1"  !CDS_PN = "1";
BODY = "RES","I188": #LOCATION = "R6M8" !CDS_LOCATION = "R6M8" #SEC = "1" !CDS_SEC = "1";
"A":   PN = "1"  !CDS_PN = "1";
"B":   PN = "2"  !CDS_PN = "2";
BODY = "74CBTLV1G125","I190": #LOCATION = "U6M1" !CDS_LOCATION = "U6M1" #SEC = "1" !CDS_SEC = "1";
"A":   PN = "2"  !CDS_PN = "2";
"B":   PN = "4"  !CDS_PN = "4";
"OE_N":   PN = "1"  !CDS_PN = "1";
BODY = "RES","I195": #LOCATION = "R1M22" !CDS_LOCATION = "R1M22" #SEC = "1" !CDS_SEC = "1";
"A":   PN = "1"  !CDS_PN = "1";
"B":   PN = "2"  !CDS_PN = "2";
BODY = "74CBTLV1G125","I196": #LOCATION = "U1M5" !CDS_LOCATION = "U1M5" #SEC = "1" !CDS_SEC = "1";
"A":   PN = "2"  !CDS_PN = "2";
"B":   PN = "4"  !CDS_PN = "4";
"OE_N":   PN = "1"  !CDS_PN = "1";
BODY = "RES","I199": #LOCATION = "R1M23" !CDS_LOCATION = "R1M23" #SEC = "1" !CDS_SEC = "1";
"A":   PN = "1"  !CDS_PN = "1";
"B":   PN = "2"  !CDS_PN = "2";
BODY = "RES","I202": #LOCATION = "R1M19" !CDS_LOCATION = "R1M19" #SEC = "1" !CDS_SEC = "1";
"A":   PN = "1"  !CDS_PN = "1";
"B":   PN = "2"  !CDS_PN = "2";
BODY = "RES","I203": #LOCATION = "R9B12" !CDS_LOCATION = "R9B12" #SEC = "1" !CDS_SEC = "1";
"A":   PN = "1"  !CDS_PN = "1";
"B":   PN = "2"  !CDS_PN = "2";
BODY = "RES","I204": #LOCATION = "R1M20" !CDS_LOCATION = "R1M20" #SEC = "1" !CDS_SEC = "1";
"A":   PN = "1"  !CDS_PN = "1";
"B":   PN = "2"  !CDS_PN = "2";
BODY = "RES","I205": #LOCATION = "R1M21" !CDS_LOCATION = "R1M21" #SEC = "1" !CDS_SEC = "1";
"A":   PN = "1"  !CDS_PN = "1";
"B":   PN = "2"  !CDS_PN = "2";
BODY = "74CBTLV1G125","I206": #LOCATION = "U4R1" !CDS_LOCATION = "U4R1" #SEC = "1" !CDS_SEC = "1";
"A":   PN = "2"  !CDS_PN = "2";
"B":   PN = "4"  !CDS_PN = "4";
"OE_N":   PN = "1"  !CDS_PN = "1";
BODY = "RES","I239": #LOCATION = "R9B11" !CDS_LOCATION = "R9B11" #SEC = "1" !CDS_SEC = "1";
"A":   PN = "1"  !CDS_PN = "1";
"B":   PN = "2"  !CDS_PN = "2";
BODY = "RES","I240": #LOCATION = "R9B13" !CDS_LOCATION = "R9B13" #SEC = "1" !CDS_SEC = "1";
"A":   PN = "1"  !CDS_PN = "1";
"B":   PN = "2"  !CDS_PN = "2";
BODY = "CAP_A","I246": #LOCATION = "C4R2" !CDS_LOCATION = "C4R2" #SEC = "1" !CDS_SEC = "1";
"A":   PN = "1"  !CDS_PN = "1";
"B":   PN = "2"  !CDS_PN = "2";
BODY = "CAP_A","I248": #LOCATION = "C1M33" !CDS_LOCATION = "C1M33" #SEC = "1" !CDS_SEC = "1";
"A":   PN = "1"  !CDS_PN = "1";
"B":   PN = "2"  !CDS_PN = "2";
BODY = "CAP_A","I250": #LOCATION = "C6M6" !CDS_LOCATION = "C6M6" #SEC = "1" !CDS_SEC = "1";
"A":   PN = "1"  !CDS_PN = "1";
"B":   PN = "2"  !CDS_PN = "2";
BODY = "NC7SB3157","I255": #LOCATION = "U2M1" !CDS_LOCATION = "U2M1" #SEC = "1" !CDS_SEC = "1";
"A":   PN = "4"  !CDS_PN = "4";
"B0":   PN = "3"  !CDS_PN = "3";
"B1":   PN = "1"  !CDS_PN = "1";
"GND":   PN = "2"  !CDS_PN = "2";
"S":   PN = "6"  !CDS_PN = "6";
"VCC":   PN = "5"  !CDS_PN = "5";
BODY = "CAP_A","I265": #LOCATION = "C1M34" !CDS_LOCATION = "C1M34" #SEC = "1" !CDS_SEC = "1";
"A":   PN = "1"  !CDS_PN = "1";
"B":   PN = "2"  !CDS_PN = "2";
BODY = "CAP_A","I266": #LOCATION = "C1M35" !CDS_LOCATION = "C1M35" #SEC = "1" !CDS_SEC = "1";
"A":   PN = "1"  !CDS_PN = "1";
"B":   PN = "2"  !CDS_PN = "2";
BODY = "CAP_A","I267": #LOCATION = "C1L20" !CDS_LOCATION = "C1L20" #SEC = "1" !CDS_SEC = "1";
"A":   PN = "1"  !CDS_PN = "1";
"B":   PN = "2"  !CDS_PN = "2";
DRAWING = "@baseboard_fab2_lib.baseboard_fab2(sch_1):page114";
BODY = "LBG_CORE_QAT_EXT_D","I40": #LOCATION = "U7C1" !CDS_LOCATION = "U7C1" #SEC = "1" !CDS_SEC = "1";
"CLKOUT_ITPXDPN":   PN = "A39"  !CDS_PN = "A39";
"CLKOUT_ITPXDPP":   PN = "C39"  !CDS_PN = "C39";
"CLKOUT_NSSCCAP0N":   PN = "A32"  !CDS_PN = "A32";
"CLKOUT_NSSCCAP0P":   PN = "C32"  !CDS_PN = "C32";
"CLKOUT_NSSCCAP1N":   PN = "B38"  !CDS_PN = "B38";
"CLKOUT_NSSCCAP1P":   PN = "D38"  !CDS_PN = "D38";
"CLKOUT_PLAT0N":   PN = "B29"  !CDS_PN = "B29";
"CLKOUT_PLAT0P":   PN = "D29"  !CDS_PN = "D29";
"CLKOUT_PLAT1N":   PN = "B40"  !CDS_PN = "B40";
"CLKOUT_PLAT1P":   PN = "D40"  !CDS_PN = "D40";
"CLKOUT_SRCN<0>":   PN = "K38"  !CDS_PN = "K38";
"CLKOUT_SRCN<1>":   PN = "K35"  !CDS_PN = "K35";
"CLKOUT_SRCN<2>":   PN = "J33"  !CDS_PN = "J33";
"CLKOUT_SRCN<3>":   PN = "K42"  !CDS_PN = "K42";
"CLKOUT_SRCN<4>":   PN = "A28"  !CDS_PN = "A28";
"CLKOUT_SRCN<5>":   PN = "J40"  !CDS_PN = "J40";
"CLKOUT_SRCN<6>":   PN = "D33"  !CDS_PN = "D33";
"CLKOUT_SRCN<7>":   PN = "H31"  !CDS_PN = "H31";
"CLKOUT_SRCN<8>":   PN = "D31"  !CDS_PN = "D31";
"CLKOUT_SRCN<9>":   PN = "J26"  !CDS_PN = "J26";
"CLKOUT_SRCN<10>":   PN = "B23"  !CDS_PN = "B23";
"CLKOUT_SRCN<11>":   PN = "B21"  !CDS_PN = "B21";
"CLKOUT_SRCN<12>":   PN = "K24"  !CDS_PN = "K24";
"CLKOUT_SRCN<13>":   PN = "C24"  !CDS_PN = "C24";
"CLKOUT_SRCN<14>":   PN = "C20"  !CDS_PN = "C20";
"CLKOUT_SRCN<15>":   PN = "K27"  !CDS_PN = "K27";
"CLKOUT_SRCP<0>":   PN = "H38"  !CDS_PN = "H38";
"CLKOUT_SRCP<1>":   PN = "H35"  !CDS_PN = "H35";
"CLKOUT_SRCP<2>":   PN = "G33"  !CDS_PN = "G33";
"CLKOUT_SRCP<3>":   PN = "H42"  !CDS_PN = "H42";
"CLKOUT_SRCP<4>":   PN = "C28"  !CDS_PN = "C28";
"CLKOUT_SRCP<5>":   PN = "G40"  !CDS_PN = "G40";
"CLKOUT_SRCP<6>":   PN = "B33"  !CDS_PN = "B33";
"CLKOUT_SRCP<7>":   PN = "K31"  !CDS_PN = "K31";
"CLKOUT_SRCP<8>":   PN = "B31"  !CDS_PN = "B31";
"CLKOUT_SRCP<9>":   PN = "G26"  !CDS_PN = "G26";
"CLKOUT_SRCP<10>":   PN = "D23"  !CDS_PN = "D23";
"CLKOUT_SRCP<11>":   PN = "D21"  !CDS_PN = "D21";
"CLKOUT_SRCP<12>":   PN = "H24"  !CDS_PN = "H24";
"CLKOUT_SRCP<13>":   PN = "A24"  !CDS_PN = "A24";
"CLKOUT_SRCP<14>":   PN = "A20"  !CDS_PN = "A20";
"CLKOUT_SRCP<15>":   PN = "H27"  !CDS_PN = "H27";
"CLOCKSE_BMCCLK":   PN = "BW50"  !CDS_PN = "BW50";
"CLOCKSE_PMSYNCCLK1":   PN = "BY51"  !CDS_PN = "BY51";
"CLOCKSE_PMSYNCCLK2":   PN = "BV51"  !CDS_PN = "BV51";
"RSVD<64>":   PN = "C26"  !CDS_PN = "C26";
"RSVD<65>":   PN = "A26"  !CDS_PN = "A26";
"RTCX1":   PN = "K17"  !CDS_PN = "K17";
"RTCX2":   PN = "H17"  !CDS_PN = "H17";
"XCLK_BIASREF":   PN = "G44"  !CDS_PN = "G44";
"XTAL_IN":   PN = "B35"  !CDS_PN = "B35";
"XTAL_OUT":   PN = "D35"  !CDS_PN = "D35";
BODY = "CAP","I46": #LOCATION = "C7C15" !CDS_LOCATION = "C7C15" &SEC = "1" #&CDS_SEC = "1";
"A":   PN = "1"  !CDS_PN = "1";
"B":   PN = "2"  !CDS_PN = "2";
BODY = "CAP","I47": #LOCATION = "C7C5" !CDS_LOCATION = "C7C5" #SEC = "1" !CDS_SEC = "1";
"A":   PN = "1"  !CDS_PN = "1";
"B":   PN = "2"  !CDS_PN = "2";
BODY = "RES","I48": #LOCATION = "R7C1" !CDS_LOCATION = "R7C1" #SEC = "1" !CDS_SEC = "1";
"A":   PN = "1"  !CDS_PN = "1";
"B":   PN = "2"  !CDS_PN = "2";
BODY = "CRYSTAL","I49": #LOCATION = "Y7C1" !CDS_LOCATION = "Y7C1" #SEC = "1" !CDS_SEC = "1";
"A":   PN = "1"  !CDS_PN = "1";
"B":   PN = "3"  !CDS_PN = "3";
BODY = "CAP","I50": #LOCATION = "C7C4" !CDS_LOCATION = "C7C4" #SEC = "1" !CDS_SEC = "1";
"A":   PN = "1"  !CDS_PN = "1";
"B":   PN = "2"  !CDS_PN = "2";
BODY = "RES","I54": #LOCATION = "R7C6" !CDS_LOCATION = "R7C6" &SEC = "1" #&CDS_SEC = "1";
"A":   PN = "1"  !CDS_PN = "1";
"B":   PN = "2"  !CDS_PN = "2";
BODY = "CRYSTAL","I55": #LOCATION = "Y7C2" !CDS_LOCATION = "Y7C2" #SEC = "1" !CDS_SEC = "1";
"A":   PN = "1"  !CDS_PN = "1";
"B":   PN = "2"  !CDS_PN = "2";
BODY = "CAP","I56": #LOCATION = "C7C13" !CDS_LOCATION = "C7C13" &SEC = "1" #&CDS_SEC = "1";
"A":   PN = "1"  !CDS_PN = "1";
"B":   PN = "2"  !CDS_PN = "2";
BODY = "RES","I110": #LOCATION = "R8B20" !CDS_LOCATION = "R8B20" #SEC = "1" !CDS_SEC = "1";
"A":   PN = "1"  !CDS_PN = "1";
"B":   PN = "2"  !CDS_PN = "2";
BODY = "RES","I124": #LOCATION = "R8B21" !CDS_LOCATION = "R8B21" #SEC = "1" !CDS_SEC = "1";
"A":   PN = "1"  !CDS_PN = "1";
"B":   PN = "2"  !CDS_PN = "2";
BODY = "RES","I141": #LOCATION = "R7C2" !CDS_LOCATION = "R7C2" #SEC = "1" !CDS_SEC = "1";
"A":   PN = "1"  !CDS_PN = "1";
"B":   PN = "2"  !CDS_PN = "2";
BODY = "RES","I142": #LOCATION = "R7C4" !CDS_LOCATION = "R7C4" #SEC = "1" !CDS_SEC = "1";
"A":   PN = "1"  !CDS_PN = "1";
"B":   PN = "2"  !CDS_PN = "2";
BODY = "RES","I149": #LOCATION = "R3N1" !CDS_LOCATION = "R3N1" &SEC = "1" #&CDS_SEC = "1";
"A":   PN = "1"  !CDS_PN = "1";
"B":   PN = "2"  !CDS_PN = "2";
DRAWING = "@baseboard_fab2_lib.baseboard_fab2(sch_1):page115";
BODY = "LBG_CORE_QAT_EXT_D","I74": #LOCATION = "U7C1" !CDS_LOCATION = "U7C1" #SEC = "2" !CDS_SEC = "2";
"RSVD<55>":   PN = "BN68"  !CDS_PN = "BN68";
"USB2_COMP":   PN = "BN70"  !CDS_PN = "BN70";
"USB2_VBUS":   PN = "BR67"  !CDS_PN = "BR67";
"USB2N_1":   PN = "BY60"  !CDS_PN = "BY60";
"USB2N_2":   PN = "CA61"  !CDS_PN = "CA61";
"USB2N_3":   PN = "CA59"  !CDS_PN = "CA59";
"USB2N_4":   PN = "BY62"  !CDS_PN = "BY62";
"USB2N_5":   PN = "BY58"  !CDS_PN = "BY58";
"USB2N_6":   PN = "CA63"  !CDS_PN = "CA63";
"USB2N_7":   PN = "CA57"  !CDS_PN = "CA57";
"USB2N_8":   PN = "BY64"  !CDS_PN = "BY64";
"USB2N_9":   PN = "BY55"  !CDS_PN = "BY55";
"USB2N_10":   PN = "BW65"  !CDS_PN = "BW65";
"USB2N_11":   PN = "CA54"  !CDS_PN = "CA54";
"USB2N_12":   PN = "BW67"  !CDS_PN = "BW67";
"USB2N_13":   PN = "BY53"  !CDS_PN = "BY53";
"USB2N_14":   PN = "BW68"  !CDS_PN = "BW68";
"USB2P_1":   PN = "BV60"  !CDS_PN = "BV60";
"USB2P_2":   PN = "BW61"  !CDS_PN = "BW61";
"USB2P_3":   PN = "BW59"  !CDS_PN = "BW59";
"USB2P_4":   PN = "BV62"  !CDS_PN = "BV62";
"USB2P_5":   PN = "BV58"  !CDS_PN = "BV58";
"USB2P_6":   PN = "BW63"  !CDS_PN = "BW63";
"USB2P_7":   PN = "BW57"  !CDS_PN = "BW57";
"USB2P_8":   PN = "BV64"  !CDS_PN = "BV64";
"USB2P_9":   PN = "BV55"  !CDS_PN = "BV55";
"USB2P_10":   PN = "BU65"  !CDS_PN = "BU65";
"USB2P_11":   PN = "BW54"  !CDS_PN = "BW54";
"USB2P_12":   PN = "BV66"  !CDS_PN = "BV66";
"USB2P_13":   PN = "BV53"  !CDS_PN = "BV53";
"USB2P_14":   PN = "BU67"  !CDS_PN = "BU67";
"USB3_1_RXN":   PN = "BK71"  !CDS_PN = "BK71";
"USB3_1_RXP":   PN = "BK69"  !CDS_PN = "BK69";
"USB3_1_TXN":   PN = "BL52"  !CDS_PN = "BL52";
"USB3_1_TXP":   PN = "BK54"  !CDS_PN = "BK54";
"USB3_2_RXN":   PN = "BJ72"  !CDS_PN = "BJ72";
"USB3_2_RXP":   PN = "BJ70"  !CDS_PN = "BJ70";
"USB3_2_TXN":   PN = "BL56"  !CDS_PN = "BL56";
"USB3_2_TXP":   PN = "BJ56"  !CDS_PN = "BJ56";
"USB3_3_RXN":   PN = "BH71"  !CDS_PN = "BH71";
"USB3_3_RXP":   PN = "BH69"  !CDS_PN = "BH69";
"USB3_3_TXN":   PN = "BM54"  !CDS_PN = "BM54";
"USB3_3_TXP":   PN = "BN56"  !CDS_PN = "BN56";
"USB3_4_RXN":   PN = "BF72"  !CDS_PN = "BF72";
"USB3_4_RXP":   PN = "BF70"  !CDS_PN = "BF70";
"USB3_4_TXN":   PN = "BH58"  !CDS_PN = "BH58";
"USB3_4_TXP":   PN = "BG56"  !CDS_PN = "BG56";
"USB3_5_RXN":   PN = "BE71"  !CDS_PN = "BE71";
"USB3_5_RXP":   PN = "BE69"  !CDS_PN = "BE69";
"USB3_5_TXN":   PN = "BK58"  !CDS_PN = "BK58";
"USB3_5_TXP":   PN = "BJ59"  !CDS_PN = "BJ59";
"USB3_6_RXN":   PN = "BD72"  !CDS_PN = "BD72";
"USB3_6_RXP":   PN = "BD70"  !CDS_PN = "BD70";
"USB3_6_TXN":   PN = "BL59"  !CDS_PN = "BL59";
"USB3_6_TXP":   PN = "BM61"  !CDS_PN = "BM61";
BODY = "RES","I90": #LOCATION = "R8B9" !CDS_LOCATION = "R8B9" #SEC = "1" !CDS_SEC = "1";
"A":   PN = "1"  !CDS_PN = "1";
"B":   PN = "2"  !CDS_PN = "2";
BODY = "RES","I114": #LOCATION = "R8B32" !CDS_LOCATION = "R8B32" #SEC = "1" !CDS_SEC = "1";
"A":   PN = "1"  !CDS_PN = "1";
"B":   PN = "2"  !CDS_PN = "2";
DRAWING = "@baseboard_fab2_lib.baseboard_fab2(sch_1):page116";
BODY = "RES","I108": #LOCATION = "R3M11" !CDS_LOCATION = "R3M11" #SEC = "1" !CDS_SEC = "1";
"A":   PN = "1"  !CDS_PN = "1";
"B":   PN = "2"  !CDS_PN = "2";
BODY = "RES","I181": #LOCATION = "R3M12" !CDS_LOCATION = "R3M12" #SEC = "1" !CDS_SEC = "1";
"A":   PN = "1"  !CDS_PN = "1";
"B":   PN = "2"  !CDS_PN = "2";
BODY = "CAP_A","I182": #LOCATION = "C2M4" !CDS_LOCATION = "C2M4" #SEC = "1" !CDS_SEC = "1";
"A":   PN = "1"  !CDS_PN = "1";
"B":   PN = "2"  !CDS_PN = "2";
BODY = "CAP_A","I183": #LOCATION = "C2M3" !CDS_LOCATION = "C2M3" #SEC = "1" !CDS_SEC = "1";
"A":   PN = "1"  !CDS_PN = "1";
"B":   PN = "2"  !CDS_PN = "2";
BODY = "LBG_CORE_QAT_EXT_D","I220": #LOCATION = "U7C1" !CDS_LOCATION = "U7C1" #SEC = "3" !CDS_SEC = "3";
"EXTCLKN":   PN = "D66"  !CDS_PN = "D66";
"EXTCLKP":   PN = "E67"  !CDS_PN = "E67";
"PCIE4_GBE_RXN":   PN = "AN70"  !CDS_PN = "AN70";
"PCIE4_GBE_RXP":   PN = "AN72"  !CDS_PN = "AN72";
"PCIE4_GBE_TXN":   PN = "BG66"  !CDS_PN = "BG66";
"PCIE4_GBE_TXP":   PN = "BJ66"  !CDS_PN = "BJ66";
"PCIE5_GBE_RXN":   PN = "AM69"  !CDS_PN = "AM69";
"PCIE5_GBE_RXP":   PN = "AM71"  !CDS_PN = "AM71";
"PCIE5_GBE_TXN":   PN = "BH65"  !CDS_PN = "BH65";
"PCIE5_GBE_TXP":   PN = "BJ63"  !CDS_PN = "BJ63";
"PCIE6_SSATA0_RXN":   PN = "BB63"  !CDS_PN = "BB63";
"PCIE6_SSATA0_RXP":   PN = "BD61"  !CDS_PN = "BD61";
"PCIE6_SSATA0_TXN":   PN = "AJ70"  !CDS_PN = "AJ70";
"PCIE6_SSATA0_TXP":   PN = "AJ72"  !CDS_PN = "AJ72";
"PCIE7_SSATA1_RXN":   PN = "AY59"  !CDS_PN = "AY59";
"PCIE7_SSATA1_RXP":   PN = "BA61"  !CDS_PN = "BA61";
"PCIE7_SSATA1_TXN":   PN = "AH69"  !CDS_PN = "AH69";
"PCIE7_SSATA1_TXP":   PN = "AH71"  !CDS_PN = "AH71";
"PCIE8_SSATA2_GBE_RXN":   PN = "BA65"  !CDS_PN = "BA65";
"PCIE8_SSATA2_GBE_RXP":   PN = "BD65"  !CDS_PN = "BD65";
"PCIE8_SSATA2_GBE_TXN":   PN = "AF70"  !CDS_PN = "AF70";
"PCIE8_SSATA2_GBE_TXP":   PN = "AF72"  !CDS_PN = "AF72";
"PCIE9_SSATA3_RXN":   PN = "AW65"  !CDS_PN = "AW65";
"PCIE9_SSATA3_RXP":   PN = "AY66"  !CDS_PN = "AY66";
"PCIE9_SSATA3_TXN":   PN = "AE69"  !CDS_PN = "AE69";
"PCIE9_SSATA3_TXP":   PN = "AE71"  !CDS_PN = "AE71";
"PCIE10_SSATA4_RXN":   PN = "AV63"  !CDS_PN = "AV63";
"PCIE10_SSATA4_RXP":   PN = "AU65"  !CDS_PN = "AU65";
"PCIE10_SSATA4_TXN":   PN = "AD70"  !CDS_PN = "AD70";
"PCIE10_SSATA4_TXP":   PN = "AD72"  !CDS_PN = "AD72";
"PCIE11_SSATA5_GBE_RXN":   PN = "AT66"  !CDS_PN = "AT66";
"PCIE11_SSATA5_GBE_RXP":   PN = "AV66"  !CDS_PN = "AV66";
"PCIE11_SSATA5_GBE_TXN":   PN = "AC69"  !CDS_PN = "AC69";
"PCIE11_SSATA5_GBE_TXP":   PN = "AC71"  !CDS_PN = "AC71";
"PCIE12_UP0_SATA0_RXN":   PN = "AR61"  !CDS_PN = "AR61";
"PCIE12_UP0_SATA0_RXP":   PN = "AT63"  !CDS_PN = "AT63";
"PCIE12_UP0_SATA0_TXN":   PN = "W69"  !CDS_PN = "W69";
"PCIE12_UP0_SATA0_TXP":   PN = "W71"  !CDS_PN = "W71";
"PCIE13_UP1_SATA1_RXN":   PN = "AL66"  !CDS_PN = "AL66";
"PCIE13_UP1_SATA1_RXP":   PN = "AN65"  !CDS_PN = "AN65";
"PCIE13_UP1_SATA1_TXN":   PN = "V70"  !CDS_PN = "V70";
"PCIE13_UP1_SATA1_TXP":   PN = "V72"  !CDS_PN = "V72";
"PCIE14_UP2_SATA2_RXN":   PN = "AK65"  !CDS_PN = "AK65";
"PCIE14_UP2_SATA2_RXP":   PN = "AJ63"  !CDS_PN = "AJ63";
"PCIE14_UP2_SATA2_TXN":   PN = "T69"  !CDS_PN = "T69";
"PCIE14_UP2_SATA2_TXP":   PN = "T71"  !CDS_PN = "T71";
"PCIE15_UP3_SATA3_RXN":   PN = "AP63"  !CDS_PN = "AP63";
"PCIE15_UP3_SATA3_RXP":   PN = "AL63"  !CDS_PN = "AL63";
"PCIE15_UP3_SATA3_TXN":   PN = "R70"  !CDS_PN = "R70";
"PCIE15_UP3_SATA3_TXP":   PN = "R72"  !CDS_PN = "R72";
"PCIE16_UP4_SATA4_RXN":   PN = "AF65"  !CDS_PN = "AF65";
"PCIE16_UP4_SATA4_RXP":   PN = "AH65"  !CDS_PN = "AH65";
"PCIE16_UP4_SATA4_TXN":   PN = "P69"  !CDS_PN = "P69";
"PCIE16_UP4_SATA4_TXP":   PN = "P71"  !CDS_PN = "P71";
"PCIE17_UP5_SATA5_RXN":   PN = "AH61"  !CDS_PN = "AH61";
"PCIE17_UP5_SATA5_RXP":   PN = "AG63"  !CDS_PN = "AG63";
"PCIE17_UP5_SATA5_TXN":   PN = "N70"  !CDS_PN = "N70";
"PCIE17_UP5_SATA5_TXP":   PN = "N72"  !CDS_PN = "N72";
"PCIE18_UP6_SATA6_RXN":   PN = "AP59"  !CDS_PN = "AP59";
"PCIE18_UP6_SATA6_RXP":   PN = "AN61"  !CDS_PN = "AN61";
"PCIE18_UP6_SATA6_TXN":   PN = "M69"  !CDS_PN = "M69";
"PCIE18_UP6_SATA6_TXP":   PN = "M71"  !CDS_PN = "M71";
"PCIE19_UP7_SATA7_RXN":   PN = "AA61"  !CDS_PN = "AA61";
"PCIE19_UP7_SATA7_RXP":   PN = "AD61"  !CDS_PN = "AD61";
"PCIE19_UP7_SATA7_TXN":   PN = "L70"  !CDS_PN = "L70";
"PCIE19_UP7_SATA7_TXP":   PN = "L72"  !CDS_PN = "L72";
"PCIE_RCOMPN":   PN = "BD58"  !CDS_PN = "BD58";
"PCIE_RCOMPP":   PN = "BB56"  !CDS_PN = "BB56";
"PCIEUP_RCOMPN":   PN = "AF58"  !CDS_PN = "AF58";
"PCIEUP_RCOMPP":   PN = "AH58"  !CDS_PN = "AH58";
"RSVD<47>":   PN = "AP69"  !CDS_PN = "AP69";
"RSVD<48>":   PN = "AP71"  !CDS_PN = "AP71";
"RSVD<49>":   PN = "G67"  !CDS_PN = "G67";
"RSVD<50>":   PN = "H69"  !CDS_PN = "H69";
"RSVD<51>":   PN = "AA69"  !CDS_PN = "AA69";
"RSVD<52>":   PN = "AA71"  !CDS_PN = "AA71";
"USB3_7_PCIE0_RXN":   PN = "BA71"  !CDS_PN = "BA71";
"USB3_7_PCIE0_RXP":   PN = "BA69"  !CDS_PN = "BA69";
"USB3_7_PCIE0_TXN":   PN = "BR61"  !CDS_PN = "BR61";
"USB3_7_PCIE0_TXP":   PN = "BN63"  !CDS_PN = "BN63";
"USB3_8_PCIE1_RXN":   PN = "AY72"  !CDS_PN = "AY72";
"USB3_8_PCIE1_RXP":   PN = "AY70"  !CDS_PN = "AY70";
"USB3_8_PCIE1_TXN":   PN = "BM65"  !CDS_PN = "BM65";
"USB3_8_PCIE1_TXP":   PN = "BR65"  !CDS_PN = "BR65";
"USB3_9_PCIE2_RXN":   PN = "AW71"  !CDS_PN = "AW71";
"USB3_9_PCIE2_RXP":   PN = "AW69"  !CDS_PN = "AW69";
"USB3_9_PCIE2_TXN":   PN = "BK65"  !CDS_PN = "BK65";
"USB3_9_PCIE2_TXP":   PN = "BL66"  !CDS_PN = "BL66";
"USB3_10_PCIE3_GBE_RXN":   PN = "AV72"  !CDS_PN = "AV72";
"USB3_10_PCIE3_GBE_RXP":   PN = "AV70"  !CDS_PN = "AV70";
"USB3_10_PCIE3_GBE_TXN":   PN = "BH61"  !CDS_PN = "BH61";
"USB3_10_PCIE3_GBE_TXP":   PN = "BK61"  !CDS_PN = "BK61";
BODY = "RES","I229": #LOCATION = "R7B8" !CDS_LOCATION = "R7B8" #SEC = "1" !CDS_SEC = "1";
"A":   PN = "1"  !CDS_PN = "1";
"B":   PN = "2"  !CDS_PN = "2";
BODY = "RES","I230": #LOCATION = "R7B7" !CDS_LOCATION = "R7B7" #SEC = "1" !CDS_SEC = "1";
"A":   PN = "1"  !CDS_PN = "1";
"B":   PN = "2"  !CDS_PN = "2";
BODY = "RES","I234": #LOCATION = "R3M9" !CDS_LOCATION = "R3M9" &SEC = "1" #&CDS_SEC = "1";
"A":   PN = "1"  !CDS_PN = "1";
"B":   PN = "2"  !CDS_PN = "2";
BODY = "RES","I235": #LOCATION = "R3M8" !CDS_LOCATION = "R3M8" &SEC = "1" #&CDS_SEC = "1";
"A":   PN = "1"  !CDS_PN = "1";
"B":   PN = "2"  !CDS_PN = "2";
DRAWING = "@baseboard_fab2_lib.baseboard_fab2(sch_1):page117";
BODY = "LBG_CORE_QAT_EXT_D","I9": #LOCATION = "U7C1" !CDS_LOCATION = "U7C1" #SEC = "4" !CDS_SEC = "4";
"DMI_RXN<0>":   PN = "D42"  !CDS_PN = "D42";
"DMI_RXN<1>":   PN = "C43"  !CDS_PN = "C43";
"DMI_RXN<2>":   PN = "D44"  !CDS_PN = "D44";
"DMI_RXN<3>":   PN = "C45"  !CDS_PN = "C45";
"DMI_RXP<0>":   PN = "B42"  !CDS_PN = "B42";
"DMI_RXP<1>":   PN = "A43"  !CDS_PN = "A43";
"DMI_RXP<2>":   PN = "B44"  !CDS_PN = "B44";
"DMI_RXP<3>":   PN = "A45"  !CDS_PN = "A45";
"DMI_TXN<0>":   PN = "H46"  !CDS_PN = "H46";
"DMI_TXN<1>":   PN = "J48"  !CDS_PN = "J48";
"DMI_TXN<2>":   PN = "K50"  !CDS_PN = "K50";
"DMI_TXN<3>":   PN = "P52"  !CDS_PN = "P52";
"DMI_TXP<0>":   PN = "K46"  !CDS_PN = "K46";
"DMI_TXP<1>":   PN = "H50"  !CDS_PN = "H50";
"DMI_TXP<2>":   PN = "M52"  !CDS_PN = "M52";
"DMI_TXP<3>":   PN = "N54"  !CDS_PN = "N54";
"PCIEUP_0_RXN":   PN = "C48"  !CDS_PN = "C48";
"PCIEUP_0_RXP":   PN = "A48"  !CDS_PN = "A48";
"PCIEUP_0_TXN":   PN = "J52"  !CDS_PN = "J52";
"PCIEUP_0_TXP":   PN = "G52"  !CDS_PN = "G52";
"PCIEUP_1_RXN":   PN = "D49"  !CDS_PN = "D49";
"PCIEUP_1_RXP":   PN = "B49"  !CDS_PN = "B49";
"PCIEUP_1_TXN":   PN = "P56"  !CDS_PN = "P56";
"PCIEUP_1_TXP":   PN = "M56"  !CDS_PN = "M56";
"PCIEUP_2_RXN":   PN = "C50"  !CDS_PN = "C50";
"PCIEUP_2_RXP":   PN = "A50"  !CDS_PN = "A50";
"PCIEUP_2_TXN":   PN = "H54"  !CDS_PN = "H54";
"PCIEUP_2_TXP":   PN = "G56"  !CDS_PN = "G56";
"PCIEUP_3_RXN":   PN = "D51"  !CDS_PN = "D51";
"PCIEUP_3_RXP":   PN = "B51"  !CDS_PN = "B51";
"PCIEUP_3_TXN":   PN = "J56"  !CDS_PN = "J56";
"PCIEUP_3_TXP":   PN = "K58"  !CDS_PN = "K58";
"PCIEUP_4_RXN":   PN = "C52"  !CDS_PN = "C52";
"PCIEUP_4_RXP":   PN = "A52"  !CDS_PN = "A52";
"PCIEUP_4_TXN":   PN = "N58"  !CDS_PN = "N58";
"PCIEUP_4_TXP":   PN = "M59"  !CDS_PN = "M59";
"PCIEUP_5_RXN":   PN = "D53"  !CDS_PN = "D53";
"PCIEUP_5_RXP":   PN = "B53"  !CDS_PN = "B53";
"PCIEUP_5_TXN":   PN = "N61"  !CDS_PN = "N61";
"PCIEUP_5_TXP":   PN = "K61"  !CDS_PN = "K61";
"PCIEUP_6_RXN":   PN = "C54"  !CDS_PN = "C54";
"PCIEUP_6_RXP":   PN = "A54"  !CDS_PN = "A54";
"PCIEUP_6_TXN":   PN = "H61"  !CDS_PN = "H61";
"PCIEUP_6_TXP":   PN = "J63"  !CDS_PN = "J63";
"PCIEUP_7_RXN":   PN = "D55"  !CDS_PN = "D55";
"PCIEUP_7_RXP":   PN = "B55"  !CDS_PN = "B55";
"PCIEUP_7_TXN":   PN = "P59"  !CDS_PN = "P59";
"PCIEUP_7_TXP":   PN = "R61"  !CDS_PN = "R61";
"PCIEUP_8_RXN":   PN = "C57"  !CDS_PN = "C57";
"PCIEUP_8_RXP":   PN = "A57"  !CDS_PN = "A57";
"PCIEUP_8_TXN":   PN = "K65"  !CDS_PN = "K65";
"PCIEUP_8_TXP":   PN = "M63"  !CDS_PN = "M63";
"PCIEUP_9_RXN":   PN = "D58"  !CDS_PN = "D58";
"PCIEUP_9_RXP":   PN = "B58"  !CDS_PN = "B58";
"PCIEUP_9_TXN":   PN = "J66"  !CDS_PN = "J66";
"PCIEUP_9_TXP":   PN = "M66"  !CDS_PN = "M66";
"PCIEUP_10_RXN":   PN = "C59"  !CDS_PN = "C59";
"PCIEUP_10_RXP":   PN = "A59"  !CDS_PN = "A59";
"PCIEUP_10_TXN":   PN = "N65"  !CDS_PN = "N65";
"PCIEUP_10_TXP":   PN = "P66"  !CDS_PN = "P66";
"PCIEUP_11_RXN":   PN = "D60"  !CDS_PN = "D60";
"PCIEUP_11_RXP":   PN = "B60"  !CDS_PN = "B60";
"PCIEUP_11_TXN":   PN = "T59"  !CDS_PN = "T59";
"PCIEUP_11_TXP":   PN = "V59"  !CDS_PN = "V59";
"PCIEUP_12_RXN":   PN = "C61"  !CDS_PN = "C61";
"PCIEUP_12_RXP":   PN = "A61"  !CDS_PN = "A61";
"PCIEUP_12_TXN":   PN = "R65"  !CDS_PN = "R65";
"PCIEUP_12_TXP":   PN = "U65"  !CDS_PN = "U65";
"PCIEUP_13_RXN":   PN = "D62"  !CDS_PN = "D62";
"PCIEUP_13_RXP":   PN = "B62"  !CDS_PN = "B62";
"PCIEUP_13_TXN":   PN = "T63"  !CDS_PN = "T63";
"PCIEUP_13_TXP":   PN = "U61"  !CDS_PN = "U61";
"PCIEUP_14_RXN":   PN = "C63"  !CDS_PN = "C63";
"PCIEUP_14_RXP":   PN = "A63"  !CDS_PN = "A63";
"PCIEUP_14_TXN":   PN = "W65"  !CDS_PN = "W65";
"PCIEUP_14_TXP":   PN = "V63"  !CDS_PN = "V63";
"PCIEUP_15_RXN":   PN = "D64"  !CDS_PN = "D64";
"PCIEUP_15_RXP":   PN = "B64"  !CDS_PN = "B64";
"PCIEUP_15_TXN":   PN = "Y66"  !CDS_PN = "Y66";
"PCIEUP_15_TXP":   PN = "AA65"  !CDS_PN = "AA65";
DRAWING = "@baseboard_fab2_lib.baseboard_fab2(sch_1):page118";
BODY = "RES","I66": #LOCATION = "R3N9" !CDS_LOCATION = "R3N9" #SEC = "1" !CDS_SEC = "1";
"A":   PN = "1"  !CDS_PN = "1";
"B":   PN = "2"  !CDS_PN = "2";
BODY = "RES","I67": #LOCATION = "R3N14" !CDS_LOCATION = "R3N14" #SEC = "1" !CDS_SEC = "1";
"A":   PN = "1"  !CDS_PN = "1";
"B":   PN = "2"  !CDS_PN = "2";
BODY = "RES","I71": #LOCATION = "R3N13" !CDS_LOCATION = "R3N13" #SEC = "1" !CDS_SEC = "1";
"A":   PN = "1"  !CDS_PN = "1";
"B":   PN = "2"  !CDS_PN = "2";
BODY = "LBG_CORE_QAT_EXT_D","I73": #LOCATION = "U7C1" !CDS_LOCATION = "U7C1" #SEC = "5" !CDS_SEC = "5";
"CPU_TRST_N":   PN = "AT56"  !CDS_PN = "AT56";
"DSW_PWROK":   PN = "K13"  !CDS_PN = "K13";
"GPD0":   PN = "G15"  !CDS_PN = "G15";
"GPD1_ACPRESENT":   PN = "H13"  !CDS_PN = "H13";
"GPD2_GBE_WAKE_N":   PN = "M11"  !CDS_PN = "M11";
"GPD3_PWRBTN_N":   PN = "C15"  !CDS_PN = "C15";
"GPD4_SLP_S3_N":   PN = "D14"  !CDS_PN = "D14";
"GPD5_SLP_S4_N":   PN = "B16"  !CDS_PN = "B16";
"GPD6_SLP_A_N":   PN = "G11"  !CDS_PN = "G11";
"GPD7":   PN = "H9"  !CDS_PN = "H9";
"GPD8_SUSCLK":   PN = "C13"  !CDS_PN = "C13";
"GPD9":   PN = "A15"  !CDS_PN = "A15";
"GPD10_SLP_S5_N":   PN = "B14"  !CDS_PN = "B14";
"GPD11_GBEPHY":   PN = "A13"  !CDS_PN = "A13";
"ITP_PMODE":   PN = "AR54"  !CDS_PN = "AR54";
"JTAG_TCK":   PN = "AL56"  !CDS_PN = "AL56";
"JTAG_TDI":   PN = "AN54"  !CDS_PN = "AN54";
"JTAG_TDO":   PN = "AP56"  !CDS_PN = "AP56";
"JTAG_TMS":   PN = "AH54"  !CDS_PN = "AH54";
"JTAGX":   PN = "AF54"  !CDS_PN = "AF54";
"LAN_RBIAS_0":   PN = "BB29"  !CDS_PN = "BB29";
"LAN_RBIAS_1":   PN = "BD42"  !CDS_PN = "BD42";
"LAN_RX_P0N":   PN = "BH31"  !CDS_PN = "BH31";
"LAN_RX_P0P":   PN = "BF31"  !CDS_PN = "BF31";
"LAN_RX_P1N":   PN = "BG29"  !CDS_PN = "BG29";
"LAN_RX_P1P":   PN = "BJ29"  !CDS_PN = "BJ29";
"LAN_RX_P2N":   PN = "BJ37"  !CDS_PN = "BJ37";
"LAN_RX_P2P":   PN = "BG37"  !CDS_PN = "BG37";
"LAN_RX_P3N":   PN = "BF35"  !CDS_PN = "BF35";
"LAN_RX_P3P":   PN = "BH35"  !CDS_PN = "BH35";
"LAN_TX_P0N":   PN = "BM27"  !CDS_PN = "BM27";
"LAN_TX_P0P":   PN = "BR27"  !CDS_PN = "BR27";
"LAN_TX_P1N":   PN = "BM24"  !CDS_PN = "BM24";
"LAN_TX_P1P":   PN = "BR24"  !CDS_PN = "BR24";
"LAN_TX_P2N":   PN = "BM35"  !CDS_PN = "BM35";
"LAN_TX_P2P":   PN = "BR35"  !CDS_PN = "BR35";
"LAN_TX_P3N":   PN = "BR31"  !CDS_PN = "BR31";
"LAN_TX_P3P":   PN = "BM31"  !CDS_PN = "BM31";
"LAN_XTAL_IN":   PN = "BV16"  !CDS_PN = "BV16";
"LAN_XTAL_OUT":   PN = "BY16"  !CDS_PN = "BY16";
"PCH_PWROK":   PN = "R17"  !CDS_PN = "R17";
"PECI":   PN = "U9"  !CDS_PN = "U9";
"PLTRST_CPU_N":   PN = "U17"  !CDS_PN = "U17";
"PM_SYNC":   PN = "U13"  !CDS_PN = "U13";
"PM_SYNC2":   PN = "V7"  !CDS_PN = "V7";
"PRDY_N":   PN = "AD54"  !CDS_PN = "AD54";
"PREQ_N":   PN = "U54"  !CDS_PN = "U54";
"PROC_PWRGD":   PN = "R9"  !CDS_PN = "R9";
"RSMRST_N":   PN = "P15"  !CDS_PN = "P15";
"RSVD<32>":   PN = "AA54"  !CDS_PN = "AA54";
"RSVD<33>":   PN = "V56"  !CDS_PN = "V56";
"RSVD<34>":   PN = "Y56"  !CDS_PN = "Y56";
"RSVD<35>":   PN = "W54"  !CDS_PN = "W54";
"RSVD<36>":   PN = "AK54"  !CDS_PN = "AK54";
"RSVD<37>":   PN = "BN29"  !CDS_PN = "BN29";
"RSVD<38>":   PN = "BL29"  !CDS_PN = "BL29";
"RSVD<39>":   PN = "BL26"  !CDS_PN = "BL26";
"RSVD<40>":   PN = "BN26"  !CDS_PN = "BN26";
"RSVD<41>":   PN = "BJ40"  !CDS_PN = "BJ40";
"RSVD<42>":   PN = "BG40"  !CDS_PN = "BG40";
"RSVD<43>":   PN = "BL33"  !CDS_PN = "BL33";
"RSVD<44>":   PN = "BN33"  !CDS_PN = "BN33";
"RSVD<45>":   PN = "P22"  !CDS_PN = "P22";
"RSVD<53>":   PN = "P26"  !CDS_PN = "P26";
"RSVD<54>":   PN = "R24"  !CDS_PN = "R24";
"SLP_GBE_N":   PN = "M15"  !CDS_PN = "M15";
"SLP_SUS_N":   PN = "P7"  !CDS_PN = "P7";
"SYS_PWROK":   PN = "BY19"  !CDS_PN = "BY19";
"SYS_RESET_N":   PN = "BV19"  !CDS_PN = "BV19";
"THRMTRIP_N":   PN = "V15"  !CDS_PN = "V15";
"TRIGGER_IN":   PN = "M7"  !CDS_PN = "M7";
"TRIGGER_OUT":   PN = "R13"  !CDS_PN = "R13";
"WAKE_N":   PN = "K9"  !CDS_PN = "K9";
BODY = "CRYSTAL","I76": #LOCATION = "Y8C1" !CDS_LOCATION = "Y8C1" #SEC = "1" !CDS_SEC = "1";
"A":   PN = "1"  !CDS_PN = "1";
"B":   PN = "3"  !CDS_PN = "3";
BODY = "CAP","I77": #LOCATION = "C8C2" !CDS_LOCATION = "C8C2" #SEC = "1" !CDS_SEC = "1";
"A":   PN = "1"  !CDS_PN = "1";
"B":   PN = "2"  !CDS_PN = "2";
BODY = "CAP","I79": #LOCATION = "C8C1" !CDS_LOCATION = "C8C1" #SEC = "1" !CDS_SEC = "1";
"A":   PN = "1"  !CDS_PN = "1";
"B":   PN = "2"  !CDS_PN = "2";
BODY = "RES","I96": #LOCATION = "R2N4" !CDS_LOCATION = "R2N4" #SEC = "1" !CDS_SEC = "1";
"A":   PN = "1"  !CDS_PN = "1";
"B":   PN = "2"  !CDS_PN = "2";
BODY = "RES","I99": #LOCATION = "R2M6" !CDS_LOCATION = "R2M6" #SEC = "1" !CDS_SEC = "1";
"A":   PN = "1"  !CDS_PN = "1";
"B":   PN = "2"  !CDS_PN = "2";
BODY = "RES","I120": #LOCATION = "R8C24" !CDS_LOCATION = "R8C24" #SEC = "1" !CDS_SEC = "1";
"A":   PN = "1"  !CDS_PN = "1";
"B":   PN = "2"  !CDS_PN = "2";
BODY = "RES","I125": #LOCATION = "R8C23" !CDS_LOCATION = "R8C23" #SEC = "1" !CDS_SEC = "1";
"A":   PN = "1"  !CDS_PN = "1";
"B":   PN = "2"  !CDS_PN = "2";
BODY = "RES","I128": #LOCATION = "R2N6" !CDS_LOCATION = "R2N6" #SEC = "1" !CDS_SEC = "1";
"A":   PN = "1"  !CDS_PN = "1";
"B":   PN = "2"  !CDS_PN = "2";
BODY = "RES","I131": #LOCATION = "R7D23" !CDS_LOCATION = "R7D23" #SEC = "1" !CDS_SEC = "1";
"A":   PN = "1"  !CDS_PN = "1";
"B":   PN = "2"  !CDS_PN = "2";
BODY = "CAP_A","I136": #LOCATION = "C7D1" !CDS_LOCATION = "C7D1" #SEC = "1" !CDS_SEC = "1";
"A":   PN = "1"  !CDS_PN = "1";
"B":   PN = "2"  !CDS_PN = "2";
BODY = "74CBTLV1G125","I142": #LOCATION = "U7D1" !CDS_LOCATION = "U7D1" &SEC = "1" #&CDS_SEC = "1";
"A":   PN = "2"  !CDS_PN = "2";
"B":   PN = "4"  !CDS_PN = "4";
"OE_N":   PN = "1"  !CDS_PN = "1";
BODY = "RES","I144": #LOCATION = "R7C23" !CDS_LOCATION = "R7C23" #SEC = "1" !CDS_SEC = "1";
"A":   PN = "1"  !CDS_PN = "1";
"B":   PN = "2"  !CDS_PN = "2";
DRAWING = "@baseboard_fab2_lib.baseboard_fab2(sch_1):page119";
BODY = "LBG_CORE_QAT_EXT_D","I115": #LOCATION = "U7C1" !CDS_LOCATION = "U7C1" #SEC = "6" !CDS_SEC = "6";
"GPP_A0_RCIN_N_ESPI_ALERT1_N":   PN = "N3"  !CDS_PN = "N3";
"GPP_A1_LAD0_ESPI_IO0":   PN = "Y3"  !CDS_PN = "Y3";
"GPP_A2_LAD1_ESPI_IO1":   PN = "N1"  !CDS_PN = "N1";
"GPP_A3_LAD2_ESPI_IO2":   PN = "W2"  !CDS_PN = "W2";
"GPP_A4_LAD3_ESPI_IO3":   PN = "Y1"  !CDS_PN = "Y1";
"GPP_A5_LFRAME_N_ESPI_CS0_N":   PN = "P4"  !CDS_PN = "P4";
"GPP_A6_SERIRQ_ESPI_CS1_N":   PN = "P2"  !CDS_PN = "P2";
"GPP_A7_PIRQA_N_ESPI_ALERT0_N":   PN = "AA2"  !CDS_PN = "AA2";
"GPP_A8_CLKRUN_N":   PN = "AB1"  !CDS_PN = "AB1";
"GPP_A9_CLKOUT_LPC0_ESPI_CLK":   PN = "R3"  !CDS_PN = "R3";
"GPP_A10_CLKOUT_LPC1":   PN = "AA4"  !CDS_PN = "AA4";
"GPP_A11_PME_N":   PN = "AC2"  !CDS_PN = "AC2";
"GPP_A12_BMBUSY_N_SXEXITHLDOFF_N":   PN = "R1"  !CDS_PN = "R1";
"GPP_A13_SUSWARN_N_SUSPWRDNACK":   PN = "T4"  !CDS_PN = "T4";
"GPP_A14_ESPI_RESET_N":   PN = "AB3"  !CDS_PN = "AB3";
"GPP_A15_SUSACK_N":   PN = "AC4"  !CDS_PN = "AC4";
"GPP_A16_CLKOUT_LPC2":   PN = "T2"  !CDS_PN = "T2";
"GPP_A17":   PN = "AD1"  !CDS_PN = "AD1";
"GPP_A18":   PN = "AD3"  !CDS_PN = "AD3";
"GPP_A19":   PN = "V3"  !CDS_PN = "V3";
"GPP_A20":   PN = "W4"  !CDS_PN = "W4";
"GPP_A21":   PN = "AE2"  !CDS_PN = "AE2";
"GPP_A22":   PN = "AE4"  !CDS_PN = "AE4";
"GPP_A23":   PN = "V1"  !CDS_PN = "V1";
"GPP_B0_CORE_VID0":   PN = "BL7"  !CDS_PN = "BL7";
"GPP_B1_CORE_VID1":   PN = "BH9"  !CDS_PN = "BH9";
"GPP_B2":   PN = "BN15"  !CDS_PN = "BN15";
"GPP_B3_CPU_GP2":   PN = "BR9"  !CDS_PN = "BR9";
"GPP_B4_CPU_GP3":   PN = "BN7"  !CDS_PN = "BN7";
"GPP_B5_SRCCLKREQ0_N":   PN = "BK17"  !CDS_PN = "BK17";
"GPP_B6_SRCCLKREQ1_N":   PN = "BG18"  !CDS_PN = "BG18";
"GPP_B7_SRCCLKREQ2_N":   PN = "BR13"  !CDS_PN = "BR13";
"GPP_B8_SRCCLKREQ3_N":   PN = "BN11"  !CDS_PN = "BN11";
"GPP_B9_SRCCLKREQ4_N":   PN = "BH20"  !CDS_PN = "BH20";
"GPP_B10_SRCCLKREQ5_N":   PN = "BL11"  !CDS_PN = "BL11";
"GPP_B11":   PN = "BK9"  !CDS_PN = "BK9";
"GPP_B12_GLB_RST_WARN_N":   PN = "BL18"  !CDS_PN = "BL18";
"GPP_B13_PLTRST_N":   PN = "BN18"  !CDS_PN = "BN18";
"GPP_B14_SPKR":   PN = "BH13"  !CDS_PN = "BH13";
"GPP_B15":   PN = "BK13"  !CDS_PN = "BK13";
"GPP_B16":   PN = "BG22"  !CDS_PN = "BG22";
"GPP_B17":   PN = "BG15"  !CDS_PN = "BG15";
"GPP_B18":   PN = "BL15"  !CDS_PN = "BL15";
"GPP_B19":   PN = "BK20"  !CDS_PN = "BK20";
"GPP_B20":   PN = "BJ22"  !CDS_PN = "BJ22";
"GPP_B21":   PN = "BH17"  !CDS_PN = "BH17";
"GPP_B22":   PN = "BR17"  !CDS_PN = "BR17";
"GPP_B23_MEIE_SML1ALRT_N_PHOT_N":   PN = "BM20"  !CDS_PN = "BM20";
"GPP_C0_SMBCLK":   PN = "BW28"  !CDS_PN = "BW28";
"GPP_C1_SMBDATA":   PN = "BV27"  !CDS_PN = "BV27";
"GPP_C2_SMBALERT_N":   PN = "BY27"  !CDS_PN = "BY27";
"GPP_C3_SML0CLK_IE":   PN = "BV29"  !CDS_PN = "BV29";
"GPP_C4_SML0DATA_IE":   PN = "BW30"  !CDS_PN = "BW30";
"GPP_C5_SML0ALERT_IE_N":   PN = "BW34"  !CDS_PN = "BW34";
"GPP_C6_SML1CLK_IE":   PN = "CA28"  !CDS_PN = "CA28";
"GPP_C7_SML1DATA_IE":   PN = "BV35"  !CDS_PN = "BV35";
"GPP_C8":   PN = "BW32"  !CDS_PN = "BW32";
"GPP_C9":   PN = "BY29"  !CDS_PN = "BY29";
"GPP_C10":   PN = "BV31"  !CDS_PN = "BV31";
"GPP_C11":   PN = "BV33"  !CDS_PN = "BV33";
"GPP_C12":   PN = "CA30"  !CDS_PN = "CA30";
"GPP_C13":   PN = "BV38"  !CDS_PN = "BV38";
"GPP_C14":   PN = "BY38"  !CDS_PN = "BY38";
"GPP_C15":   PN = "CA32"  !CDS_PN = "CA32";
"GPP_C16":   PN = "BW37"  !CDS_PN = "BW37";
"GPP_C17":   PN = "BY31"  !CDS_PN = "BY31";
"GPP_C18":   PN = "BY35"  !CDS_PN = "BY35";
"GPP_C19":   PN = "BW39"  !CDS_PN = "BW39";
"GPP_C20":   PN = "CA39"  !CDS_PN = "CA39";
"GPP_C21":   PN = "BY33"  !CDS_PN = "BY33";
"GPP_C22":   PN = "CA34"  !CDS_PN = "CA34";
"GPP_C23":   PN = "CA37"  !CDS_PN = "CA37";
"GPP_D0":   PN = "BR42"  !CDS_PN = "BR42";
"GPP_D1":   PN = "BK46"  !CDS_PN = "BK46";
"GPP_D2":   PN = "BJ44"  !CDS_PN = "BJ44";
"GPP_D3":   PN = "BW45"  !CDS_PN = "BW45";
"GPP_D4":   PN = "BM42"  !CDS_PN = "BM42";
"GPP_D5":   PN = "BM38"  !CDS_PN = "BM38";
"GPP_D6":   PN = "BW41"  !CDS_PN = "BW41";
"GPP_D7":   PN = "CA45"  !CDS_PN = "CA45";
"GPP_D8":   PN = "BR38"  !CDS_PN = "BR38";
"GPP_D9_SSATA_DEVSLP3":   PN = "BY42"  !CDS_PN = "BY42";
"GPP_D10_SSATA_DEVSLP4":   PN = "BV47"  !CDS_PN = "BV47";
"GPP_D11_SSATA_DEVSLP5":   PN = "BY47"  !CDS_PN = "BY47";
"GPP_D12_SSATA_SDATAOUT1":   PN = "BN40"  !CDS_PN = "BN40";
"GPP_D13_SML0BCLK_IE":   PN = "BY44"  !CDS_PN = "BY44";
"GPP_D14_SML0BDATA_IE":   PN = "BL44"  !CDS_PN = "BL44";
"GPP_D15_SSATA_SDATAOUT0":   PN = "BW43"  !CDS_PN = "BW43";
"GPP_D16_SML0BALERT_IE_N":   PN = "BV42"  !CDS_PN = "BV42";
"GPP_D17":   PN = "BW48"  !CDS_PN = "BW48";
"GPP_D18":   PN = "CA41"  !CDS_PN = "CA41";
"GPP_D19":   PN = "CA43"  !CDS_PN = "CA43";
"GPP_D20":   PN = "CA48"  !CDS_PN = "CA48";
"GPP_D21_IE_UART_RX":   PN = "BV44"  !CDS_PN = "BV44";
"GPP_D22_IE_UART_TX":   PN = "BR46"  !CDS_PN = "BR46";
"GPP_D23":   PN = "BN44"  !CDS_PN = "BN44";
BODY = "RES","I172": #LOCATION = "R2M3" !CDS_LOCATION = "R2M3" #SEC = "1" !CDS_SEC = "1";
"A":   PN = "1"  !CDS_PN = "1";
"B":   PN = "2"  !CDS_PN = "2";
BODY = "RES","I173": #LOCATION = "R2N1" !CDS_LOCATION = "R2N1" #SEC = "1" !CDS_SEC = "1";
"A":   PN = "1"  !CDS_PN = "1";
"B":   PN = "2"  !CDS_PN = "2";
BODY = "RES","I174": #LOCATION = "R2M7" !CDS_LOCATION = "R2M7" #SEC = "1" !CDS_SEC = "1";
"A":   PN = "1"  !CDS_PN = "1";
"B":   PN = "2"  !CDS_PN = "2";
BODY = "FET_N_DUAL","I175": #LOCATION = "Q9A2" !CDS_LOCATION = "Q9A2" #SEC = "1" !CDS_SEC = "1";
"DRAIN<0>":   PN = "6"  !CDS_PN = "6";
"GATE<0>":   PN = "2"  !CDS_PN = "2";
"SOURCE<0>":   PN = "1"  !CDS_PN = "1";
BODY = "RES","I178": #LOCATION = "R9A20" !CDS_LOCATION = "R9A20" #SEC = "1" !CDS_SEC = "1";
"A":   PN = "1"  !CDS_PN = "1";
"B":   PN = "2"  !CDS_PN = "2";
BODY = "LED","I179": #LOCATION = "DS9A5" !CDS_LOCATION = "DS9A5" #SEC = "1" !CDS_SEC = "1";
"A":   PN = "1"  !CDS_PN = "1";
"C":   PN = "2"  !CDS_PN = "2";
BODY = "FET_N_DUAL","I180": #LOCATION = "Q9A2" !CDS_LOCATION = "Q9A2" #SEC = "2" !CDS_SEC = "2";
"DRAIN<0>":   PN = "3"  !CDS_PN = "3";
"GATE<0>":   PN = "5"  !CDS_PN = "5";
"SOURCE<0>":   PN = "4"  !CDS_PN = "4";
BODY = "RES","I183": #LOCATION = "R9A18" !CDS_LOCATION = "R9A18" #SEC = "1" !CDS_SEC = "1";
"A":   PN = "1"  !CDS_PN = "1";
"B":   PN = "2"  !CDS_PN = "2";
BODY = "RES","I186": #LOCATION = "R9A21" !CDS_LOCATION = "R9A21" #SEC = "1" !CDS_SEC = "1";
"A":   PN = "1"  !CDS_PN = "1";
"B":   PN = "2"  !CDS_PN = "2";
BODY = "RES","I189": #LOCATION = "R7C26" !CDS_LOCATION = "R7C26" #SEC = "1" !CDS_SEC = "1";
"A":   PN = "1"  !CDS_PN = "1";
"B":   PN = "2"  !CDS_PN = "2";
BODY = "RES","I213": #LOCATION = "R2U48" !CDS_LOCATION = "R2U48" #SEC = "1" !CDS_SEC = "1";
"A":   PN = "1"  !CDS_PN = "1";
"B":   PN = "2"  !CDS_PN = "2";
BODY = "RES","I215": #LOCATION = "R2U50" !CDS_LOCATION = "R2U50" #SEC = "1" !CDS_SEC = "1";
"A":   PN = "1"  !CDS_PN = "1";
"B":   PN = "2"  !CDS_PN = "2";
DRAWING = "@baseboard_fab2_lib.baseboard_fab2(sch_1):page120";
BODY = "LBG_CORE_QAT_EXT_D","I147": #LOCATION = "U7C1" !CDS_LOCATION = "U7C1" #SEC = "7" !CDS_SEC = "7";
"GPIO_RCOMP_3P3":   PN = "BY25"  !CDS_PN = "BY25";
"GPP_E0_SATAXPCIE0_SATAGP0":   PN = "BH50"  !CDS_PN = "BH50";
"GPP_E1_SATAXPCIE1_SATAGP1":   PN = "AY52"  !CDS_PN = "AY52";
"GPP_E2_SATAXPCIE2_SATAGP2":   PN = "BG52"  !CDS_PN = "BG52";
"GPP_E3_CPU_GP0":   PN = "BE52"  !CDS_PN = "BE52";
"GPP_E4_SATA_DEVSLP0":   PN = "AV52"  !CDS_PN = "AV52";
"GPP_E5_SATA_DEVSLP1":   PN = "AT52"  !CDS_PN = "AT52";
"GPP_E6_SATA_DEVSLP2":   PN = "BB52"  !CDS_PN = "BB52";
"GPP_E7_CPU_GP1":   PN = "BJ48"  !CDS_PN = "BJ48";
"GPP_E8_SATA_LED_N":   PN = "AV56"  !CDS_PN = "AV56";
"GPP_E9_USB2_OC0_N":   PN = "BL48"  !CDS_PN = "BL48";
"GPP_E10_USB2_OC1_N":   PN = "BN48"  !CDS_PN = "BN48";
"GPP_E11_USB2_OC2_N":   PN = "AW54"  !CDS_PN = "AW54";
"GPP_E12_USB2_OC3_N":   PN = "AU58"  !CDS_PN = "AU58";
"GPP_F0_SATAXPCIE3_SATAGP3":   PN = "AG7"  !CDS_PN = "AG7";
"GPP_F1_SATAXPCIE4_SATAGP4":   PN = "AK9"  !CDS_PN = "AK9";
"GPP_F2_SATAXPCIE5_SATAGP5":   PN = "AK20"  !CDS_PN = "AK20";
"GPP_F3_SATAXPCIE6_SATAGP6":   PN = "AK13"  !CDS_PN = "AK13";
"GPP_F4_SATAXPCIE7_SATAGP7":   PN = "AH13"  !CDS_PN = "AH13";
"GPP_F5_SATA_DEVSLP3":   PN = "AH17"  !CDS_PN = "AH17";
"GPP_F6_SATA_DEVSLP4":   PN = "AL18"  !CDS_PN = "AL18";
"GPP_F7_SATA_DEVSLP5":   PN = "AK17"  !CDS_PN = "AK17";
"GPP_F8_SATA_DEVSLP6":   PN = "AH9"  !CDS_PN = "AH9";
"GPP_F9_SATA_DEVSLP7":   PN = "AR20"  !CDS_PN = "AR20";
"GPP_F10_SATA_SCLOCK":   PN = "AL7"  !CDS_PN = "AL7";
"GPP_F11_SATA_SLOAD":   PN = "AR9"  !CDS_PN = "AR9";
"GPP_F12_SATA_SDATAOUT1":   PN = "AP7"  !CDS_PN = "AP7";
"GPP_F13_SATA_SDATAOUT0":   PN = "AP11"  !CDS_PN = "AP11";
"GPP_F14_SSATA_LED_N":   PN = "AL11"  !CDS_PN = "AL11";
"GPP_F15_USB2_OC4_N":   PN = "AR13"  !CDS_PN = "AR13";
"GPP_F16_USB2_OC5_N":   PN = "AU13"  !CDS_PN = "AU13";
"GPP_F17_USB2_OC6_N":   PN = "AP15"  !CDS_PN = "AP15";
"GPP_F18_USB2_OC7_N":   PN = "AL15"  !CDS_PN = "AL15";
"GPP_F19_LAN_SMBCLK":   PN = "AU9"  !CDS_PN = "AU9";
"GPP_F20_LAN_SMBDATA":   PN = "AU20"  !CDS_PN = "AU20";
"GPP_F21_LAN_SMBALRT_N":   PN = "AR17"  !CDS_PN = "AR17";
"GPP_F22_SSATA_SCLOCK":   PN = "AP18"  !CDS_PN = "AP18";
"GPP_F23_SSATA_SLOAD":   PN = "AU17"  !CDS_PN = "AU17";
"GPP_G0_FANTACH0_FANTACH0IE":   PN = "AY11"  !CDS_PN = "AY11";
"GPP_G1_FANTACH1_FANTACH1IE":   PN = "AV15"  !CDS_PN = "AV15";
"GPP_G2_FANTACH2_FANTACH2IE":   PN = "BE22"  !CDS_PN = "BE22";
"GPP_G3_FANTACH3_FANTACH3IE":   PN = "AY7"  !CDS_PN = "AY7";
"GPP_G4_FANTACH4_FANTACH4IE":   PN = "BA9"  !CDS_PN = "BA9";
"GPP_G5_FANTACH5_FANTACH5IE":   PN = "AW20"  !CDS_PN = "AW20";
"GPP_G6_FANTACH6_FANTACH6IE":   PN = "AV18"  !CDS_PN = "AV18";
"GPP_G7_FANTACH7_FANTACH7IE":   PN = "AY15"  !CDS_PN = "AY15";
"GPP_G8_FANPWM0_FANPWM0IE":   PN = "BG11"  !CDS_PN = "BG11";
"GPP_G9_FANPWM1_FAMPWM1IE":   PN = "AV11"  !CDS_PN = "AV11";
"GPP_G10_FANPWM2_FANPWM2IE":   PN = "BE11"  !CDS_PN = "BE11";
"GPP_G11_FANPWM3_FANPMW3IE":   PN = "BA20"  !CDS_PN = "BA20";
"GPP_G12":   PN = "BD13"  !CDS_PN = "BD13";
"GPP_G13":   PN = "AY18"  !CDS_PN = "AY18";
"GPP_G14":   PN = "AV7"  !CDS_PN = "AV7";
"GPP_G15":   PN = "BE18"  !CDS_PN = "BE18";
"GPP_G16":   PN = "BD17"  !CDS_PN = "BD17";
"GPP_G17_ADR_COMPLETE":   PN = "BD9"  !CDS_PN = "BD9";
"GPP_G18_NMI_N":   PN = "BE7"  !CDS_PN = "BE7";
"GPP_G19_SMI_N":   PN = "BE15"  !CDS_PN = "BE15";
"GPP_G20_SSATA_DEVSLP0":   PN = "BA17"  !CDS_PN = "BA17";
"GPP_G21_SSATA_DEVSLP1":   PN = "BG7"  !CDS_PN = "BG7";
"GPP_G22_SSATA_DEVSLP2":   PN = "BD20"  !CDS_PN = "BD20";
"GPP_G23_SSATAXPCIE0_SSATAGP0":   PN = "BA13"  !CDS_PN = "BA13";
"GPP_H0_SRCCLKREQ6_N":   PN = "AT4"  !CDS_PN = "AT4";
"GPP_H1_SRCCLKREQ7_N":   PN = "AW4"  !CDS_PN = "AW4";
"GPP_H2_SRCCLKREQ8_N":   PN = "AV3"  !CDS_PN = "AV3";
"GPP_H3_SRCCLKREQ9_N":   PN = "AR1"  !CDS_PN = "AR1";
"GPP_H4_SRCCLKREQ10_N":   PN = "AT2"  !CDS_PN = "AT2";
"GPP_H5_SRCCLKREQ11_N":   PN = "AY3"  !CDS_PN = "AY3";
"GPP_H6_SRCCLKREQ12_N":   PN = "AW2"  !CDS_PN = "AW2";
"GPP_H7_SRCCLKREQ13_N":   PN = "AV1"  !CDS_PN = "AV1";
"GPP_H8_SRCCLKREQ14_N":   PN = "AR3"  !CDS_PN = "AR3";
"GPP_H9_SRCCLKREQ15_N":   PN = "BE2"  !CDS_PN = "BE2";
"GPP_H10_SML2CLK_IE":   PN = "BA4"  !CDS_PN = "BA4";
"GPP_H11_SML2DATA_IE":   PN = "BD1"  !CDS_PN = "BD1";
"GPP_H12_SML2ALERT_N_IE_N":   PN = "BB1"  !CDS_PN = "BB1";
"GPP_H13_SML3CLK_IE":   PN = "AY1"  !CDS_PN = "AY1";
"GPP_H14_SML3DATA_IE":   PN = "BC2"  !CDS_PN = "BC2";
"GPP_H15_SML3ALERT_N_IE_N":   PN = "BB3"  !CDS_PN = "BB3";
"GPP_H16_SML4CLK_IE":   PN = "BF1"  !CDS_PN = "BF1";
"GPP_H17_SML4DATA_IE":   PN = "BE4"  !CDS_PN = "BE4";
"GPP_H18_SML4ALERT_N_IE_N":   PN = "BC4"  !CDS_PN = "BC4";
"GPP_H19_SSATAXPCIE1_SSATAGP1":   PN = "BD3"  !CDS_PN = "BD3";
"GPP_H20_SSATAXPCIE2_SSATAGP2":   PN = "BF3"  !CDS_PN = "BF3";
"GPP_H21_SSATAXPCIE3_SSATAGP3":   PN = "BA2"  !CDS_PN = "BA2";
"GPP_H22_SSATAXPCIE4_SSATAGP4":   PN = "BH2"  !CDS_PN = "BH2";
"GPP_H23_SSATAXPCIE5_SSATAGP5":   PN = "BH4"  !CDS_PN = "BH4";
"GPP_I0_LAN_TDO":   PN = "CA20"  !CDS_PN = "CA20";
"GPP_I1_LAN_TCK":   PN = "BV21"  !CDS_PN = "BV21";
"GPP_I2_LAN_TMS":   PN = "CA22"  !CDS_PN = "CA22";
"GPP_I3_LAN_TDI":   PN = "BY23"  !CDS_PN = "BY23";
"GPP_I4_DO_RESET_IN_N":   PN = "BW20"  !CDS_PN = "BW20";
"GPP_I5_DO_RESET_OUT_N":   PN = "BW24"  !CDS_PN = "BW24";
"GPP_I6_RESET_DONE":   PN = "BV23"  !CDS_PN = "BV23";
"GPP_I7_LAN_TRST_N":   PN = "CA24"  !CDS_PN = "CA24";
"GPP_I8_PCI_DIS_N":   PN = "BW22"  !CDS_PN = "BW22";
"GPP_I9_LAN_DIS_N":   PN = "BY21"  !CDS_PN = "BY21";
"GPP_I10":   PN = "BV25"  !CDS_PN = "BV25";
"GPP_J0_LAN_LED_P0_0":   PN = "BL1"  !CDS_PN = "BL1";
"GPP_J1_LAN_LED_P0_1":   PN = "BK4"  !CDS_PN = "BK4";
"GPP_J2_LAN_LED_P1_0":   PN = "BP4"  !CDS_PN = "BP4";
"GPP_J3_LAN_LED_P1_1":   PN = "BK2"  !CDS_PN = "BK2";
"GPP_J4_LAN_LED_P2_0":   PN = "BL3"  !CDS_PN = "BL3";
"GPP_J5_LAN_LED_P2_1":   PN = "BU6"  !CDS_PN = "BU6";
"GPP_J6_LAN_LED_P3_0":   PN = "CA13"  !CDS_PN = "CA13";
"GPP_J7_LAN_LED_P3_1":   PN = "BM2"  !CDS_PN = "BM2";
"GPP_J8_LAN_I2C_SCL_MDC_P0":   PN = "BM4"  !CDS_PN = "BM4";
"GPP_J9_LAN_I2C_SDA_MDIO_P0":   PN = "BN3"  !CDS_PN = "BN3";
"GPP_J10_LAN_I2C_SCL_MDC_P1":   PN = "BW5"  !CDS_PN = "BW5";
"GPP_J11_LAN_I2C_SDA_MDIO_P1":   PN = "BV8"  !CDS_PN = "BV8";
"GPP_J12_LAN_I2C_SCL_MDC_P2":   PN = "BT5"  !CDS_PN = "BT5";
"GPP_J13_LAN_I2C_SDA_MDIO_P2":   PN = "BW11"  !CDS_PN = "BW11";
"GPP_J14_LAN_I2C_SCL_MDC_P3":   PN = "BW6"  !CDS_PN = "BW6";
"GPP_J15_LAN_I2C_SDA_MDIO_P3":   PN = "BW9"  !CDS_PN = "BW9";
"GPP_J16_LAN_SDP_P0_0":   PN = "BV10"  !CDS_PN = "BV10";
"GPP_J17_LAN_SDP_P0_1":   PN = "CA11"  !CDS_PN = "CA11";
"GPP_J18_LAN_SDP_P1_0":   PN = "BY10"  !CDS_PN = "BY10";
"GPP_J19_LAN_SDP_P1_1":   PN = "BY14"  !CDS_PN = "BY14";
"GPP_J20_LAN_SDP_P2_0":   PN = "BW13"  !CDS_PN = "BW13";
"GPP_J21_LAN_SDP_P2_1":   PN = "BV12"  !CDS_PN = "BV12";
"GPP_J22_LAN_SDP_P3_0":   PN = "BY12"  !CDS_PN = "BY12";
"GPP_J23_LAN_SDP_P3_1":   PN = "BV14"  !CDS_PN = "BV14";
BODY = "RES","I148": #LOCATION = "R8C21" !CDS_LOCATION = "R8C21" #SEC = "1" !CDS_SEC = "1";
"A":   PN = "1"  !CDS_PN = "1";
"B":   PN = "2"  !CDS_PN = "2";
BODY = "RES","I218": #LOCATION = "R2M1" !CDS_LOCATION = "R2M1" #SEC = "1" !CDS_SEC = "1";
"A":   PN = "1"  !CDS_PN = "1";
"B":   PN = "2"  !CDS_PN = "2";
BODY = "RES","I219": #LOCATION = "R2N26" !CDS_LOCATION = "R2N26" #SEC = "1" !CDS_SEC = "1";
"A":   PN = "1"  !CDS_PN = "1";
"B":   PN = "2"  !CDS_PN = "2";
DRAWING = "@baseboard_fab2_lib.baseboard_fab2(sch_1):page121";
BODY = "RES","I31": #LOCATION = "R7C15" !CDS_LOCATION = "R7C15" &SEC = "1" #&CDS_SEC = "1";
"A":   PN = "1"  !CDS_PN = "1";
"B":   PN = "2"  !CDS_PN = "2";
BODY = "RES","I33": #LOCATION = "R7C16" !CDS_LOCATION = "R7C16" &SEC = "1" #&CDS_SEC = "1";
"A":   PN = "1"  !CDS_PN = "1";
"B":   PN = "2"  !CDS_PN = "2";
BODY = "LBG_CORE_QAT_EXT_D","I34": #LOCATION = "U7C1" !CDS_LOCATION = "U7C1" #SEC = "8" !CDS_SEC = "8";
"CGC_DUT_DETECT_N":   PN = "C70"  !CDS_PN = "C70";
"GPIO_RCOMP_1P8_3P3":   PN = "AM4"  !CDS_PN = "AM4";
"GPP_K0_LAN_NCSI_CLK_IN":   PN = "AJ1"  !CDS_PN = "AJ1";
"GPP_K1_LAN_NCSI_TXD0":   PN = "AM2"  !CDS_PN = "AM2";
"GPP_K2_LAN_NCSI_TXD1":   PN = "AK2"  !CDS_PN = "AK2";
"GPP_K3_LAN_NCSI_TX_EN":   PN = "AL3"  !CDS_PN = "AL3";
"GPP_K4_LAN_NCSI_CRS_DV":   PN = "AN3"  !CDS_PN = "AN3";
"GPP_K5_LAN_NCSI_RXD0":   PN = "AL1"  !CDS_PN = "AL1";
"GPP_K6_LAN_NCSI_RXD1":   PN = "AN1"  !CDS_PN = "AN1";
"GPP_K7":   PN = "AH2"  !CDS_PN = "AH2";
"GPP_K8_LAN_NCSI_ARB_IN":   PN = "AJ3"  !CDS_PN = "AJ3";
"GPP_K9_LAN_NCSI_ARB_OUT":   PN = "AK4"  !CDS_PN = "AK4";
"GPP_K10_PE_RST_N":   PN = "AH4"  !CDS_PN = "AH4";
"GPP_L2_TESTCH0_D0":   PN = "AE18"  !CDS_PN = "AE18";
"GPP_L3_TESTCH0_D1":   PN = "AE15"  !CDS_PN = "AE15";
"GPP_L4_TESTCH0_D2":   PN = "AE11"  !CDS_PN = "AE11";
"GPP_L5_TESTCH0_D3":   PN = "Y18"  !CDS_PN = "Y18";
"GPP_L6_TESTCH0_D4":   PN = "AA20"  !CDS_PN = "AA20";
"GPP_L7_TESTCH0_D5":   PN = "AA17"  !CDS_PN = "AA17";
"GPP_L8_TESTCH0_D6":   PN = "AD9"  !CDS_PN = "AD9";
"GPP_L9_TESTCH0_D7":   PN = "AD17"  !CDS_PN = "AD17";
"GPP_L10_TESTCH0_CLK":   PN = "AF20"  !CDS_PN = "AF20";
"GPP_L11_TESTCH1_D0":   PN = "AD20"  !CDS_PN = "AD20";
"GPP_L12_TESTCH1_D1":   PN = "Y15"  !CDS_PN = "Y15";
"GPP_L13_TESTCH1_D2":   PN = "AD13"  !CDS_PN = "AD13";
"GPP_L14_TESTCH1_D3":   PN = "AA13"  !CDS_PN = "AA13";
"GPP_L15_TESTCH1_D4":   PN = "Y11"  !CDS_PN = "Y11";
"GPP_L16_TESTCH1_D5":   PN = "Y7"  !CDS_PN = "Y7";
"GPP_L17_TESTCH1_D6":   PN = "AA9"  !CDS_PN = "AA9";
"GPP_L18_TESTCH1_D7":   PN = "AE7"  !CDS_PN = "AE7";
"GPP_L19_TESTCH1_CLK":   PN = "AG11"  !CDS_PN = "AG11";
"HDA_BCLK":   PN = "P18"  !CDS_PN = "P18";
"HDA_RST_N":   PN = "M18"  !CDS_PN = "M18";
"HDA_SDI_0":   PN = "K20"  !CDS_PN = "K20";
"HDA_SDI_1":   PN = "V18"  !CDS_PN = "V18";
"HDA_SDO":   PN = "U24"  !CDS_PN = "U24";
"HDA_SYNC":   PN = "H20"  !CDS_PN = "H20";
"INTRUDER_N":   PN = "AG18"  !CDS_PN = "AG18";
"RSVD<0>":   PN = "AF61"  !CDS_PN = "AF61";
"RSVD<1>":   PN = "AC56"  !CDS_PN = "AC56";
"RSVD<2>":   PN = "AA58"  !CDS_PN = "AA58";
"RSVD<3>":   PN = "V11"  !CDS_PN = "V11";
"RSVD<4>":   PN = "P37"  !CDS_PN = "P37";
"RSVD<5>":   PN = "AG15"  !CDS_PN = "AG15";
"RSVD<6>":   PN = "AT69"  !CDS_PN = "AT69";
"RSVD<7>":   PN = "F8"  !CDS_PN = "F8";
"RSVD<8>":   PN = "F69"  !CDS_PN = "F69";
"RSVD<9>":   PN = "F66"  !CDS_PN = "F66";
"RSVD<10>":   PN = "D8"  !CDS_PN = "D8";
"RSVD<11>":   PN = "C18"  !CDS_PN = "C18";
"RSVD<12>":   PN = "C68"  !CDS_PN = "C68";
"RSVD<13>":   PN = "C67"  !CDS_PN = "C67";
"RSVD<14>":   PN = "E18"  !CDS_PN = "E18";
"RSVD<15>":   PN = "C6"  !CDS_PN = "C6";
"RSVD<16>":   PN = "C5"  !CDS_PN = "C5";
"RSVD<17>":   PN = "B10"  !CDS_PN = "B10";
"RSVD<18>":   PN = "C11"  !CDS_PN = "C11";
"RSVD<19>":   PN = "C9"  !CDS_PN = "C9";
"RSVD<20>":   PN = "D10"  !CDS_PN = "D10";
"RSVD<21>":   PN = "A11"  !CDS_PN = "A11";
"RSVD<22>":   PN = "AT71"  !CDS_PN = "AT71";
"RSVD<23>":   PN = "P40"  !CDS_PN = "P40";
"RSVD<24>":   PN = "P44"  !CDS_PN = "P44";
"RSVD<25>":   PN = "P48"  !CDS_PN = "P48";
"RSVD<26>":   PN = "BH24"  !CDS_PN = "BH24";
"RSVD<27>":   PN = "BG26"  !CDS_PN = "BG26";
"RSVD<46>":   PN = "BW3"  !CDS_PN = "BW3";
"RSVD<66>":   PN = "U20"  !CDS_PN = "U20";
"RSVD<67>":   PN = "R20"  !CDS_PN = "R20";
"RSVD<68>":   PN = "V22"  !CDS_PN = "V22";
"RTCRST_N":   PN = "P11"  !CDS_PN = "P11";
"SPI0_CLK":   PN = "K2"  !CDS_PN = "K2";
"SPI0_FLASH_CS0_N":   PN = "J3"  !CDS_PN = "J3";
"SPI0_FLASH_CS1_N":   PN = "G7"  !CDS_PN = "G7";
"SPI0_IO2":   PN = "F5"  !CDS_PN = "F5";
"SPI0_IO3":   PN = "L1"  !CDS_PN = "L1";
"SPI0_MISO_IO1":   PN = "L3"  !CDS_PN = "L3";
"SPI0_MOSI_IO0":   PN = "H4"  !CDS_PN = "H4";
"SPI0_TPM_CS_N":   PN = "K4"  !CDS_PN = "K4";
"SRTCRST_N":   PN = "G18"  !CDS_PN = "G18";
BODY = "RES","I35": #LOCATION = "R8C26" !CDS_LOCATION = "R8C26" #SEC = "1" !CDS_SEC = "1";
"A":   PN = "1"  !CDS_PN = "1";
"B":   PN = "2"  !CDS_PN = "2";
BODY = "RES","I37": #LOCATION = "R3N10" !CDS_LOCATION = "R3N10" #SEC = "1" !CDS_SEC = "1";
"A":   PN = "1"  !CDS_PN = "1";
"B":   PN = "2"  !CDS_PN = "2";
BODY = "RES","I73": #LOCATION = "R7C20" !CDS_LOCATION = "R7C20" #SEC = "1" !CDS_SEC = "1";
"A":   PN = "1"  !CDS_PN = "1";
"B":   PN = "2"  !CDS_PN = "2";
BODY = "RES","I89": #LOCATION = "R3P3" !CDS_LOCATION = "R3P3" #SEC = "1" !CDS_SEC = "1";
"A":   PN = "1"  !CDS_PN = "1";
"B":   PN = "2"  !CDS_PN = "2";
BODY = "RES","I90": #LOCATION = "R3P2" !CDS_LOCATION = "R3P2" #SEC = "1" !CDS_SEC = "1";
"A":   PN = "1"  !CDS_PN = "1";
"B":   PN = "2"  !CDS_PN = "2";
BODY = "RES","I91": #LOCATION = "R2P1" !CDS_LOCATION = "R2P1" #SEC = "1" !CDS_SEC = "1";
"A":   PN = "1"  !CDS_PN = "1";
"B":   PN = "2"  !CDS_PN = "2";
BODY = "RES","I98": #LOCATION = "R7C14" !CDS_LOCATION = "R7C14" #SEC = "1" !CDS_SEC = "1";
"A":   PN = "1"  !CDS_PN = "1";
"B":   PN = "2"  !CDS_PN = "2";
BODY = "RES","I101": #LOCATION = "R8D11" !CDS_LOCATION = "R8D11" #SEC = "1" !CDS_SEC = "1";
"A":   PN = "1"  !CDS_PN = "1";
"B":   PN = "2"  !CDS_PN = "2";
DRAWING = "@baseboard_fab2_lib.baseboard_fab2(sch_1):page122";
BODY = "LBG_CORE_QAT_EXT_D","I63": #LOCATION = "U7C1" !CDS_LOCATION = "U7C1" #SEC = "9" !CDS_SEC = "9";
"RSVD<28>":   PN = "R35"  !CDS_PN = "R35";
"RSVD<29>":   PN = "P33"  !CDS_PN = "P33";
"RSVD<30>":   PN = "R31"  !CDS_PN = "R31";
"RSVD<31>":   PN = "P29"  !CDS_PN = "P29";
"RSVD<58>":   PN = "AP27"  !CDS_PN = "AP27";
"RSVD<59>":   PN = "AT27"  !CDS_PN = "AT27";
"VCCA_CLKFILT_1P05<0>":   PN = "W50"  !CDS_PN = "W50";
"VCCA_CLKFILT_1P05<1>":   PN = "AG45"  !CDS_PN = "AG45";
"VCCA_CLKFILT_1P05<2>":   PN = "AJ46"  !CDS_PN = "AJ46";
"VCCA_CLKFILT_1P05<3>":   PN = "AJ48"  !CDS_PN = "AJ48";
"VCCA_CLKFILT_1P05<4>":   PN = "AE46"  !CDS_PN = "AE46";
"VCCA_CLKUNF_1P05<0>":   PN = "AH50"  !CDS_PN = "AH50";
"VCCA_CLKUNF_1P05<1>":   PN = "U50"  !CDS_PN = "U50";
"VCCA_CLKXTAL_1P05":   PN = "AD50"  !CDS_PN = "AD50";
"VCCA_PLL0_1P05":   PN = "AG48"  !CDS_PN = "AG48";
"VCCA_PLL1_1P05":   PN = "AE45"  !CDS_PN = "AE45";
"VCCMPHY_1P05<0>":   PN = "AW45"  !CDS_PN = "AW45";
"VCCMPHY_1P05<1>":   PN = "AW43"  !CDS_PN = "AW43";
"VCCMPHY_1P05<2>":   PN = "AJ43"  !CDS_PN = "AJ43";
"VCCMPHY_1P05<3>":   PN = "AU45"  !CDS_PN = "AU45";
"VCCMPHY_1P05<4>":   PN = "AU43"  !CDS_PN = "AU43";
"VCCMPHY_1P05<5>":   PN = "AT45"  !CDS_PN = "AT45";
"VCCMPHY_1P05<6>":   PN = "AT43"  !CDS_PN = "AT43";
"VCCMPHY_1P05<7>":   PN = "AP45"  !CDS_PN = "AP45";
"VCCMPHY_1P05<8>":   PN = "AP43"  !CDS_PN = "AP43";
"VCCMPHY_1P05<9>":   PN = "AM45"  !CDS_PN = "AM45";
"VCCMPHY_1P05<10>":   PN = "AM43"  !CDS_PN = "AM43";
"VCCMPHY_1P05<11>":   PN = "AK45"  !CDS_PN = "AK45";
"VCCMPHY_1P05<12>":   PN = "AK43"  !CDS_PN = "AK43";
"VCCP10GBE_HV_1P8<0>":   PN = "BA29"  !CDS_PN = "BA29";
"VCCP10GBE_HV_1P8<1>":   PN = "BA27"  !CDS_PN = "BA27";
"VCCP10GBE_LV_1P05<0>":   PN = "BB37"  !CDS_PN = "BB37";
"VCCP10GBE_LV_1P05<1>":   PN = "BB33"  !CDS_PN = "BB33";
"VCCP10GBE_LV_1P05<2>":   PN = "BA37"  !CDS_PN = "BA37";
"VCCP10GBE_LV_1P05<3>":   PN = "BA36"  !CDS_PN = "BA36";
"VCCP10GBE_LV_1P05<4>":   PN = "BA34"  !CDS_PN = "BA34";
"VCCP10GBE_LV_1P05<5>":   PN = "BA32"  !CDS_PN = "BA32";
"VCCP10GBE_LV_1P05<6>":   PN = "BA30"  !CDS_PN = "BA30";
"VCCP10GBEPLL_1P05<0>":   PN = "BD38"  !CDS_PN = "BD38";
"VCCP10GBEPLL_1P05<1>":   PN = "BB40"  !CDS_PN = "BB40";
"VCCP10GBEPLL_1P05<2>":   PN = "BA41"  !CDS_PN = "BA41";
"VCCP10GBEPLL_1P05<3>":   PN = "BA39"  !CDS_PN = "BA39";
"VCCP_1P8<0>":   PN = "BD46"  !CDS_PN = "BD46";
"VCCP_1P8<1>":   PN = "AE26"  !CDS_PN = "AE26";
"VCCP_3P3<0>":   PN = "BA46"  !CDS_PN = "BA46";
"VCCP_3P3<1>":   PN = "BA45"  !CDS_PN = "BA45";
"VCCP_3P3<2>":   PN = "AD24"  !CDS_PN = "AD24";
"VCCP_3P3<5>":   PN = "AN24"  !CDS_PN = "AN24";
"VCCP_HSIOPLL_1P05<0>":   PN = "AW48"  !CDS_PN = "AW48";
"VCCP_HSIOPLL_1P05<2>":   PN = "AU48"  !CDS_PN = "AU48";
"VCCP_HSIOPLL_1P05<3>":   PN = "AP48"  !CDS_PN = "AP48";
"VCCP_HSIOPLLUNF_1P05":   PN = "AT48"  !CDS_PN = "AT48";
"VCCP_UPPLL_1P05<0>":   PN = "AN50"  !CDS_PN = "AN50";
"VCCP_UPPLL_1P05<2>":   PN = "AK50"  !CDS_PN = "AK50";
"VCCP_UPPLLUNF_1P05":   PN = "AM48"  !CDS_PN = "AM48";
"VCCPDSW_3P3":   PN = "AH24"  !CDS_PN = "AH24";
"VCCPGPP_1P8<0>":   PN = "AU29"  !CDS_PN = "AU29";
"VCCPGPP_1P8<1>":   PN = "AW29"  !CDS_PN = "AW29";
"VCCPGPP_1P8<2>":   PN = "AT29"  !CDS_PN = "AT29";
"VCCPGPP_1P8<3>":   PN = "AM29"  !CDS_PN = "AM29";
"VCCPGPP_1P8<4>":   PN = "AP29"  !CDS_PN = "AP29";
"VCCPGPP_1P8<5>":   PN = "AW27"  !CDS_PN = "AW27";
"VCCPGPP_1P8<6>":   PN = "AK24"  !CDS_PN = "AK24";
"VCCPGPPA":   PN = "AW24"  !CDS_PN = "AW24";
"VCCPGPPB":   PN = "BE26"  !CDS_PN = "BE26";
"VCCPGPPC":   PN = "BE40"  !CDS_PN = "BE40";
"VCCPGPPD":   PN = "BA43"  !CDS_PN = "BA43";
"VCCPGPPE":   PN = "BE44"  !CDS_PN = "BE44";
"VCCPGPPF":   PN = "AU27"  !CDS_PN = "AU27";
"VCCPGPPG":   PN = "BA26"  !CDS_PN = "BA26";
"VCCPGPPH":   PN = "BA24"  !CDS_PN = "BA24";
"VCCPGPPJ":   PN = "BB26"  !CDS_PN = "BB26";
"VCCPGPPK":   PN = "AU24"  !CDS_PN = "AU24";
"VCCPHDA_1P8":   PN = "AG27"  !CDS_PN = "AG27";
"VCCPRIM_1P05<0>":   PN = "BF46"  !CDS_PN = "BF46";
"VCCPRIM_1P05<1>":   PN = "BE48"  !CDS_PN = "BE48";
"VCCPRIM_1P05<2>":   PN = "AU39"  !CDS_PN = "AU39";
"VCCPRIM_1P05<3>":   PN = "AU37"  !CDS_PN = "AU37";
"VCCPRIM_1P05<4>":   PN = "AT39"  !CDS_PN = "AT39";
"VCCPRIM_1P05<5>":   PN = "AM27"  !CDS_PN = "AM27";
"VCCPRIM_1P05<6>":   PN = "AJ29"  !CDS_PN = "AJ29";
"VCCPRIM_1P05<7>":   PN = "AC26"  !CDS_PN = "AC26";
"VCCPRIM_1P05<8>":   PN = "AA46"  !CDS_PN = "AA46";
"VCCPRIM_1P05<9>":   PN = "AA45"  !CDS_PN = "AA45";
"VCCPRIM_1P05<10>":   PN = "Y46"  !CDS_PN = "Y46";
"VCCPRIM_1P05<11>":   PN = "Y45"  !CDS_PN = "Y45";
"VCCPRIM_1P05<12>":   PN = "V44"  !CDS_PN = "V44";
"VCCPRIM_1P05<13>":   PN = "U46"  !CDS_PN = "U46";
"VCCPRIM_1P05<14>":   PN = "T44"  !CDS_PN = "T44";
"VCCPRIM_1P05<15>":   PN = "R46"  !CDS_PN = "R46";
"VCCPRIM_1P05<16>":   PN = "R42"  !CDS_PN = "R42";
"VCCPRIM_1P05<17>":   PN = "AK27"  !CDS_PN = "AK27";
"VCCPRIM_1P05<18>":   PN = "AA24"  !CDS_PN = "AA24";
"VCCPRIM_1P05<19>":   PN = "Y26"  !CDS_PN = "Y26";
"VCCPRTC":   PN = "AJ27"  !CDS_PN = "AJ27";
"VCCPRTCPRIM_3P3":   PN = "AG29"  !CDS_PN = "AG29";
"VCCPSPI":   PN = "AR24"  !CDS_PN = "AR24";
"VCCPSPI_1P8":   PN = "AK29"  !CDS_PN = "AK29";
"VCCPUSBDSW_3P3":   PN = "BA48"  !CDS_PN = "BA48";
"VCCRTCEXT":   PN = "AG22"  !CDS_PN = "AG22";
DRAWING = "@baseboard_fab2_lib.baseboard_fab2(sch_1):page123";
BODY = "LBG_CORE_QAT_EXT_D","I13": #LOCATION = "U7C1" !CDS_LOCATION = "U7C1" #SEC = "11" !CDS_SEC = "11";
"VSS<355>":   PN = "N31"  !CDS_PN = "N31";
"VSS<356>":   PN = "N27"  !CDS_PN = "N27";
"VSS<357>":   PN = "N24"  !CDS_PN = "N24";
"VSS<358>":   PN = "N20"  !CDS_PN = "N20";
"VSS<359>":   PN = "N17"  !CDS_PN = "N17";
"VSS<360>":   PN = "N13"  !CDS_PN = "N13";
"VSS<361>":   PN = "M48"  !CDS_PN = "M48";
"VSS<362>":   PN = "M44"  !CDS_PN = "M44";
"VSS<363>":   PN = "N50"  !CDS_PN = "N50";
"VSS<364>":   PN = "N42"  !CDS_PN = "N42";
"VSS<365>":   PN = "M40"  !CDS_PN = "M40";
"VSS<366>":   PN = "M4"  !CDS_PN = "M4";
"VSS<367>":   PN = "M37"  !CDS_PN = "M37";
"VSS<368>":   PN = "M33"  !CDS_PN = "M33";
"VSS<369>":   PN = "M29"  !CDS_PN = "M29";
"VSS<370>":   PN = "M26"  !CDS_PN = "M26";
"VSS<371>":   PN = "M22"  !CDS_PN = "M22";
"VSS<372>":   PN = "M2"  !CDS_PN = "M2";
"VSS<373>":   PN = "L68"  !CDS_PN = "L68";
"VSS<374>":   PN = "L5"  !CDS_PN = "L5";
"VSS<375>":   PN = "K71"  !CDS_PN = "K71";
"VSS<376>":   PN = "K69"  !CDS_PN = "K69";
"VSS<377>":   PN = "K54"  !CDS_PN = "K54";
"VSS<378>":   PN = "J70"  !CDS_PN = "J70";
"VSS<379>":   PN = "J68"  !CDS_PN = "J68";
"VSS<380>":   PN = "J59"  !CDS_PN = "J59";
"VSS<381>":   PN = "J44"  !CDS_PN = "J44";
"VSS<382>":   PN = "J37"  !CDS_PN = "J37";
"VSS<383>":   PN = "J22"  !CDS_PN = "J22";
"VSS<384>":   PN = "J15"  !CDS_PN = "J15";
"VSS<385>":   PN = "J11"  !CDS_PN = "J11";
"VSS<386>":   PN = "H65"  !CDS_PN = "H65";
"VSS<387>":   PN = "J7"  !CDS_PN = "J7";
"VSS<388>":   PN = "J5"  !CDS_PN = "J5";
"VSS<389>":   PN = "J29"  !CDS_PN = "J29";
"VSS<390>":   PN = "H58"  !CDS_PN = "H58";
"VSS<391>":   PN = "G66"  !CDS_PN = "G66";
"VSS<392>":   PN = "G63"  !CDS_PN = "G63";
"VSS<393>":   PN = "G6"  !CDS_PN = "G6";
"VSS<394>":   PN = "G48"  !CDS_PN = "G48";
"VSS<395>":   PN = "G37"  !CDS_PN = "G37";
"VSS<396>":   PN = "G29"  !CDS_PN = "G29";
"VSS<397>":   PN = "G22"  !CDS_PN = "G22";
"VSS<398>":   PN = "E9"  !CDS_PN = "E9";
"VSS<399>":   PN = "G59"  !CDS_PN = "G59";
"VSS<400>":   PN = "E63"  !CDS_PN = "E63";
"VSS<401>":   PN = "E61"  !CDS_PN = "E61";
"VSS<402>":   PN = "E6"  !CDS_PN = "E6";
"VSS<403>":   PN = "E57"  !CDS_PN = "E57";
"VSS<404>":   PN = "E54"  !CDS_PN = "E54";
"VSS<405>":   PN = "E52"  !CDS_PN = "E52";
"VSS<406>":   PN = "E50"  !CDS_PN = "E50";
"VSS<407>":   PN = "E48"  !CDS_PN = "E48";
"VSS<408>":   PN = "E45"  !CDS_PN = "E45";
"VSS<409>":   PN = "E43"  !CDS_PN = "E43";
"VSS<410>":   PN = "E41"  !CDS_PN = "E41";
"VSS<411>":   PN = "E39"  !CDS_PN = "E39";
"VSS<412>":   PN = "E37"  !CDS_PN = "E37";
"VSS<413>":   PN = "E34"  !CDS_PN = "E34";
"VSS<414>":   PN = "E32"  !CDS_PN = "E32";
"VSS<415>":   PN = "E30"  !CDS_PN = "E30";
"VSS<416>":   PN = "E28"  !CDS_PN = "E28";
"VSS<417>":   PN = "E26"  !CDS_PN = "E26";
"VSS<418>":   PN = "E24"  !CDS_PN = "E24";
"VSS<419>":   PN = "E22"  !CDS_PN = "E22";
"VSS<420>":   PN = "E20"  !CDS_PN = "E20";
"VSS<421>":   PN = "E15"  !CDS_PN = "E15";
"VSS<422>":   PN = "E13"  !CDS_PN = "E13";
"VSS<423>":   PN = "E11"  !CDS_PN = "E11";
"VSS<424>":   PN = "D47"  !CDS_PN = "D47";
"VSS<425>":   PN = "E65"  !CDS_PN = "E65";
"VSS<426>":   PN = "E59"  !CDS_PN = "E59";
"VSS<427>":   PN = "D27"  !CDS_PN = "D27";
"VSS<428>":   PN = "D25"  !CDS_PN = "D25";
"VSS<429>":   PN = "D19"  !CDS_PN = "D19";
"VSS<430>":   PN = "D16"  !CDS_PN = "D16";
"VSS<431>":   PN = "D12"  !CDS_PN = "D12";
"VSS<432>":   PN = "C65"  !CDS_PN = "C65";
"VSS<433>":   PN = "C41"  !CDS_PN = "C41";
"VSS<434>":   PN = "C37"  !CDS_PN = "C37";
"VSS<435>":   PN = "C34"  !CDS_PN = "C34";
"VSS<436>":   PN = "C30"  !CDS_PN = "C30";
"VSS<437>":   PN = "C22"  !CDS_PN = "C22";
"VSS<438>":   PN = "B47"  !CDS_PN = "B47";
"VSS<439>":   PN = "B27"  !CDS_PN = "B27";
"VSS<440>":   PN = "B25"  !CDS_PN = "B25";
"VSS<441>":   PN = "B19"  !CDS_PN = "B19";
"VSS<442>":   PN = "B12"  !CDS_PN = "B12";
"VSS<443>":   PN = "A41"  !CDS_PN = "A41";
"VSS<444>":   PN = "A37"  !CDS_PN = "A37";
"VSS<445>":   PN = "A34"  !CDS_PN = "A34";
"VSS<446>":   PN = "A30"  !CDS_PN = "A30";
"VSS<447>":   PN = "A22"  !CDS_PN = "A22";
"VSS<448>":   PN = "A18"  !CDS_PN = "A18";
"VSS<449>":   PN = "Y70"  !CDS_PN = "Y70";
"VSS<450>":   PN = "Y72"  !CDS_PN = "Y72";
"VSS<451>":   PN = "AT37"  !CDS_PN = "AT37";
"VSS<452>":   PN = "BB48"  !CDS_PN = "BB48";
"VSS<453>":   PN = "CA70"  !CDS_PN = "CA70";
"VSS<454>":   PN = "BW72"  !CDS_PN = "BW72";
"VSS<455>":   PN = "BW70"  !CDS_PN = "BW70";
"VSS<456>":   PN = "BU72"  !CDS_PN = "BU72";
"VSS<457>":   PN = "BR72"  !CDS_PN = "BR72";
"VSS<458>":   PN = "G72"  !CDS_PN = "G72";
"VSS<459>":   PN = "G1"  !CDS_PN = "G1";
"VSS<460>":   PN = "E72"  !CDS_PN = "E72";
"VSS<461>":   PN = "E1"  !CDS_PN = "E1";
"VSS<462>":   PN = "C72"  !CDS_PN = "C72";
"VSS<463>":   PN = "C3"  !CDS_PN = "C3";
"VSS<464>":   PN = "BR1"  !CDS_PN = "BR1";
"VSS<465>":   PN = "BU1"  !CDS_PN = "BU1";
"VSS<466>":   PN = "BW1"  !CDS_PN = "BW1";
"VSS<467>":   PN = "CA3"  !CDS_PN = "CA3";
"VSS<468>":   PN = "A70"  !CDS_PN = "A70";
"VSS<469>":   PN = "CA5"  !CDS_PN = "CA5";
"VSS<470>":   PN = "CA7"  !CDS_PN = "CA7";
"VSS<471>":   PN = "CA9"  !CDS_PN = "CA9";
"VSS<472>":   PN = "CA65"  !CDS_PN = "CA65";
"VSS<473>":   PN = "CA66"  !CDS_PN = "CA66";
"VSS<474>":   PN = "CA68"  !CDS_PN = "CA68";
"VSS<475>":   PN = "BN72"  !CDS_PN = "BN72";
"VSS<476>":   PN = "BN1"  !CDS_PN = "BN1";
"VSS<477>":   PN = "J72"  !CDS_PN = "J72";
"VSS<478>":   PN = "J1"  !CDS_PN = "J1";
"VSS<479>":   PN = "A68"  !CDS_PN = "A68";
"VSS<480>":   PN = "A66"  !CDS_PN = "A66";
"VSS<481>":   PN = "A65"  !CDS_PN = "A65";
"VSS<482>":   PN = "A9"  !CDS_PN = "A9";
"VSS<483>":   PN = "A7"  !CDS_PN = "A7";
"VSS<484>":   PN = "A5"  !CDS_PN = "A5";
"VSS<485>":   PN = "E3"  !CDS_PN = "E3";
"VSS<486>":   PN = "F3"  !CDS_PN = "F3";
"VSS<487>":   PN = "BR3"  !CDS_PN = "BR3";
"VSS<488>":   PN = "BU3"  !CDS_PN = "BU3";
"VSS<489>":   PN = "E70"  !CDS_PN = "E70";
"VSS<490>":   PN = "F70"  !CDS_PN = "F70";
"VSS<491>":   PN = "BR70"  !CDS_PN = "BR70";
"VSS<492>":   PN = "BU70"  !CDS_PN = "BU70";
"VSS<493>":   PN = "BT69"  !CDS_PN = "BT69";
"VSS<494>":   PN = "BP69"  !CDS_PN = "BP69";
BODY = "LBG_CORE_QAT_EXT_D","I21": #LOCATION = "U7C1" !CDS_LOCATION = "U7C1" #SEC = "10" !CDS_SEC = "10";
"VCCMPHY_1P05<13>":   PN = "AE27"  !CDS_PN = "AE27";
"VCCPRIM_AVID<0>":   PN = "AU36"  !CDS_PN = "AU36";
"VCCPRIM_AVID<1>":   PN = "AU34"  !CDS_PN = "AU34";
"VCCPRIM_AVID<2>":   PN = "AU32"  !CDS_PN = "AU32";
"VCCPRIM_AVID<3>":   PN = "AT36"  !CDS_PN = "AT36";
"VCCPRIM_AVID<4>":   PN = "AT34"  !CDS_PN = "AT34";
"VCCPRIM_AVID<5>":   PN = "AT32"  !CDS_PN = "AT32";
"VCCPRIM_AVID<6>":   PN = "AP39"  !CDS_PN = "AP39";
"VCCPRIM_AVID<7>":   PN = "AP37"  !CDS_PN = "AP37";
"VCCPRIM_AVID<8>":   PN = "AP36"  !CDS_PN = "AP36";
"VCCPRIM_AVID<9>":   PN = "AP34"  !CDS_PN = "AP34";
"VCCPRIM_AVID<10>":   PN = "AP32"  !CDS_PN = "AP32";
"VCCPRIM_AVID<11>":   PN = "AM39"  !CDS_PN = "AM39";
"VCCPRIM_AVID<12>":   PN = "AM37"  !CDS_PN = "AM37";
"VCCPRIM_AVID<13>":   PN = "AM36"  !CDS_PN = "AM36";
"VCCPRIM_AVID<14>":   PN = "AM34"  !CDS_PN = "AM34";
"VCCPRIM_AVID<15>":   PN = "AM32"  !CDS_PN = "AM32";
"VCCPRIM_AVID<16>":   PN = "AK39"  !CDS_PN = "AK39";
"VCCPRIM_AVID<17>":   PN = "AK37"  !CDS_PN = "AK37";
"VCCPRIM_AVID<18>":   PN = "AK34"  !CDS_PN = "AK34";
"VCCPRIM_AVID<19>":   PN = "AG39"  !CDS_PN = "AG39";
"VCCPRIM_AVID<20>":   PN = "AG37"  !CDS_PN = "AG37";
"VCCPRIM_AVID<21>":   PN = "AG36"  !CDS_PN = "AG36";
"VCCPRIM_AVID<22>":   PN = "AG34"  !CDS_PN = "AG34";
"VCCPRIM_AVID<23>":   PN = "AG32"  !CDS_PN = "AG32";
"VCCPRIM_AVID<24>":   PN = "AE41"  !CDS_PN = "AE41";
"VCCPRIM_AVID<25>":   PN = "AE39"  !CDS_PN = "AE39";
"VCCPRIM_AVID<26>":   PN = "AE37"  !CDS_PN = "AE37";
"VCCPRIM_AVID<27>":   PN = "AE36"  !CDS_PN = "AE36";
"VCCPRIM_AVID<28>":   PN = "AE34"  !CDS_PN = "AE34";
"VCCPRIM_AVID<29>":   PN = "AE32"  !CDS_PN = "AE32";
"VCCPRIM_AVID<30>":   PN = "AE30"  !CDS_PN = "AE30";
"VCCPRIM_AVID<31>":   PN = "U27"  !CDS_PN = "U27";
"VCCPRIM_AVID<32>":   PN = "AC41"  !CDS_PN = "AC41";
"VCCPRIM_AVID<33>":   PN = "AC39"  !CDS_PN = "AC39";
"VCCPRIM_AVID<34>":   PN = "AC37"  !CDS_PN = "AC37";
"VCCPRIM_AVID<35>":   PN = "AC36"  !CDS_PN = "AC36";
"VCCPRIM_AVID<36>":   PN = "AC34"  !CDS_PN = "AC34";
"VCCPRIM_AVID<37>":   PN = "AC32"  !CDS_PN = "AC32";
"VCCPRIM_AVID<38>":   PN = "AC30"  !CDS_PN = "AC30";
"VCCPRIM_AVID<39>":   PN = "AC29"  !CDS_PN = "AC29";
"VCCPRIM_AVID<40>":   PN = "AA41"  !CDS_PN = "AA41";
"VCCPRIM_AVID<41>":   PN = "AA39"  !CDS_PN = "AA39";
"VCCPRIM_AVID<42>":   PN = "AA37"  !CDS_PN = "AA37";
"VCCPRIM_AVID<43>":   PN = "AA36"  !CDS_PN = "AA36";
"VCCPRIM_AVID<44>":   PN = "AA34"  !CDS_PN = "AA34";
"VCCPRIM_AVID<45>":   PN = "AA32"  !CDS_PN = "AA32";
"VCCPRIM_AVID<46>":   PN = "AA30"  !CDS_PN = "AA30";
"VCCPRIM_AVID<47>":   PN = "AA29"  !CDS_PN = "AA29";
"VCCPRIM_AVID<48>":   PN = "Y41"  !CDS_PN = "Y41";
"VCCPRIM_AVID<49>":   PN = "Y39"  !CDS_PN = "Y39";
"VCCPRIM_AVID<50>":   PN = "Y37"  !CDS_PN = "Y37";
"VCCPRIM_AVID<51>":   PN = "Y36"  !CDS_PN = "Y36";
"VCCPRIM_AVID<52>":   PN = "Y34"  !CDS_PN = "Y34";
"VCCPRIM_AVID<53>":   PN = "Y32"  !CDS_PN = "Y32";
"VCCPRIM_AVID<54>":   PN = "Y30"  !CDS_PN = "Y30";
"VCCPRIM_AVID<55>":   PN = "Y29"  !CDS_PN = "Y29";
"VCCPRIM_AVID<56>":   PN = "V40"  !CDS_PN = "V40";
"VCCPRIM_AVID<57>":   PN = "V33"  !CDS_PN = "V33";
"VCCPRIM_AVID<58>":   PN = "V29"  !CDS_PN = "V29";
"VCCPRIM_AVID<59>":   PN = "U38"  !CDS_PN = "U38";
"VCCPRIM_AVID<60>":   PN = "U35"  !CDS_PN = "U35";
"VCCPRIM_AVID<61>":   PN = "U31"  !CDS_PN = "U31";
"VCCPRIM_AVID<62>":   PN = "AK32"  !CDS_PN = "AK32";
"VCCPRIM_AVID_QAT_SENSE":   PN = "V37"  !CDS_PN = "V37";
"VCCPRIM_AVID_SENSE":   PN = "AK36"  !CDS_PN = "AK36";
DRAWING = "@baseboard_fab2_lib.baseboard_fab2(sch_1):page124";
BODY = "LBG_CORE_QAT_EXT_D","I15": #LOCATION = "U7C1" !CDS_LOCATION = "U7C1" #SEC = "14" !CDS_SEC = "14";
"VSS<0>":   PN = "CA52"  !CDS_PN = "CA52";
"VSS<1>":   PN = "CA50"  !CDS_PN = "CA50";
"VSS<2>":   PN = "CA26"  !CDS_PN = "CA26";
"VSS<3>":   PN = "CA18"  !CDS_PN = "CA18";
"VSS<4>":   PN = "CA15"  !CDS_PN = "CA15";
"VSS<5>":   PN = "BY49"  !CDS_PN = "BY49";
"VSS<6>":   PN = "BY40"  !CDS_PN = "BY40";
"VSS<7>":   PN = "BW52"  !CDS_PN = "BW52";
"VSS<8>":   PN = "BW26"  !CDS_PN = "BW26";
"VSS<9>":   PN = "BW18"  !CDS_PN = "BW18";
"VSS<10>":   PN = "BW15"  !CDS_PN = "BW15";
"VSS<11>":   PN = "BV40"  !CDS_PN = "BV40";
"VSS<12>":   PN = "BU9"  !CDS_PN = "BU9";
"VSS<13>":   PN = "BU63"  !CDS_PN = "BU63";
"VSS<14>":   PN = "BU61"  !CDS_PN = "BU61";
"VSS<15>":   PN = "BU59"  !CDS_PN = "BU59";
"VSS<16>":   PN = "BU57"  !CDS_PN = "BU57";
"VSS<17>":   PN = "BU54"  !CDS_PN = "BU54";
"VSS<18>":   PN = "BU52"  !CDS_PN = "BU52";
"VSS<19>":   PN = "BU50"  !CDS_PN = "BU50";
"VSS<20>":   PN = "BU48"  !CDS_PN = "BU48";
"VSS<21>":   PN = "BU45"  !CDS_PN = "BU45";
"VSS<22>":   PN = "BU43"  !CDS_PN = "BU43";
"VSS<23>":   PN = "BU41"  !CDS_PN = "BU41";
"VSS<24>":   PN = "BU39"  !CDS_PN = "BU39";
"VSS<25>":   PN = "BU37"  !CDS_PN = "BU37";
"VSS<26>":   PN = "BU34"  !CDS_PN = "BU34";
"VSS<27>":   PN = "BU32"  !CDS_PN = "BU32";
"VSS<28>":   PN = "BU30"  !CDS_PN = "BU30";
"VSS<29>":   PN = "BU28"  !CDS_PN = "BU28";
"VSS<30>":   PN = "BU26"  !CDS_PN = "BU26";
"VSS<31>":   PN = "BU24"  !CDS_PN = "BU24";
"VSS<32>":   PN = "BU22"  !CDS_PN = "BU22";
"VSS<33>":   PN = "BU20"  !CDS_PN = "BU20";
"VSS<34>":   PN = "BU18"  !CDS_PN = "BU18";
"VSS<35>":   PN = "BU15"  !CDS_PN = "BU15";
"VSS<36>":   PN = "BV49"  !CDS_PN = "BV49";
"VSS<37>":   PN = "BU11"  !CDS_PN = "BU11";
"VSS<38>":   PN = "BU13"  !CDS_PN = "BU13";
"VSS<39>":   PN = "BT66"  !CDS_PN = "BT66";
"VSS<40>":   PN = "BR6"  !CDS_PN = "BR6";
"VSS<41>":   PN = "BR58"  !CDS_PN = "BR58";
"VSS<42>":   PN = "BR54"  !CDS_PN = "BR54";
"VSS<43>":   PN = "BT8"  !CDS_PN = "BT8";
"VSS<44>":   PN = "BR50"  !CDS_PN = "BR50";
"VSS<45>":   PN = "BR20"  !CDS_PN = "BR20";
"VSS<46>":   PN = "BN66"  !CDS_PN = "BN66";
"VSS<47>":   PN = "BN52"  !CDS_PN = "BN52";
"VSS<48>":   PN = "BN5"  !CDS_PN = "BN5";
"VSS<49>":   PN = "BN59"  !CDS_PN = "BN59";
"VSS<50>":   PN = "BN22"  !CDS_PN = "BN22";
"VSS<51>":   PN = "BM9"  !CDS_PN = "BM9";
"VSS<52>":   PN = "BM71"  !CDS_PN = "BM71";
"VSS<53>":   PN = "BM69"  !CDS_PN = "BM69";
"VSS<54>":   PN = "BM58"  !CDS_PN = "BM58";
"VSS<55>":   PN = "BM50"  !CDS_PN = "BM50";
"VSS<56>":   PN = "BM46"  !CDS_PN = "BM46";
"VSS<57>":   PN = "BN37"  !CDS_PN = "BN37";
"VSS<58>":   PN = "BM17"  !CDS_PN = "BM17";
"VSS<59>":   PN = "BM13"  !CDS_PN = "BM13";
"VSS<60>":   PN = "BL72"  !CDS_PN = "BL72";
"VSS<61>":   PN = "BL70"  !CDS_PN = "BL70";
"VSS<62>":   PN = "BL63"  !CDS_PN = "BL63";
"VSS<63>":   PN = "BL5"  !CDS_PN = "BL5";
"VSS<64>":   PN = "BL37"  !CDS_PN = "BL37";
"VSS<65>":   PN = "BL68"  !CDS_PN = "BL68";
"VSS<66>":   PN = "BL40"  !CDS_PN = "BL40";
"VSS<67>":   PN = "BL22"  !CDS_PN = "BL22";
"VSS<68>":   PN = "BK50"  !CDS_PN = "BK50";
"VSS<69>":   PN = "BK42"  !CDS_PN = "BK42";
"VSS<70>":   PN = "BK38"  !CDS_PN = "BK38";
"VSS<71>":   PN = "BK35"  !CDS_PN = "BK35";
"VSS<72>":   PN = "BK31"  !CDS_PN = "BK31";
"VSS<73>":   PN = "BK27"  !CDS_PN = "BK27";
"VSS<74>":   PN = "BK24"  !CDS_PN = "BK24";
BODY = "LBG_CORE_QAT_EXT_D","I16": #LOCATION = "U7C1" !CDS_LOCATION = "U7C1" #SEC = "13" !CDS_SEC = "13";
"VSS<75>":   PN = "BJ68"  !CDS_PN = "BJ68";
"VSS<76>":   PN = "BJ52"  !CDS_PN = "BJ52";
"VSS<77>":   PN = "BJ33"  !CDS_PN = "BJ33";
"VSS<78>":   PN = "BJ3"  !CDS_PN = "BJ3";
"VSS<79>":   PN = "BJ26"  !CDS_PN = "BJ26";
"VSS<80>":   PN = "BJ18"  !CDS_PN = "BJ18";
"VSS<81>":   PN = "BJ15"  !CDS_PN = "BJ15";
"VSS<82>":   PN = "BJ7"  !CDS_PN = "BJ7";
"VSS<83>":   PN = "BJ5"  !CDS_PN = "BJ5";
"VSS<84>":   PN = "BJ11"  !CDS_PN = "BJ11";
"VSS<85>":   PN = "BJ1"  !CDS_PN = "BJ1";
"VSS<86>":   PN = "BH54"  !CDS_PN = "BH54";
"VSS<87>":   PN = "BH46"  !CDS_PN = "BH46";
"VSS<88>":   PN = "BH42"  !CDS_PN = "BH42";
"VSS<89>":   PN = "BH38"  !CDS_PN = "BH38";
"VSS<90>":   PN = "BH27"  !CDS_PN = "BH27";
"VSS<91>":   PN = "BG63"  !CDS_PN = "BG63";
"VSS<92>":   PN = "BG59"  !CDS_PN = "BG59";
"VSS<93>":   PN = "BG48"  !CDS_PN = "BG48";
"VSS<94>":   PN = "BG33"  !CDS_PN = "BG33";
"VSS<95>":   PN = "BF9"  !CDS_PN = "BF9";
"VSS<96>":   PN = "BF68"  !CDS_PN = "BF68";
"VSS<97>":   PN = "BF65"  !CDS_PN = "BF65";
"VSS<98>":   PN = "BF61"  !CDS_PN = "BF61";
"VSS<99>":   PN = "BF58"  !CDS_PN = "BF58";
"VSS<100>":   PN = "BF50"  !CDS_PN = "BF50";
"VSS<101>":   PN = "BF5"  !CDS_PN = "BF5";
"VSS<102>":   PN = "BF42"  !CDS_PN = "BF42";
"VSS<103>":   PN = "BF38"  !CDS_PN = "BF38";
"VSS<104>":   PN = "BF27"  !CDS_PN = "BF27";
"VSS<105>":   PN = "BF24"  !CDS_PN = "BF24";
"VSS<106>":   PN = "BF20"  !CDS_PN = "BF20";
"VSS<107>":   PN = "BG44"  !CDS_PN = "BG44";
"VSS<108>":   PN = "BF54"  !CDS_PN = "BF54";
"VSS<109>":   PN = "BF17"  !CDS_PN = "BF17";
"VSS<110>":   PN = "BF13"  !CDS_PN = "BF13";
"VSS<111>":   PN = "BE66"  !CDS_PN = "BE66";
"VSS<112>":   PN = "BE63"  !CDS_PN = "BE63";
"VSS<113>":   PN = "BE59"  !CDS_PN = "BE59";
"VSS<114>":   PN = "BE56"  !CDS_PN = "BE56";
"VSS<115>":   PN = "BE37"  !CDS_PN = "BE37";
"VSS<116>":   PN = "BE33"  !CDS_PN = "BE33";
"VSS<117>":   PN = "BE29"  !CDS_PN = "BE29";
"VSS<118>":   PN = "BD68"  !CDS_PN = "BD68";
"VSS<119>":   PN = "BD54"  !CDS_PN = "BD54";
"VSS<120>":   PN = "BD50"  !CDS_PN = "BD50";
"VSS<121>":   PN = "BD5"  !CDS_PN = "BD5";
"VSS<122>":   PN = "BD35"  !CDS_PN = "BD35";
"VSS<123>":   PN = "BD31"  !CDS_PN = "BD31";
"VSS<124>":   PN = "BD27"  !CDS_PN = "BD27";
"VSS<125>":   PN = "BD24"  !CDS_PN = "BD24";
"VSS<126>":   PN = "BC71"  !CDS_PN = "BC71";
"VSS<127>":   PN = "BC69"  !CDS_PN = "BC69";
"VSS<128>":   PN = "BB72"  !CDS_PN = "BB72";
"VSS<129>":   PN = "BB70"  !CDS_PN = "BB70";
"VSS<130>":   PN = "BB68"  !CDS_PN = "BB68";
"VSS<131>":   PN = "BB66"  !CDS_PN = "BB66";
"VSS<132>":   PN = "BB59"  !CDS_PN = "BB59";
"VSS<133>":   PN = "BB44"  !CDS_PN = "BB44";
"VSS<134>":   PN = "BB22"  !CDS_PN = "BB22";
"VSS<135>":   PN = "BB18"  !CDS_PN = "BB18";
"VSS<136>":   PN = "BB15"  !CDS_PN = "BB15";
"VSS<137>":   PN = "BB11"  !CDS_PN = "BB11";
"VSS<138>":   PN = "BB7"  !CDS_PN = "BB7";
"VSS<139>":   PN = "BB5"  !CDS_PN = "BB5";
"VSS<140>":   PN = "BA58"  !CDS_PN = "BA58";
"VSS<141>":   PN = "BA54"  !CDS_PN = "BA54";
"VSS<142>":   PN = "BA50"  !CDS_PN = "BA50";
"VSS<143>":   PN = "AY68"  !CDS_PN = "AY68";
"VSS<144>":   PN = "AY63"  !CDS_PN = "AY63";
"VSS<145>":   PN = "AY56"  !CDS_PN = "AY56";
"VSS<146>":   PN = "AY22"  !CDS_PN = "AY22";
"VSS<147>":   PN = "AY5"  !CDS_PN = "AY5";
"VSS<148>":   PN = "AW61"  !CDS_PN = "AW61";
"VSS<149>":   PN = "AW58"  !CDS_PN = "AW58";
"VSS<150>":   PN = "AW50"  !CDS_PN = "AW50";
"VSS<151>":   PN = "AW46"  !CDS_PN = "AW46";
"VSS<152>":   PN = "AW41"  !CDS_PN = "AW41";
"VSS<153>":   PN = "AW39"  !CDS_PN = "AW39";
"VSS<154>":   PN = "AW37"  !CDS_PN = "AW37";
"VSS<155>":   PN = "AW36"  !CDS_PN = "AW36";
"VSS<156>":   PN = "AW34"  !CDS_PN = "AW34";
"VSS<157>":   PN = "AW32"  !CDS_PN = "AW32";
"VSS<158>":   PN = "AW30"  !CDS_PN = "AW30";
"VSS<159>":   PN = "AW26"  !CDS_PN = "AW26";
"VSS<160>":   PN = "AW17"  !CDS_PN = "AW17";
"VSS<161>":   PN = "AW13"  !CDS_PN = "AW13";
"VSS<162>":   PN = "AW9"  !CDS_PN = "AW9";
"VSS<163>":   PN = "AV68"  !CDS_PN = "AV68";
"VSS<164>":   PN = "AV59"  !CDS_PN = "AV59";
"VSS<165>":   PN = "AV22"  !CDS_PN = "AV22";
"VSS<166>":   PN = "AV5"  !CDS_PN = "AV5";
"VSS<167>":   PN = "AU61"  !CDS_PN = "AU61";
"VSS<168>":   PN = "AU54"  !CDS_PN = "AU54";
"VSS<169>":   PN = "AU50"  !CDS_PN = "AU50";
"VSS<170>":   PN = "AU46"  !CDS_PN = "AU46";
"VSS<171>":   PN = "AU41"  !CDS_PN = "AU41";
"VSS<172>":   PN = "AE22"  !CDS_PN = "AE22";
"VSS<173>":   PN = "AU30"  !CDS_PN = "AU30";
"VSS<174>":   PN = "AU26"  !CDS_PN = "AU26";
"VSS<175>":   PN = "AT59"  !CDS_PN = "AT59";
"VSS<176>":   PN = "AT46"  !CDS_PN = "AT46";
"VSS<177>":   PN = "AT41"  !CDS_PN = "AT41";
"VSS<178>":   PN = "AT30"  !CDS_PN = "AT30";
"VSS<179>":   PN = "AT26"  !CDS_PN = "AT26";
"VSS<180>":   PN = "AT22"  !CDS_PN = "AT22";
"VSS<181>":   PN = "AT18"  !CDS_PN = "AT18";
"VSS<182>":   PN = "AT15"  !CDS_PN = "AT15";
"VSS<183>":   PN = "AT11"  !CDS_PN = "AT11";
"VSS<184>":   PN = "AT7"  !CDS_PN = "AT7";
"VSS<185>":   PN = "AR72"  !CDS_PN = "AR72";
"VSS<186>":   PN = "AR70"  !CDS_PN = "AR70";
"VSS<187>":   PN = "AR68"  !CDS_PN = "AR68";
"VSS<188>":   PN = "AR65"  !CDS_PN = "AR65";
"VSS<189>":   PN = "AR58"  !CDS_PN = "AR58";
"VSS<190>":   PN = "AR50"  !CDS_PN = "AR50";
"VSS<191>":   PN = "AR5"  !CDS_PN = "AR5";
"VSS<192>":   PN = "AP66"  !CDS_PN = "AP66";
"VSS<193>":   PN = "AP52"  !CDS_PN = "AP52";
"VSS<194>":   PN = "AP46"  !CDS_PN = "AP46";
"VSS<195>":   PN = "AP41"  !CDS_PN = "AP41";
"VSS<196>":   PN = "AP4"  !CDS_PN = "AP4";
"VSS<197>":   PN = "AP30"  !CDS_PN = "AP30";
"VSS<198>":   PN = "AP26"  !CDS_PN = "AP26";
"VSS<199>":   PN = "AP2"  !CDS_PN = "AP2";
"VSS<200>":   PN = "AN9"  !CDS_PN = "AN9";
"VSS<201>":   PN = "AN58"  !CDS_PN = "AN58";
"VSS<202>":   PN = "AN5"  !CDS_PN = "AN5";
"VSS<203>":   PN = "AN20"  !CDS_PN = "AN20";
"VSS<204>":   PN = "AP22"  !CDS_PN = "AP22";
"VSS<205>":   PN = "AN68"  !CDS_PN = "AN68";
"VSS<206>":   PN = "AN17"  !CDS_PN = "AN17";
"VSS<207>":   PN = "AN13"  !CDS_PN = "AN13";
"VSS<208>":   PN = "AM46"  !CDS_PN = "AM46";
"VSS<209>":   PN = "AM41"  !CDS_PN = "AM41";
"VSS<210>":   PN = "AM30"  !CDS_PN = "AM30";
"VSS<211>":   PN = "AM26"  !CDS_PN = "AM26";
"VSS<212>":   PN = "AL72"  !CDS_PN = "AL72";
"VSS<213>":   PN = "AL70"  !CDS_PN = "AL70";
"VSS<214>":   PN = "AL68"  !CDS_PN = "AL68";
BODY = "LBG_CORE_QAT_EXT_D","I17": #LOCATION = "U7C1" !CDS_LOCATION = "U7C1" #SEC = "12" !CDS_SEC = "12";
"VSS<215>":   PN = "AL59"  !CDS_PN = "AL59";
"VSS<216>":   PN = "AL52"  !CDS_PN = "AL52";
"VSS<217>":   PN = "AL5"  !CDS_PN = "AL5";
"VSS<218>":   PN = "AL22"  !CDS_PN = "AL22";
"VSS<219>":   PN = "AK71"  !CDS_PN = "AK71";
"VSS<220>":   PN = "AK69"  !CDS_PN = "AK69";
"VSS<221>":   PN = "AK61"  !CDS_PN = "AK61";
"VSS<222>":   PN = "AK58"  !CDS_PN = "AK58";
"VSS<223>":   PN = "AK48"  !CDS_PN = "AK48";
"VSS<224>":   PN = "AK46"  !CDS_PN = "AK46";
"VSS<225>":   PN = "AK41"  !CDS_PN = "AK41";
"VSS<226>":   PN = "AK26"  !CDS_PN = "AK26";
"VSS<227>":   PN = "AJ7"  !CDS_PN = "AJ7";
"VSS<228>":   PN = "AJ68"  !CDS_PN = "AJ68";
"VSS<229>":   PN = "AJ66"  !CDS_PN = "AJ66";
"VSS<230>":   PN = "AJ59"  !CDS_PN = "AJ59";
"VSS<231>":   PN = "AJ52"  !CDS_PN = "AJ52";
"VSS<232>":   PN = "AJ5"  !CDS_PN = "AJ5";
"VSS<233>":   PN = "AJ41"  !CDS_PN = "AJ41";
"VSS<234>":   PN = "AJ39"  !CDS_PN = "AJ39";
"VSS<235>":   PN = "AJ37"  !CDS_PN = "AJ37";
"VSS<236>":   PN = "AJ36"  !CDS_PN = "AJ36";
"VSS<237>":   PN = "AJ34"  !CDS_PN = "AJ34";
"VSS<238>":   PN = "AJ30"  !CDS_PN = "AJ30";
"VSS<239>":   PN = "AJ26"  !CDS_PN = "AJ26";
"VSS<240>":   PN = "AJ22"  !CDS_PN = "AJ22";
"VSS<241>":   PN = "AJ18"  !CDS_PN = "AJ18";
"VSS<242>":   PN = "AJ15"  !CDS_PN = "AJ15";
"VSS<243>":   PN = "AK30"  !CDS_PN = "AK30";
"VSS<244>":   PN = "AJ56"  !CDS_PN = "AJ56";
"VSS<245>":   PN = "AJ32"  !CDS_PN = "AJ32";
"VSS<246>":   PN = "AJ11"  !CDS_PN = "AJ11";
"VSS<247>":   PN = "AH20"  !CDS_PN = "AH20";
"VSS<248>":   PN = "AG66"  !CDS_PN = "AG66";
"VSS<249>":   PN = "AG59"  !CDS_PN = "AG59";
"VSS<250>":   PN = "AG56"  !CDS_PN = "AG56";
"VSS<251>":   PN = "AG52"  !CDS_PN = "AG52";
"VSS<252>":   PN = "AG43"  !CDS_PN = "AG43";
"VSS<253>":   PN = "AG41"  !CDS_PN = "AG41";
"VSS<254>":   PN = "AG30"  !CDS_PN = "AG30";
"VSS<255>":   PN = "AG26"  !CDS_PN = "AG26";
"VSS<256>":   PN = "AF68"  !CDS_PN = "AF68";
"VSS<257>":   PN = "AF3"  !CDS_PN = "AF3";
"VSS<258>":   PN = "AF24"  !CDS_PN = "AF24";
"VSS<259>":   PN = "AF17"  !CDS_PN = "AF17";
"VSS<260>":   PN = "AF9"  !CDS_PN = "AF9";
"VSS<261>":   PN = "AF5"  !CDS_PN = "AF5";
"VSS<262>":   PN = "AF13"  !CDS_PN = "AF13";
"VSS<263>":   PN = "AF1"  !CDS_PN = "AF1";
"VSS<264>":   PN = "AE66"  !CDS_PN = "AE66";
"VSS<265>":   PN = "AE63"  !CDS_PN = "AE63";
"VSS<266>":   PN = "AE59"  !CDS_PN = "AE59";
"VSS<267>":   PN = "AE56"  !CDS_PN = "AE56";
"VSS<268>":   PN = "AE52"  !CDS_PN = "AE52";
"VSS<269>":   PN = "AE48"  !CDS_PN = "AE48";
"VSS<270>":   PN = "J18"  !CDS_PN = "J18";
"VSS<271>":   PN = "AE29"  !CDS_PN = "AE29";
"VSS<272>":   PN = "AD68"  !CDS_PN = "AD68";
"VSS<273>":   PN = "AD65"  !CDS_PN = "AD65";
"VSS<274>":   PN = "AD5"  !CDS_PN = "AD5";
"VSS<275>":   PN = "AC7"  !CDS_PN = "AC7";
"VSS<276>":   PN = "AC66"  !CDS_PN = "AC66";
"VSS<277>":   PN = "AC63"  !CDS_PN = "AC63";
"VSS<278>":   PN = "AC59"  !CDS_PN = "AC59";
"VSS<279>":   PN = "AC52"  !CDS_PN = "AC52";
"VSS<280>":   PN = "AC48"  !CDS_PN = "AC48";
"VSS<281>":   PN = "AC46"  !CDS_PN = "AC46";
"VSS<282>":   PN = "AC43"  !CDS_PN = "AC43";
"VSS<283>":   PN = "AC27"  !CDS_PN = "AC27";
"VSS<284>":   PN = "AD58"  !CDS_PN = "AD58";
"VSS<285>":   PN = "AC45"  !CDS_PN = "AC45";
"VSS<286>":   PN = "AC22"  !CDS_PN = "AC22";
"VSS<287>":   PN = "AC18"  !CDS_PN = "AC18";
"VSS<288>":   PN = "AC15"  !CDS_PN = "AC15";
"VSS<289>":   PN = "AC11"  !CDS_PN = "AC11";
"VSS<290>":   PN = "AB72"  !CDS_PN = "AB72";
"VSS<291>":   PN = "AB70"  !CDS_PN = "AB70";
"VSS<292>":   PN = "AB68"  !CDS_PN = "AB68";
"VSS<293>":   PN = "AB5"  !CDS_PN = "AB5";
"VSS<294>":   PN = "AA48"  !CDS_PN = "AA48";
"VSS<295>":   PN = "AA43"  !CDS_PN = "AA43";
"VSS<296>":   PN = "AA27"  !CDS_PN = "AA27";
"VSS<297>":   PN = "AA26"  !CDS_PN = "AA26";
"VSS<298>":   PN = "Y68"  !CDS_PN = "Y68";
"VSS<299>":   PN = "Y63"  !CDS_PN = "Y63";
"VSS<300>":   PN = "Y59"  !CDS_PN = "Y59";
"VSS<301>":   PN = "Y52"  !CDS_PN = "Y52";
"VSS<302>":   PN = "Y5"  !CDS_PN = "Y5";
"VSS<303>":   PN = "Y48"  !CDS_PN = "Y48";
"VSS<304>":   PN = "Y27"  !CDS_PN = "Y27";
"VSS<305>":   PN = "Y22"  !CDS_PN = "Y22";
"VSS<306>":   PN = "W9"  !CDS_PN = "W9";
"VSS<307>":   PN = "W61"  !CDS_PN = "W61";
"VSS<308>":   PN = "Y43"  !CDS_PN = "Y43";
"VSS<309>":   PN = "AA50"  !CDS_PN = "AA50";
"VSS<310>":   PN = "W24"  !CDS_PN = "W24";
"VSS<311>":   PN = "W20"  !CDS_PN = "W20";
"VSS<312>":   PN = "W17"  !CDS_PN = "W17";
"VSS<313>":   PN = "W13"  !CDS_PN = "W13";
"VSS<314>":   PN = "V68"  !CDS_PN = "V68";
"VSS<315>":   PN = "V66"  !CDS_PN = "V66";
"VSS<316>":   PN = "W58"  !CDS_PN = "W58";
"VSS<317>":   PN = "V52"  !CDS_PN = "V52";
"VSS<318>":   PN = "V5"  !CDS_PN = "V5";
"VSS<319>":   PN = "V48"  !CDS_PN = "V48";
"VSS<320>":   PN = "V26"  !CDS_PN = "V26";
"VSS<321>":   PN = "U58"  !CDS_PN = "U58";
"VSS<322>":   PN = "AG46"  !CDS_PN = "AG46";
"VSS<323>":   PN = "AF50"  !CDS_PN = "AF50";
"VSS<324>":   PN = "T7"  !CDS_PN = "T7";
"VSS<325>":   PN = "T66"  !CDS_PN = "T66";
"VSS<326>":   PN = "T52"  !CDS_PN = "T52";
"VSS<327>":   PN = "T48"  !CDS_PN = "T48";
"VSS<328>":   PN = "AJ45"  !CDS_PN = "AJ45";
"VSS<329>":   PN = "T40"  !CDS_PN = "T40";
"VSS<330>":   PN = "T37"  !CDS_PN = "T37";
"VSS<331>":   PN = "T33"  !CDS_PN = "T33";
"VSS<332>":   PN = "T29"  !CDS_PN = "T29";
"VSS<333>":   PN = "T26"  !CDS_PN = "T26";
"VSS<334>":   PN = "T22"  !CDS_PN = "T22";
"VSS<335>":   PN = "T18"  !CDS_PN = "T18";
"VSS<336>":   PN = "T15"  !CDS_PN = "T15";
"VSS<337>":   PN = "T11"  !CDS_PN = "T11";
"VSS<338>":   PN = "R68"  !CDS_PN = "R68";
"VSS<339>":   PN = "R58"  !CDS_PN = "R58";
"VSS<340>":   PN = "T56"  !CDS_PN = "T56";
"VSS<341>":   PN = "R54"  !CDS_PN = "R54";
"VSS<342>":   PN = "R50"  !CDS_PN = "R50";
"VSS<343>":   PN = "R5"  !CDS_PN = "R5";
"VSS<344>":   PN = "U42"  !CDS_PN = "U42";
"VSS<345>":   PN = "R27"  !CDS_PN = "R27";
"VSS<346>":   PN = "P63"  !CDS_PN = "P63";
"VSS<347>":   PN = "AE43"  !CDS_PN = "AE43";
"VSS<348>":   PN = "N9"  !CDS_PN = "N9";
"VSS<349>":   PN = "N68"  !CDS_PN = "N68";
"VSS<350>":   PN = "R38"  !CDS_PN = "R38";
"VSS<351>":   PN = "N5"  !CDS_PN = "N5";
"VSS<352>":   PN = "N46"  !CDS_PN = "N46";
"VSS<353>":   PN = "N38"  !CDS_PN = "N38";
"VSS<354>":   PN = "N35"  !CDS_PN = "N35";
DRAWING = "@baseboard_fab2_lib.baseboard_fab2(sch_1):page125";
BODY = "RES","I11": #LOCATION = "R2R11" !CDS_LOCATION = "R2R11" &SEC = "1" #&CDS_SEC = "1";
"A":   PN = "1"  !CDS_PN = "1";
"B":   PN = "2"  !CDS_PN = "2";
BODY = "RES","I15": #LOCATION = "R2T1" !CDS_LOCATION = "R2T1" &SEC = "1" #&CDS_SEC = "1";
"A":   PN = "1"  !CDS_PN = "1";
"B":   PN = "2"  !CDS_PN = "2";
BODY = "RES","I21": #LOCATION = "R8E6" !CDS_LOCATION = "R8E6" #SEC = "1" !CDS_SEC = "1";
"A":   PN = "1"  !CDS_PN = "1";
"B":   PN = "2"  !CDS_PN = "2";
BODY = "RES","I24": #LOCATION = "R8E4" !CDS_LOCATION = "R8E4" &SEC = "1" #&CDS_SEC = "1";
"A":   PN = "1"  !CDS_PN = "1";
"B":   PN = "2"  !CDS_PN = "2";
BODY = "RES","I40": #LOCATION = "R8C18" !CDS_LOCATION = "R8C18" &SEC = "1" #&CDS_SEC = "1";
"A":   PN = "1"  !CDS_PN = "1";
"B":   PN = "2"  !CDS_PN = "2";
BODY = "RES","I41": #LOCATION = "R8C17" !CDS_LOCATION = "R8C17" #SEC = "1" !CDS_SEC = "1";
"A":   PN = "1"  !CDS_PN = "1";
"B":   PN = "2"  !CDS_PN = "2";
BODY = "RES","I50": #LOCATION = "R8D5" !CDS_LOCATION = "R8D5" &SEC = "1" #&CDS_SEC = "1";
"A":   PN = "1"  !CDS_PN = "1";
"B":   PN = "2"  !CDS_PN = "2";
BODY = "RES","I52": #LOCATION = "R8D13" !CDS_LOCATION = "R8D13" &SEC = "1" #&CDS_SEC = "1";
"A":   PN = "1"  !CDS_PN = "1";
"B":   PN = "2"  !CDS_PN = "2";
BODY = "RES","I60": #LOCATION = "R7D13" !CDS_LOCATION = "R7D13" &SEC = "1" #&CDS_SEC = "1";
"A":   PN = "1"  !CDS_PN = "1";
"B":   PN = "2"  !CDS_PN = "2";
BODY = "RES","I70": #LOCATION = "R7D1" !CDS_LOCATION = "R7D1" #SEC = "1" !CDS_SEC = "1";
"A":   PN = "1"  !CDS_PN = "1";
"B":   PN = "2"  !CDS_PN = "2";
BODY = "RES","I71": #LOCATION = "R8D16" !CDS_LOCATION = "R8D16" #SEC = "1" !CDS_SEC = "1";
"A":   PN = "1"  !CDS_PN = "1";
"B":   PN = "2"  !CDS_PN = "2";
BODY = "RES","I72": #LOCATION = "R3N2" !CDS_LOCATION = "R3N2" #SEC = "1" !CDS_SEC = "1";
"A":   PN = "1"  !CDS_PN = "1";
"B":   PN = "2"  !CDS_PN = "2";
BODY = "RES","I76": #LOCATION = "R2U30" !CDS_LOCATION = "R2U30" &SEC = "1" #&CDS_SEC = "1";
"A":   PN = "1"  !CDS_PN = "1";
"B":   PN = "2"  !CDS_PN = "2";
BODY = "RES","I78": #LOCATION = "R3N17" !CDS_LOCATION = "R3N17" #SEC = "1" !CDS_SEC = "1";
"A":   PN = "1"  !CDS_PN = "1";
"B":   PN = "2"  !CDS_PN = "2";
BODY = "RES","I83": #LOCATION = "R2N14" !CDS_LOCATION = "R2N14" #SEC = "1" !CDS_SEC = "1";
"A":   PN = "1"  !CDS_PN = "1";
"B":   PN = "2"  !CDS_PN = "2";
DRAWING = "@baseboard_fab2_lib.baseboard_fab2(sch_1):page126";
BODY = "RES","I6": #LOCATION = "R7D19" !CDS_LOCATION = "R7D19" #SEC = "1" !CDS_SEC = "1";
"A":   PN = "1"  !CDS_PN = "1";
"B":   PN = "2"  !CDS_PN = "2";
BODY = "RES","I10": #LOCATION = "R2N10" !CDS_LOCATION = "R2N10" #SEC = "1" !CDS_SEC = "1";
"A":   PN = "1"  !CDS_PN = "1";
"B":   PN = "2"  !CDS_PN = "2";
BODY = "RES","I12": #LOCATION = "R1D35" !CDS_LOCATION = "R1D35" #SEC = "1" !CDS_SEC = "1";
"A":   PN = "1"  !CDS_PN = "1";
"B":   PN = "2"  !CDS_PN = "2";
BODY = "FET_N","I13": #LOCATION = "Q8E2" !CDS_LOCATION = "Q8E2" #SEC = "1" !CDS_SEC = "1";
"DRN":   PN = "3"  !CDS_PN = "3";
"GATE":   PN = "1"  !CDS_PN = "1";
"SRC":   PN = "2"  !CDS_PN = "2";
BODY = "RES","I20": #LOCATION = "R8C9" !CDS_LOCATION = "R8C9" #SEC = "1" !CDS_SEC = "1";
"A":   PN = "1"  !CDS_PN = "1";
"B":   PN = "2"  !CDS_PN = "2";
BODY = "RES","I22": #LOCATION = "R3P62" !CDS_LOCATION = "R3P62" #SEC = "1" !CDS_SEC = "1";
"A":   PN = "1"  !CDS_PN = "1";
"B":   PN = "2"  !CDS_PN = "2";
BODY = "RES","I23": #LOCATION = "R3P64" !CDS_LOCATION = "R3P64" #SEC = "1" !CDS_SEC = "1";
"A":   PN = "1"  !CDS_PN = "1";
"B":   PN = "2"  !CDS_PN = "2";
DRAWING = "@baseboard_fab2_lib.baseboard_fab2(sch_1):page127";
BODY = "FERRITE","I8": #LOCATION = "FB3M1" !CDS_LOCATION = "FB3M1" #SEC = "1" !CDS_SEC = "1";
"A":   PN = "1"  !CDS_PN = "1";
"B":   PN = "2"  !CDS_PN = "2";
BODY = "CAP_A","I9": #LOCATION = "C3M21" !CDS_LOCATION = "C3M21" #SEC = "1" !CDS_SEC = "1";
"A":   PN = "1"  !CDS_PN = "1";
"B":   PN = "2"  !CDS_PN = "2";
BODY = "FERRITE","I17": #LOCATION = "FB3M2" !CDS_LOCATION = "FB3M2" #SEC = "1" !CDS_SEC = "1";
"A":   PN = "1"  !CDS_PN = "1";
"B":   PN = "2"  !CDS_PN = "2";
BODY = "CAP_A","I18": #LOCATION = "C3M22" !CDS_LOCATION = "C3M22" #SEC = "1" !CDS_SEC = "1";
"A":   PN = "1"  !CDS_PN = "1";
"B":   PN = "2"  !CDS_PN = "2";
BODY = "FERRITE","I26": #LOCATION = "FB3M3" !CDS_LOCATION = "FB3M3" #SEC = "1" !CDS_SEC = "1";
"A":   PN = "1"  !CDS_PN = "1";
"B":   PN = "2"  !CDS_PN = "2";
BODY = "CAP_A","I27": #LOCATION = "C3M30" !CDS_LOCATION = "C3M30" #SEC = "1" !CDS_SEC = "1";
"A":   PN = "1"  !CDS_PN = "1";
"B":   PN = "2"  !CDS_PN = "2";
BODY = "CAP","I43": #LOCATION = "C2M5" !CDS_LOCATION = "C2M5" #SEC = "1" !CDS_SEC = "1";
"A":   PN = "1"  !CDS_PN = "1";
"B":   PN = "2"  !CDS_PN = "2";
BODY = "CAP_A","I44": #LOCATION = "C2M7" !CDS_LOCATION = "C2M7" #SEC = "1" !CDS_SEC = "1";
"A":   PN = "1"  !CDS_PN = "1";
"B":   PN = "2"  !CDS_PN = "2";
BODY = "FERRITE","I46": #LOCATION = "FB2M1" !CDS_LOCATION = "FB2M1" #SEC = "1" !CDS_SEC = "1";
"A":   PN = "1"  !CDS_PN = "1";
"B":   PN = "2"  !CDS_PN = "2";
BODY = "CAP","I49": #LOCATION = "C2M10" !CDS_LOCATION = "C2M10" #SEC = "1" !CDS_SEC = "1";
"A":   PN = "1"  !CDS_PN = "1";
"B":   PN = "2"  !CDS_PN = "2";
BODY = "CAP_A","I50": #LOCATION = "C2M9" !CDS_LOCATION = "C2M9" #SEC = "1" !CDS_SEC = "1";
"A":   PN = "1"  !CDS_PN = "1";
"B":   PN = "2"  !CDS_PN = "2";
BODY = "FERRITE","I56": #LOCATION = "FB3M4" !CDS_LOCATION = "FB3M4" #SEC = "1" !CDS_SEC = "1";
"A":   PN = "1"  !CDS_PN = "1";
"B":   PN = "2"  !CDS_PN = "2";
BODY = "CAP_A","I57": #LOCATION = "C3M31" !CDS_LOCATION = "C3M31" #SEC = "1" !CDS_SEC = "1";
"A":   PN = "1"  !CDS_PN = "1";
"B":   PN = "2"  !CDS_PN = "2";
BODY = "CAP","I64": #LOCATION = "C2N6" !CDS_LOCATION = "C2N6" #SEC = "1" !CDS_SEC = "1";
"A":   PN = "1"  !CDS_PN = "1";
"B":   PN = "2"  !CDS_PN = "2";
BODY = "CAP_A","I65": #LOCATION = "C2N5" !CDS_LOCATION = "C2N5" #SEC = "1" !CDS_SEC = "1";
"A":   PN = "1"  !CDS_PN = "1";
"B":   PN = "2"  !CDS_PN = "2";
BODY = "FERRITE","I69": #LOCATION = "FB2M2" !CDS_LOCATION = "FB2M2" #SEC = "1" !CDS_SEC = "1";
"A":   PN = "1"  !CDS_PN = "1";
"B":   PN = "2"  !CDS_PN = "2";
BODY = "INDUCTOR","I71": #LOCATION = "L2M1" !CDS_LOCATION = "L2M1" #SEC = "1" !CDS_SEC = "1";
"INA":   PN = "1"  !CDS_PN = "1";
"INB":   PN = "2"  !CDS_PN = "2";
BODY = "CAP_A","I74": #LOCATION = "C2M8" !CDS_LOCATION = "C2M8" #SEC = "1" !CDS_SEC = "1";
"A":   PN = "1"  !CDS_PN = "1";
"B":   PN = "2"  !CDS_PN = "2";
BODY = "CAP_A","I76": #LOCATION = "C2M6" !CDS_LOCATION = "C2M6" #SEC = "1" !CDS_SEC = "1";
"A":   PN = "1"  !CDS_PN = "1";
"B":   PN = "2"  !CDS_PN = "2";
BODY = "CAP_A","I78": #LOCATION = "C2M25" !CDS_LOCATION = "C2M25" #SEC = "1" !CDS_SEC = "1";
"A":   PN = "1"  !CDS_PN = "1";
"B":   PN = "2"  !CDS_PN = "2";
BODY = "CAP_A","I80": #LOCATION = "C3M29" !CDS_LOCATION = "C3M29" #SEC = "1" !CDS_SEC = "1";
"A":   PN = "1"  !CDS_PN = "1";
"B":   PN = "2"  !CDS_PN = "2";
BODY = "CAP","I81": #LOCATION = "C3M24" !CDS_LOCATION = "C3M24" #SEC = "1" !CDS_SEC = "1";
"A":   PN = "1"  !CDS_PN = "1";
"B":   PN = "2"  !CDS_PN = "2";
BODY = "CAP","I82": #LOCATION = "C3M23" !CDS_LOCATION = "C3M23" #SEC = "1" !CDS_SEC = "1";
"A":   PN = "1"  !CDS_PN = "1";
"B":   PN = "2"  !CDS_PN = "2";
BODY = "CAP_A","I83": #LOCATION = "C3M27" !CDS_LOCATION = "C3M27" #SEC = "1" !CDS_SEC = "1";
"A":   PN = "1"  !CDS_PN = "1";
"B":   PN = "2"  !CDS_PN = "2";
BODY = "CAP_A","I84": #LOCATION = "C3M20" !CDS_LOCATION = "C3M20" #SEC = "1" !CDS_SEC = "1";
"A":   PN = "1"  !CDS_PN = "1";
"B":   PN = "2"  !CDS_PN = "2";
BODY = "CAP","I85": #LOCATION = "C3M18" !CDS_LOCATION = "C3M18" #SEC = "1" !CDS_SEC = "1";
"A":   PN = "1"  !CDS_PN = "1";
"B":   PN = "2"  !CDS_PN = "2";
BODY = "CAP","I86": #LOCATION = "C3M17" !CDS_LOCATION = "C3M17" #SEC = "1" !CDS_SEC = "1";
"A":   PN = "1"  !CDS_PN = "1";
"B":   PN = "2"  !CDS_PN = "2";
BODY = "CAP_A","I87": #LOCATION = "C3M19" !CDS_LOCATION = "C3M19" #SEC = "1" !CDS_SEC = "1";
"A":   PN = "1"  !CDS_PN = "1";
"B":   PN = "2"  !CDS_PN = "2";
DRAWING = "@baseboard_fab2_lib.baseboard_fab2(sch_1):page129";
BODY = "CAP","I35": #LOCATION = "C7B25" !CDS_LOCATION = "C7B25" &SEC = "1" #&CDS_SEC = "1";
"A":   PN = "1"  !CDS_PN = "1";
"B":   PN = "2"  !CDS_PN = "2";
BODY = "CAP","I69": #LOCATION = "C7B27" !CDS_LOCATION = "C7B27" &SEC = "1" #&CDS_SEC = "1";
"A":   PN = "1"  !CDS_PN = "1";
"B":   PN = "2"  !CDS_PN = "2";
BODY = "CAP","I70": #LOCATION = "C7B28" !CDS_LOCATION = "C7B28" &SEC = "1" #&CDS_SEC = "1";
"A":   PN = "1"  !CDS_PN = "1";
"B":   PN = "2"  !CDS_PN = "2";
BODY = "CAP","I71": #LOCATION = "C7C2" !CDS_LOCATION = "C7C2" &SEC = "1" #&CDS_SEC = "1";
"A":   PN = "1"  !CDS_PN = "1";
"B":   PN = "2"  !CDS_PN = "2";
BODY = "CAP","I72": #LOCATION = "C3M40" !CDS_LOCATION = "C3M40" &SEC = "1" #&CDS_SEC = "1";
"A":   PN = "1"  !CDS_PN = "1";
"B":   PN = "2"  !CDS_PN = "2";
BODY = "CAP","I73": #LOCATION = "C3M37" !CDS_LOCATION = "C3M37" &SEC = "1" #&CDS_SEC = "1";
"A":   PN = "1"  !CDS_PN = "1";
"B":   PN = "2"  !CDS_PN = "2";
BODY = "CAP","I74": #LOCATION = "C3N9" !CDS_LOCATION = "C3N9" &SEC = "1" #&CDS_SEC = "1";
"A":   PN = "1"  !CDS_PN = "1";
"B":   PN = "2"  !CDS_PN = "2";
BODY = "CAP","I75": #LOCATION = "C3N8" !CDS_LOCATION = "C3N8" &SEC = "1" #&CDS_SEC = "1";
"A":   PN = "1"  !CDS_PN = "1";
"B":   PN = "2"  !CDS_PN = "2";
BODY = "CAP","I76": #LOCATION = "C7C3" !CDS_LOCATION = "C7C3" &SEC = "1" #&CDS_SEC = "1";
"A":   PN = "1"  !CDS_PN = "1";
"B":   PN = "2"  !CDS_PN = "2";
BODY = "CAP","I77": #LOCATION = "C7C1" !CDS_LOCATION = "C7C1" &SEC = "1" #&CDS_SEC = "1";
"A":   PN = "1"  !CDS_PN = "1";
"B":   PN = "2"  !CDS_PN = "2";
BODY = "CAP","I78": #LOCATION = "C7B29" !CDS_LOCATION = "C7B29" &SEC = "1" #&CDS_SEC = "1";
"A":   PN = "1"  !CDS_PN = "1";
"B":   PN = "2"  !CDS_PN = "2";
BODY = "CAP","I79": #LOCATION = "C7B26" !CDS_LOCATION = "C7B26" &SEC = "1" #&CDS_SEC = "1";
"A":   PN = "1"  !CDS_PN = "1";
"B":   PN = "2"  !CDS_PN = "2";
BODY = "CAP","I80": #LOCATION = "C3M44" !CDS_LOCATION = "C3M44" &SEC = "1" #&CDS_SEC = "1";
"A":   PN = "1"  !CDS_PN = "1";
"B":   PN = "2"  !CDS_PN = "2";
BODY = "CAP","I81": #LOCATION = "C3M41" !CDS_LOCATION = "C3M41" &SEC = "1" #&CDS_SEC = "1";
"A":   PN = "1"  !CDS_PN = "1";
"B":   PN = "2"  !CDS_PN = "2";
BODY = "CAP","I82": #LOCATION = "C3M45" !CDS_LOCATION = "C3M45" &SEC = "1" #&CDS_SEC = "1";
"A":   PN = "1"  !CDS_PN = "1";
"B":   PN = "2"  !CDS_PN = "2";
BODY = "CAP","I83": #LOCATION = "C3N13" !CDS_LOCATION = "C3N13" &SEC = "1" #&CDS_SEC = "1";
"A":   PN = "1"  !CDS_PN = "1";
"B":   PN = "2"  !CDS_PN = "2";
DRAWING = "@baseboard_fab2_lib.baseboard_fab2(sch_1):page130";
BODY = "CAP","I2": #LOCATION = "C7D2" !CDS_LOCATION = "C7D2" #SEC = "1" !CDS_SEC = "1";
"A":   PN = "1"  !CDS_PN = "1";
"B":   PN = "2"  !CDS_PN = "2";
BODY = "CAP_A","I4": #LOCATION = "C2N26" !CDS_LOCATION = "C2N26" &SEC = "1" #&CDS_SEC = "1";
"A":   PN = "1"  !CDS_PN = "1";
"B":   PN = "2"  !CDS_PN = "2";
BODY = "CAP_A","I7": #LOCATION = "C2N19" !CDS_LOCATION = "C2N19" &SEC = "1" #&CDS_SEC = "1";
"A":   PN = "1"  !CDS_PN = "1";
"B":   PN = "2"  !CDS_PN = "2";
BODY = "CAP","I8": #LOCATION = "C2N24" !CDS_LOCATION = "C2N24" &SEC = "1" #&CDS_SEC = "1";
"A":   PN = "1"  !CDS_PN = "1";
"B":   PN = "2"  !CDS_PN = "2";
BODY = "CAP","I9": #LOCATION = "C2N22" !CDS_LOCATION = "C2N22" &SEC = "1" #&CDS_SEC = "1";
"A":   PN = "1"  !CDS_PN = "1";
"B":   PN = "2"  !CDS_PN = "2";
BODY = "CAP_A","I12": #LOCATION = "C2N20" !CDS_LOCATION = "C2N20" &SEC = "1" #&CDS_SEC = "1";
"A":   PN = "1"  !CDS_PN = "1";
"B":   PN = "2"  !CDS_PN = "2";
BODY = "CAP","I15": #LOCATION = "C2N21" !CDS_LOCATION = "C2N21" &SEC = "1" #&CDS_SEC = "1";
"A":   PN = "1"  !CDS_PN = "1";
"B":   PN = "2"  !CDS_PN = "2";
BODY = "CAP_A","I16": #LOCATION = "C3N29" !CDS_LOCATION = "C3N29" &SEC = "1" #&CDS_SEC = "1";
"A":   PN = "1"  !CDS_PN = "1";
"B":   PN = "2"  !CDS_PN = "2";
BODY = "CAP","I19": #LOCATION = "C8C3" !CDS_LOCATION = "C8C3" &SEC = "1" #&CDS_SEC = "1";
"A":   PN = "1"  !CDS_PN = "1";
"B":   PN = "2"  !CDS_PN = "2";
BODY = "CAP","I20": #LOCATION = "C8C4" !CDS_LOCATION = "C8C4" &SEC = "1" #&CDS_SEC = "1";
"A":   PN = "1"  !CDS_PN = "1";
"B":   PN = "2"  !CDS_PN = "2";
BODY = "CAP","I21": #LOCATION = "C8C5" !CDS_LOCATION = "C8C5" &SEC = "1" #&CDS_SEC = "1";
"A":   PN = "1"  !CDS_PN = "1";
"B":   PN = "2"  !CDS_PN = "2";
BODY = "CAP","I22": #LOCATION = "C8C6" !CDS_LOCATION = "C8C6" &SEC = "1" #&CDS_SEC = "1";
"A":   PN = "1"  !CDS_PN = "1";
"B":   PN = "2"  !CDS_PN = "2";
BODY = "CAP","I24": #LOCATION = "C2N23" !CDS_LOCATION = "C2N23" &SEC = "1" #&CDS_SEC = "1";
"A":   PN = "1"  !CDS_PN = "1";
"B":   PN = "2"  !CDS_PN = "2";
BODY = "CAP","I25": #LOCATION = "C2N14" !CDS_LOCATION = "C2N14" &SEC = "1" #&CDS_SEC = "1";
"A":   PN = "1"  !CDS_PN = "1";
"B":   PN = "2"  !CDS_PN = "2";
BODY = "CAP","I28": #LOCATION = "C2N17" !CDS_LOCATION = "C2N17" &SEC = "1" #&CDS_SEC = "1";
"A":   PN = "1"  !CDS_PN = "1";
"B":   PN = "2"  !CDS_PN = "2";
BODY = "CAP_A","I29": #LOCATION = "C2N18" !CDS_LOCATION = "C2N18" &SEC = "1" #&CDS_SEC = "1";
"A":   PN = "1"  !CDS_PN = "1";
"B":   PN = "2"  !CDS_PN = "2";
BODY = "CAP_A","I30": #LOCATION = "C8B2" !CDS_LOCATION = "C8B2" &SEC = "1" #&CDS_SEC = "1";
"A":   PN = "1"  !CDS_PN = "1";
"B":   PN = "2"  !CDS_PN = "2";
BODY = "CAP_A","I32": #LOCATION = "C8B3" !CDS_LOCATION = "C8B3" &SEC = "1" #&CDS_SEC = "1";
"A":   PN = "1"  !CDS_PN = "1";
"B":   PN = "2"  !CDS_PN = "2";
BODY = "CAP_A","I34": #LOCATION = "C2N25" !CDS_LOCATION = "C2N25" &SEC = "1" #&CDS_SEC = "1";
"A":   PN = "1"  !CDS_PN = "1";
"B":   PN = "2"  !CDS_PN = "2";
BODY = "CAP_A","I37": #LOCATION = "C2M16" !CDS_LOCATION = "C2M16" &SEC = "1" #&CDS_SEC = "1";
"A":   PN = "1"  !CDS_PN = "1";
"B":   PN = "2"  !CDS_PN = "2";
BODY = "CAP_A","I38": #LOCATION = "C7D3" !CDS_LOCATION = "C7D3" &SEC = "1" #&CDS_SEC = "1";
"A":   PN = "1"  !CDS_PN = "1";
"B":   PN = "2"  !CDS_PN = "2";
BODY = "CAP_A","I39": #LOCATION = "C8B4" !CDS_LOCATION = "C8B4" &SEC = "1" #&CDS_SEC = "1";
"A":   PN = "1"  !CDS_PN = "1";
"B":   PN = "2"  !CDS_PN = "2";
BODY = "CAP_A","I41": #LOCATION = "C8B1" !CDS_LOCATION = "C8B1" &SEC = "1" #&CDS_SEC = "1";
"A":   PN = "1"  !CDS_PN = "1";
"B":   PN = "2"  !CDS_PN = "2";
BODY = "CAP_A","I42": #LOCATION = "C3N23" !CDS_LOCATION = "C3N23" &SEC = "1" #&CDS_SEC = "1";
"A":   PN = "1"  !CDS_PN = "1";
"B":   PN = "2"  !CDS_PN = "2";
BODY = "CAP_A","I43": #LOCATION = "C2M1" !CDS_LOCATION = "C2M1" &SEC = "1" #&CDS_SEC = "1";
"A":   PN = "1"  !CDS_PN = "1";
"B":   PN = "2"  !CDS_PN = "2";
BODY = "CAP_A","I45": #LOCATION = "C2M2" !CDS_LOCATION = "C2M2" &SEC = "1" #&CDS_SEC = "1";
"A":   PN = "1"  !CDS_PN = "1";
"B":   PN = "2"  !CDS_PN = "2";
BODY = "CAP_A","I47": #LOCATION = "C2N15" !CDS_LOCATION = "C2N15" &SEC = "1" #&CDS_SEC = "1";
"A":   PN = "1"  !CDS_PN = "1";
"B":   PN = "2"  !CDS_PN = "2";
BODY = "CAP_A","I49": #LOCATION = "C3N21" !CDS_LOCATION = "C3N21" &SEC = "1" #&CDS_SEC = "1";
"A":   PN = "1"  !CDS_PN = "1";
"B":   PN = "2"  !CDS_PN = "2";
BODY = "CAP_A","I50": #LOCATION = "C3N25" !CDS_LOCATION = "C3N25" &SEC = "1" #&CDS_SEC = "1";
"A":   PN = "1"  !CDS_PN = "1";
"B":   PN = "2"  !CDS_PN = "2";
BODY = "CAP_A","I52": #LOCATION = "C2N16" !CDS_LOCATION = "C2N16" &SEC = "1" #&CDS_SEC = "1";
"A":   PN = "1"  !CDS_PN = "1";
"B":   PN = "2"  !CDS_PN = "2";
BODY = "CAP_A","I53": #LOCATION = "C3N22" !CDS_LOCATION = "C3N22" &SEC = "1" #&CDS_SEC = "1";
"A":   PN = "1"  !CDS_PN = "1";
"B":   PN = "2"  !CDS_PN = "2";
DRAWING = "@baseboard_fab2_lib.baseboard_fab2(sch_1):page131";
BODY = "CAP_A","I1": #LOCATION = "C7B15" !CDS_LOCATION = "C7B15" &SEC = "1" #&CDS_SEC = "1";
"A":   PN = "1"  !CDS_PN = "1";
"B":   PN = "2"  !CDS_PN = "2";
BODY = "CAP_A","I2": #LOCATION = "C7B19" !CDS_LOCATION = "C7B19" &SEC = "1" #&CDS_SEC = "1";
"A":   PN = "1"  !CDS_PN = "1";
"B":   PN = "2"  !CDS_PN = "2";
BODY = "CAP_A","I3": #LOCATION = "C7B16" !CDS_LOCATION = "C7B16" &SEC = "1" #&CDS_SEC = "1";
"A":   PN = "1"  !CDS_PN = "1";
"B":   PN = "2"  !CDS_PN = "2";
BODY = "CAP_A","I4": #LOCATION = "C7B21" !CDS_LOCATION = "C7B21" &SEC = "1" #&CDS_SEC = "1";
"A":   PN = "1"  !CDS_PN = "1";
"B":   PN = "2"  !CDS_PN = "2";
BODY = "CAP_A","I6": #LOCATION = "C7B20" !CDS_LOCATION = "C7B20" &SEC = "1" #&CDS_SEC = "1";
"A":   PN = "1"  !CDS_PN = "1";
"B":   PN = "2"  !CDS_PN = "2";
BODY = "CAP_A","I7": #LOCATION = "C7B23" !CDS_LOCATION = "C7B23" &SEC = "1" #&CDS_SEC = "1";
"A":   PN = "1"  !CDS_PN = "1";
"B":   PN = "2"  !CDS_PN = "2";
BODY = "CAP_A","I8": #LOCATION = "C8B10" !CDS_LOCATION = "C8B10" &SEC = "1" #&CDS_SEC = "1";
"A":   PN = "1"  !CDS_PN = "1";
"B":   PN = "2"  !CDS_PN = "2";
BODY = "CAP_A","I10": #LOCATION = "C7B22" !CDS_LOCATION = "C7B22" &SEC = "1" #&CDS_SEC = "1";
"A":   PN = "1"  !CDS_PN = "1";
"B":   PN = "2"  !CDS_PN = "2";
BODY = "CAP_A","I11": #LOCATION = "C7B24" !CDS_LOCATION = "C7B24" &SEC = "1" #&CDS_SEC = "1";
"A":   PN = "1"  !CDS_PN = "1";
"B":   PN = "2"  !CDS_PN = "2";
BODY = "CAP_A","I12": #LOCATION = "C7B18" !CDS_LOCATION = "C7B18" &SEC = "1" #&CDS_SEC = "1";
"A":   PN = "1"  !CDS_PN = "1";
"B":   PN = "2"  !CDS_PN = "2";
BODY = "CAP_A","I14": #LOCATION = "C8B9" !CDS_LOCATION = "C8B9" &SEC = "1" #&CDS_SEC = "1";
"A":   PN = "1"  !CDS_PN = "1";
"B":   PN = "2"  !CDS_PN = "2";
BODY = "CAP_A","I15": #LOCATION = "C8B11" !CDS_LOCATION = "C8B11" &SEC = "1" #&CDS_SEC = "1";
"A":   PN = "1"  !CDS_PN = "1";
"B":   PN = "2"  !CDS_PN = "2";
BODY = "CAP_A","I16": #LOCATION = "C8B14" !CDS_LOCATION = "C8B14" &SEC = "1" #&CDS_SEC = "1";
"A":   PN = "1"  !CDS_PN = "1";
"B":   PN = "2"  !CDS_PN = "2";
BODY = "CAP_A","I18": #LOCATION = "C7B17" !CDS_LOCATION = "C7B17" &SEC = "1" #&CDS_SEC = "1";
"A":   PN = "1"  !CDS_PN = "1";
"B":   PN = "2"  !CDS_PN = "2";
BODY = "CAP_A","I20": #LOCATION = "C8B13" !CDS_LOCATION = "C8B13" &SEC = "1" #&CDS_SEC = "1";
"A":   PN = "1"  !CDS_PN = "1";
"B":   PN = "2"  !CDS_PN = "2";
BODY = "CAP","I22": #LOCATION = "C8B16" !CDS_LOCATION = "C8B16" &SEC = "1" #&CDS_SEC = "1";
"A":   PN = "1"  !CDS_PN = "1";
"B":   PN = "2"  !CDS_PN = "2";
BODY = "CAP","I24": #LOCATION = "C8B15" !CDS_LOCATION = "C8B15" &SEC = "1" #&CDS_SEC = "1";
"A":   PN = "1"  !CDS_PN = "1";
"B":   PN = "2"  !CDS_PN = "2";
BODY = "CAP_A","I27": #LOCATION = "C2M22" !CDS_LOCATION = "C2M22" &SEC = "1" #&CDS_SEC = "1";
"A":   PN = "1"  !CDS_PN = "1";
"B":   PN = "2"  !CDS_PN = "2";
BODY = "CAP_A","I28": #LOCATION = "C2M21" !CDS_LOCATION = "C2M21" &SEC = "1" #&CDS_SEC = "1";
"A":   PN = "1"  !CDS_PN = "1";
"B":   PN = "2"  !CDS_PN = "2";
BODY = "CAP_A","I29": #LOCATION = "C2M18" !CDS_LOCATION = "C2M18" &SEC = "1" #&CDS_SEC = "1";
"A":   PN = "1"  !CDS_PN = "1";
"B":   PN = "2"  !CDS_PN = "2";
BODY = "CAP_A","I31": #LOCATION = "C2M19" !CDS_LOCATION = "C2M19" &SEC = "1" #&CDS_SEC = "1";
"A":   PN = "1"  !CDS_PN = "1";
"B":   PN = "2"  !CDS_PN = "2";
BODY = "CAP_A","I32": #LOCATION = "C3M38" !CDS_LOCATION = "C3M38" &SEC = "1" #&CDS_SEC = "1";
"A":   PN = "1"  !CDS_PN = "1";
"B":   PN = "2"  !CDS_PN = "2";
BODY = "CAP","I34": #LOCATION = "C2M17" !CDS_LOCATION = "C2M17" &SEC = "1" #&CDS_SEC = "1";
"A":   PN = "1"  !CDS_PN = "1";
"B":   PN = "2"  !CDS_PN = "2";
BODY = "CAP","I35": #LOCATION = "C2M11" !CDS_LOCATION = "C2M11" &SEC = "1" #&CDS_SEC = "1";
"A":   PN = "1"  !CDS_PN = "1";
"B":   PN = "2"  !CDS_PN = "2";
BODY = "CAP","I37": #LOCATION = "C8A13" !CDS_LOCATION = "C8A13" &SEC = "1" #&CDS_SEC = "1";
"A":   PN = "1"  !CDS_PN = "1";
"B":   PN = "2"  !CDS_PN = "2";
BODY = "CAP_A","I39": #LOCATION = "C2M20" !CDS_LOCATION = "C2M20" &SEC = "1" #&CDS_SEC = "1";
"A":   PN = "1"  !CDS_PN = "1";
"B":   PN = "2"  !CDS_PN = "2";
BODY = "CAP_A","I40": #LOCATION = "C2N13" !CDS_LOCATION = "C2N13" &SEC = "1" #&CDS_SEC = "1";
"A":   PN = "1"  !CDS_PN = "1";
"B":   PN = "2"  !CDS_PN = "2";
BODY = "CAP_A","I41": #LOCATION = "C2N2" !CDS_LOCATION = "C2N2" &SEC = "1" #&CDS_SEC = "1";
"A":   PN = "1"  !CDS_PN = "1";
"B":   PN = "2"  !CDS_PN = "2";
BODY = "CAP_A","I42": #LOCATION = "C3M43" !CDS_LOCATION = "C3M43" &SEC = "1" #&CDS_SEC = "1";
"A":   PN = "1"  !CDS_PN = "1";
"B":   PN = "2"  !CDS_PN = "2";
BODY = "CAP_A","I43": #LOCATION = "C2N7" !CDS_LOCATION = "C2N7" &SEC = "1" #&CDS_SEC = "1";
"A":   PN = "1"  !CDS_PN = "1";
"B":   PN = "2"  !CDS_PN = "2";
BODY = "CAP_A","I44": #LOCATION = "C3M39" !CDS_LOCATION = "C3M39" &SEC = "1" #&CDS_SEC = "1";
"A":   PN = "1"  !CDS_PN = "1";
"B":   PN = "2"  !CDS_PN = "2";
BODY = "CAP_A","I45": #LOCATION = "C3M42" !CDS_LOCATION = "C3M42" &SEC = "1" #&CDS_SEC = "1";
"A":   PN = "1"  !CDS_PN = "1";
"B":   PN = "2"  !CDS_PN = "2";
BODY = "CAP_A","I47": #LOCATION = "C2N8" !CDS_LOCATION = "C2N8" &SEC = "1" #&CDS_SEC = "1";
"A":   PN = "1"  !CDS_PN = "1";
"B":   PN = "2"  !CDS_PN = "2";
BODY = "CAP_A","I48": #LOCATION = "C2M13" !CDS_LOCATION = "C2M13" &SEC = "1" #&CDS_SEC = "1";
"A":   PN = "1"  !CDS_PN = "1";
"B":   PN = "2"  !CDS_PN = "2";
BODY = "CAP_A","I50": #LOCATION = "C2N10" !CDS_LOCATION = "C2N10" &SEC = "1" #&CDS_SEC = "1";
"A":   PN = "1"  !CDS_PN = "1";
"B":   PN = "2"  !CDS_PN = "2";
BODY = "CAP_A","I52": #LOCATION = "C2M12" !CDS_LOCATION = "C2M12" &SEC = "1" #&CDS_SEC = "1";
"A":   PN = "1"  !CDS_PN = "1";
"B":   PN = "2"  !CDS_PN = "2";
DRAWING = "@baseboard_fab2_lib.baseboard_fab2(sch_1):page132";
BODY = "CAP_A","I1": #LOCATION = "C3L25" !CDS_LOCATION = "C3L25" &SEC = "1" #&CDS_SEC = "1";
"A":   PN = "1"  !CDS_PN = "1";
"B":   PN = "2"  !CDS_PN = "2";
BODY = "CAP_A","I2": #LOCATION = "C3M7" !CDS_LOCATION = "C3M7" &SEC = "1" #&CDS_SEC = "1";
"A":   PN = "1"  !CDS_PN = "1";
"B":   PN = "2"  !CDS_PN = "2";
BODY = "CAP_A","I3": #LOCATION = "C3L26" !CDS_LOCATION = "C3L26" &SEC = "1" #&CDS_SEC = "1";
"A":   PN = "1"  !CDS_PN = "1";
"B":   PN = "2"  !CDS_PN = "2";
BODY = "CAP_A","I4": #LOCATION = "C3L27" !CDS_LOCATION = "C3L27" &SEC = "1" #&CDS_SEC = "1";
"A":   PN = "1"  !CDS_PN = "1";
"B":   PN = "2"  !CDS_PN = "2";
BODY = "CAP_A","I6": #LOCATION = "C3M6" !CDS_LOCATION = "C3M6" &SEC = "1" #&CDS_SEC = "1";
"A":   PN = "1"  !CDS_PN = "1";
"B":   PN = "2"  !CDS_PN = "2";
BODY = "CAP_A","I7": #LOCATION = "C7C9" !CDS_LOCATION = "C7C9" &SEC = "1" #&CDS_SEC = "1";
"A":   PN = "1"  !CDS_PN = "1";
"B":   PN = "2"  !CDS_PN = "2";
BODY = "CAP_A","I8": #LOCATION = "C3N27" !CDS_LOCATION = "C3N27" &SEC = "1" #&CDS_SEC = "1";
"A":   PN = "1"  !CDS_PN = "1";
"B":   PN = "2"  !CDS_PN = "2";
BODY = "CAP_A","I9": #LOCATION = "C3N30" !CDS_LOCATION = "C3N30" &SEC = "1" #&CDS_SEC = "1";
"A":   PN = "1"  !CDS_PN = "1";
"B":   PN = "2"  !CDS_PN = "2";
BODY = "CAP_A","I11": #LOCATION = "C7A36" !CDS_LOCATION = "C7A36" &SEC = "1" #&CDS_SEC = "1";
"A":   PN = "1"  !CDS_PN = "1";
"B":   PN = "2"  !CDS_PN = "2";
BODY = "CAP_A","I12": #LOCATION = "C3N12" !CDS_LOCATION = "C3N12" &SEC = "1" #&CDS_SEC = "1";
"A":   PN = "1"  !CDS_PN = "1";
"B":   PN = "2"  !CDS_PN = "2";
BODY = "CAP_A","I13": #LOCATION = "C3N10" !CDS_LOCATION = "C3N10" &SEC = "1" #&CDS_SEC = "1";
"A":   PN = "1"  !CDS_PN = "1";
"B":   PN = "2"  !CDS_PN = "2";
BODY = "CAP_A","I16": #LOCATION = "C3N24" !CDS_LOCATION = "C3N24" &SEC = "1" #&CDS_SEC = "1";
"A":   PN = "1"  !CDS_PN = "1";
"B":   PN = "2"  !CDS_PN = "2";
BODY = "CAP_A","I17": #LOCATION = "C3N28" !CDS_LOCATION = "C3N28" &SEC = "1" #&CDS_SEC = "1";
"A":   PN = "1"  !CDS_PN = "1";
"B":   PN = "2"  !CDS_PN = "2";
BODY = "CAP_A","I19": #LOCATION = "C3N11" !CDS_LOCATION = "C3N11" &SEC = "1" #&CDS_SEC = "1";
"A":   PN = "1"  !CDS_PN = "1";
"B":   PN = "2"  !CDS_PN = "2";
BODY = "CAP_A","I20": #LOCATION = "C3N31" !CDS_LOCATION = "C3N31" &SEC = "1" #&CDS_SEC = "1";
"A":   PN = "1"  !CDS_PN = "1";
"B":   PN = "2"  !CDS_PN = "2";
BODY = "CAP","I23": #LOCATION = "C7A33" !CDS_LOCATION = "C7A33" &SEC = "1" #&CDS_SEC = "1";
"A":   PN = "1"  !CDS_PN = "1";
"B":   PN = "2"  !CDS_PN = "2";
BODY = "CAP","I24": #LOCATION = "C7B4" !CDS_LOCATION = "C7B4" &SEC = "1" #&CDS_SEC = "1";
"A":   PN = "1"  !CDS_PN = "1";
"B":   PN = "2"  !CDS_PN = "2";
BODY = "CAP_A","I26": #LOCATION = "C2N9" !CDS_LOCATION = "C2N9" &SEC = "1" #&CDS_SEC = "1";
"A":   PN = "1"  !CDS_PN = "1";
"B":   PN = "2"  !CDS_PN = "2";
BODY = "CAP_A","I27": #LOCATION = "C2N3" !CDS_LOCATION = "C2N3" &SEC = "1" #&CDS_SEC = "1";
"A":   PN = "1"  !CDS_PN = "1";
"B":   PN = "2"  !CDS_PN = "2";
BODY = "CAP_A","I28": #LOCATION = "C2N4" !CDS_LOCATION = "C2N4" &SEC = "1" #&CDS_SEC = "1";
"A":   PN = "1"  !CDS_PN = "1";
"B":   PN = "2"  !CDS_PN = "2";
BODY = "CAP_A","I29": #LOCATION = "C2N12" !CDS_LOCATION = "C2N12" &SEC = "1" #&CDS_SEC = "1";
"A":   PN = "1"  !CDS_PN = "1";
"B":   PN = "2"  !CDS_PN = "2";
BODY = "CAP_A","I30": #LOCATION = "C2N11" !CDS_LOCATION = "C2N11" &SEC = "1" #&CDS_SEC = "1";
"A":   PN = "1"  !CDS_PN = "1";
"B":   PN = "2"  !CDS_PN = "2";
BODY = "CAP_A","I31": #LOCATION = "C3N19" !CDS_LOCATION = "C3N19" &SEC = "1" #&CDS_SEC = "1";
"A":   PN = "1"  !CDS_PN = "1";
"B":   PN = "2"  !CDS_PN = "2";
BODY = "CAP_A","I32": #LOCATION = "C3N3" !CDS_LOCATION = "C3N3" &SEC = "1" #&CDS_SEC = "1";
"A":   PN = "1"  !CDS_PN = "1";
"B":   PN = "2"  !CDS_PN = "2";
BODY = "CAP_A","I34": #LOCATION = "C3N1" !CDS_LOCATION = "C3N1" &SEC = "1" #&CDS_SEC = "1";
"A":   PN = "1"  !CDS_PN = "1";
"B":   PN = "2"  !CDS_PN = "2";
BODY = "CAP_A","I35": #LOCATION = "C3N7" !CDS_LOCATION = "C3N7" &SEC = "1" #&CDS_SEC = "1";
"A":   PN = "1"  !CDS_PN = "1";
"B":   PN = "2"  !CDS_PN = "2";
BODY = "CAP_A","I36": #LOCATION = "C3N16" !CDS_LOCATION = "C3N16" &SEC = "1" #&CDS_SEC = "1";
"A":   PN = "1"  !CDS_PN = "1";
"B":   PN = "2"  !CDS_PN = "2";
BODY = "CAP","I38": #LOCATION = "C7A32" !CDS_LOCATION = "C7A32" &SEC = "1" #&CDS_SEC = "1";
"A":   PN = "1"  !CDS_PN = "1";
"B":   PN = "2"  !CDS_PN = "2";
BODY = "CAP","I40": #LOCATION = "C7A31" !CDS_LOCATION = "C7A31" &SEC = "1" #&CDS_SEC = "1";
"A":   PN = "1"  !CDS_PN = "1";
"B":   PN = "2"  !CDS_PN = "2";
BODY = "CAP_A","I42": #LOCATION = "C3N18" !CDS_LOCATION = "C3N18" &SEC = "1" #&CDS_SEC = "1";
"A":   PN = "1"  !CDS_PN = "1";
"B":   PN = "2"  !CDS_PN = "2";
BODY = "CAP_A","I43": #LOCATION = "C3N2" !CDS_LOCATION = "C3N2" &SEC = "1" #&CDS_SEC = "1";
"A":   PN = "1"  !CDS_PN = "1";
"B":   PN = "2"  !CDS_PN = "2";
BODY = "CAP_A","I44": #LOCATION = "C3N6" !CDS_LOCATION = "C3N6" &SEC = "1" #&CDS_SEC = "1";
"A":   PN = "1"  !CDS_PN = "1";
"B":   PN = "2"  !CDS_PN = "2";
BODY = "CAP_A","I45": #LOCATION = "C3N17" !CDS_LOCATION = "C3N17" &SEC = "1" #&CDS_SEC = "1";
"A":   PN = "1"  !CDS_PN = "1";
"B":   PN = "2"  !CDS_PN = "2";
BODY = "CAP_A","I46": #LOCATION = "C3N4" !CDS_LOCATION = "C3N4" &SEC = "1" #&CDS_SEC = "1";
"A":   PN = "1"  !CDS_PN = "1";
"B":   PN = "2"  !CDS_PN = "2";
BODY = "CAP_A","I48": #LOCATION = "C3N5" !CDS_LOCATION = "C3N5" &SEC = "1" #&CDS_SEC = "1";
"A":   PN = "1"  !CDS_PN = "1";
"B":   PN = "2"  !CDS_PN = "2";
BODY = "CAP_A","I49": #LOCATION = "C3N15" !CDS_LOCATION = "C3N15" &SEC = "1" #&CDS_SEC = "1";
"A":   PN = "1"  !CDS_PN = "1";
"B":   PN = "2"  !CDS_PN = "2";
BODY = "CAP_A","I51": #LOCATION = "C3N20" !CDS_LOCATION = "C3N20" &SEC = "1" #&CDS_SEC = "1";
"A":   PN = "1"  !CDS_PN = "1";
"B":   PN = "2"  !CDS_PN = "2";
BODY = "CAP_A","I52": #LOCATION = "C3L23" !CDS_LOCATION = "C3L23" &SEC = "1" #&CDS_SEC = "1";
"A":   PN = "1"  !CDS_PN = "1";
"B":   PN = "2"  !CDS_PN = "2";
BODY = "CAP_A","I54": #LOCATION = "C3L22" !CDS_LOCATION = "C3L22" &SEC = "1" #&CDS_SEC = "1";
"A":   PN = "1"  !CDS_PN = "1";
"B":   PN = "2"  !CDS_PN = "2";
BODY = "CAP_A","I56": #LOCATION = "C3L24" !CDS_LOCATION = "C3L24" &SEC = "1" #&CDS_SEC = "1";
"A":   PN = "1"  !CDS_PN = "1";
"B":   PN = "2"  !CDS_PN = "2";
DRAWING = "@baseboard_fab2_lib.baseboard_fab2(sch_1):page133";
BODY = "RES","I120": #LOCATION = "R3N3" !CDS_LOCATION = "R3N3" &SEC = "1" #&CDS_SEC = "1";
"A":   PN = "1"  !CDS_PN = "1";
"B":   PN = "2"  !CDS_PN = "2";
BODY = "RES","I122": #LOCATION = "R2N12" !CDS_LOCATION = "R2N12" &SEC = "1" #&CDS_SEC = "1";
"A":   PN = "1"  !CDS_PN = "1";
"B":   PN = "2"  !CDS_PN = "2";
BODY = "RES","I200": #LOCATION = "R7D8" !CDS_LOCATION = "R7D8" #SEC = "1" !CDS_SEC = "1";
"A":   PN = "1"  !CDS_PN = "1";
"B":   PN = "2"  !CDS_PN = "2";
BODY = "RES","I202": #LOCATION = "R7D10" !CDS_LOCATION = "R7D10" #SEC = "1" !CDS_SEC = "1";
"A":   PN = "1"  !CDS_PN = "1";
"B":   PN = "2"  !CDS_PN = "2";
BODY = "RES","I237": #LOCATION = "R7D12" !CDS_LOCATION = "R7D12" #SEC = "1" !CDS_SEC = "1";
"A":   PN = "1"  !CDS_PN = "1";
"B":   PN = "2"  !CDS_PN = "2";
BODY = "RES","I243": #LOCATION = "R7D3" !CDS_LOCATION = "R7D3" #SEC = "1" !CDS_SEC = "1";
"A":   PN = "1"  !CDS_PN = "1";
"B":   PN = "2"  !CDS_PN = "2";
BODY = "RES","I245": #LOCATION = "R7D4" !CDS_LOCATION = "R7D4" #SEC = "1" !CDS_SEC = "1";
"A":   PN = "1"  !CDS_PN = "1";
"B":   PN = "2"  !CDS_PN = "2";
BODY = "RES","I247": #LOCATION = "R2N16" !CDS_LOCATION = "R2N16" &SEC = "1" #&CDS_SEC = "1";
"A":   PN = "1"  !CDS_PN = "1";
"B":   PN = "2"  !CDS_PN = "2";
BODY = "RES","I258": #LOCATION = "R2R5" !CDS_LOCATION = "R2R5" #SEC = "1" !CDS_SEC = "1";
"A":   PN = "1"  !CDS_PN = "1";
"B":   PN = "2"  !CDS_PN = "2";
BODY = "RES","I267": #LOCATION = "R2N9" !CDS_LOCATION = "R2N9" #SEC = "1" !CDS_SEC = "1";
"A":   PN = "1"  !CDS_PN = "1";
"B":   PN = "2"  !CDS_PN = "2";
BODY = "RES","I280": #LOCATION = "R8B23" !CDS_LOCATION = "R8B23" #SEC = "1" !CDS_SEC = "1";
"A":   PN = "1"  !CDS_PN = "1";
"B":   PN = "2"  !CDS_PN = "2";
BODY = "RES","I282": #LOCATION = "R8B30" !CDS_LOCATION = "R8B30" #SEC = "1" !CDS_SEC = "1";
"A":   PN = "1"  !CDS_PN = "1";
"B":   PN = "2"  !CDS_PN = "2";
BODY = "RES","I284": #LOCATION = "R2M4" !CDS_LOCATION = "R2M4" #SEC = "1" !CDS_SEC = "1";
"A":   PN = "1"  !CDS_PN = "1";
"B":   PN = "2"  !CDS_PN = "2";
BODY = "RES","I286": #LOCATION = "R8C4" !CDS_LOCATION = "R8C4" #SEC = "1" !CDS_SEC = "1";
"A":   PN = "1"  !CDS_PN = "1";
"B":   PN = "2"  !CDS_PN = "2";
BODY = "RES","I295": #LOCATION = "R7B6" !CDS_LOCATION = "R7B6" #SEC = "1" !CDS_SEC = "1";
"A":   PN = "1"  !CDS_PN = "1";
"B":   PN = "2"  !CDS_PN = "2";
BODY = "RES","I296": #LOCATION = "R7C8" !CDS_LOCATION = "R7C8" #SEC = "1" !CDS_SEC = "1";
"A":   PN = "1"  !CDS_PN = "1";
"B":   PN = "2"  !CDS_PN = "2";
BODY = "RES","I297": #LOCATION = "R7C5" !CDS_LOCATION = "R7C5" #SEC = "1" !CDS_SEC = "1";
"A":   PN = "1"  !CDS_PN = "1";
"B":   PN = "2"  !CDS_PN = "2";
BODY = "RES","I301": #LOCATION = "R8D14" !CDS_LOCATION = "R8D14" #SEC = "1" !CDS_SEC = "1";
"A":   PN = "1"  !CDS_PN = "1";
"B":   PN = "2"  !CDS_PN = "2";
BODY = "RES","I303": #LOCATION = "R8C6" !CDS_LOCATION = "R8C6" #SEC = "1" !CDS_SEC = "1";
"A":   PN = "1"  !CDS_PN = "1";
"B":   PN = "2"  !CDS_PN = "2";
BODY = "RES","I304": #LOCATION = "R8C2" !CDS_LOCATION = "R8C2" #SEC = "1" !CDS_SEC = "1";
"A":   PN = "1"  !CDS_PN = "1";
"B":   PN = "2"  !CDS_PN = "2";
BODY = "RES","I306": #LOCATION = "R7D6" !CDS_LOCATION = "R7D6" #SEC = "1" !CDS_SEC = "1";
"A":   PN = "1"  !CDS_PN = "1";
"B":   PN = "2"  !CDS_PN = "2";
BODY = "RES","I307": #LOCATION = "R8B31" !CDS_LOCATION = "R8B31" #SEC = "1" !CDS_SEC = "1";
"A":   PN = "1"  !CDS_PN = "1";
"B":   PN = "2"  !CDS_PN = "2";
BODY = "RES","I309": #LOCATION = "R2N7" !CDS_LOCATION = "R2N7" #SEC = "1" !CDS_SEC = "1";
"A":   PN = "1"  !CDS_PN = "1";
"B":   PN = "2"  !CDS_PN = "2";
BODY = "RES","I315": #LOCATION = "R3P7" !CDS_LOCATION = "R3P7" #SEC = "1" !CDS_SEC = "1";
"A":   PN = "1"  !CDS_PN = "1";
"B":   PN = "2"  !CDS_PN = "2";
BODY = "RES","I316": #LOCATION = "R3P5" !CDS_LOCATION = "R3P5" #SEC = "1" !CDS_SEC = "1";
"A":   PN = "1"  !CDS_PN = "1";
"B":   PN = "2"  !CDS_PN = "2";
BODY = "RES","I317": #LOCATION = "R3P6" !CDS_LOCATION = "R3P6" #SEC = "1" !CDS_SEC = "1";
"A":   PN = "1"  !CDS_PN = "1";
"B":   PN = "2"  !CDS_PN = "2";
BODY = "RES","I318": #LOCATION = "R3N15" !CDS_LOCATION = "R3N15" #SEC = "1" !CDS_SEC = "1";
"A":   PN = "1"  !CDS_PN = "1";
"B":   PN = "2"  !CDS_PN = "2";
BODY = "RES","I321": #LOCATION = "R3N16" !CDS_LOCATION = "R3N16" #SEC = "1" !CDS_SEC = "1";
"A":   PN = "1"  !CDS_PN = "1";
"B":   PN = "2"  !CDS_PN = "2";
BODY = "RES","I322": #LOCATION = "R3P8" !CDS_LOCATION = "R3P8" #SEC = "1" !CDS_SEC = "1";
"A":   PN = "1"  !CDS_PN = "1";
"B":   PN = "2"  !CDS_PN = "2";
BODY = "RES","I326": #LOCATION = "R8C1" !CDS_LOCATION = "R8C1" #SEC = "1" !CDS_SEC = "1";
"A":   PN = "1"  !CDS_PN = "1";
"B":   PN = "2"  !CDS_PN = "2";
BODY = "RES","I327": #LOCATION = "R8C7" !CDS_LOCATION = "R8C7" #SEC = "1" !CDS_SEC = "1";
"A":   PN = "1"  !CDS_PN = "1";
"B":   PN = "2"  !CDS_PN = "2";
BODY = "RES","I331": #LOCATION = "R7D7" !CDS_LOCATION = "R7D7" #SEC = "1" !CDS_SEC = "1";
"A":   PN = "1"  !CDS_PN = "1";
"B":   PN = "2"  !CDS_PN = "2";
BODY = "RES","I332": #LOCATION = "R7D2" !CDS_LOCATION = "R7D2" #SEC = "1" !CDS_SEC = "1";
"A":   PN = "1"  !CDS_PN = "1";
"B":   PN = "2"  !CDS_PN = "2";
BODY = "RES","I333": #LOCATION = "R8C25" !CDS_LOCATION = "R8C25" #SEC = "1" !CDS_SEC = "1";
"A":   PN = "1"  !CDS_PN = "1";
"B":   PN = "2"  !CDS_PN = "2";
BODY = "RES","I341": #LOCATION = "R2N32" !CDS_LOCATION = "R2N32" #SEC = "1" !CDS_SEC = "1";
"A":   PN = "1"  !CDS_PN = "1";
"B":   PN = "2"  !CDS_PN = "2";
BODY = "RES","I349": #LOCATION = "R2M8" !CDS_LOCATION = "R2M8" #SEC = "1" !CDS_SEC = "1";
"A":   PN = "1"  !CDS_PN = "1";
"B":   PN = "2"  !CDS_PN = "2";
BODY = "RES","I352": #LOCATION = "R2N29" !CDS_LOCATION = "R2N29" #SEC = "1" !CDS_SEC = "1";
"A":   PN = "1"  !CDS_PN = "1";
"B":   PN = "2"  !CDS_PN = "2";
BODY = "RES","I355": #LOCATION = "R8E3" !CDS_LOCATION = "R8E3" #SEC = "1" !CDS_SEC = "1";
"A":   PN = "1"  !CDS_PN = "1";
"B":   PN = "2"  !CDS_PN = "2";
BODY = "RES","I356": #LOCATION = "R7D44" !CDS_LOCATION = "R7D44" #SEC = "1" !CDS_SEC = "1";
"A":   PN = "1"  !CDS_PN = "1";
"B":   PN = "2"  !CDS_PN = "2";
BODY = "RES","I357": #LOCATION = "R3P53" !CDS_LOCATION = "R3P53" #SEC = "1" !CDS_SEC = "1";
"A":   PN = "1"  !CDS_PN = "1";
"B":   PN = "2"  !CDS_PN = "2";
BODY = "RES","I360": #LOCATION = "R2P22" !CDS_LOCATION = "R2P22" #SEC = "1" !CDS_SEC = "1";
"A":   PN = "1"  !CDS_PN = "1";
"B":   PN = "2"  !CDS_PN = "2";
BODY = "RES","I362": #LOCATION = "R8D44" !CDS_LOCATION = "R8D44" #SEC = "1" !CDS_SEC = "1";
"A":   PN = "1"  !CDS_PN = "1";
"B":   PN = "2"  !CDS_PN = "2";
DRAWING = "@baseboard_fab2_lib.baseboard_fab2(sch_1):page134";
BODY = "RES","I3": #LOCATION = "R2P17" !CDS_LOCATION = "R2P17" #SEC = "1" !CDS_SEC = "1";
"A":   PN = "1"  !CDS_PN = "1";
"B":   PN = "2"  !CDS_PN = "2";
BODY = "FET_N","I4": #LOCATION = "Q8D2" !CDS_LOCATION = "Q8D2" #SEC = "1" !CDS_SEC = "1";
"DRN":   PN = "3"  !CDS_PN = "3";
"GATE":   PN = "1"  !CDS_PN = "1";
"SRC":   PN = "2"  !CDS_PN = "2";
BODY = "RES","I9": #LOCATION = "R7C21" !CDS_LOCATION = "R7C21" #SEC = "1" !CDS_SEC = "1";
"A":   PN = "1"  !CDS_PN = "1";
"B":   PN = "2"  !CDS_PN = "2";
BODY = "FET_N","I10": #LOCATION = "Q7D1" !CDS_LOCATION = "Q7D1" #SEC = "1" !CDS_SEC = "1";
"DRN":   PN = "3"  !CDS_PN = "3";
"GATE":   PN = "1"  !CDS_PN = "1";
"SRC":   PN = "2"  !CDS_PN = "2";
BODY = "RES","I11": #LOCATION = "R7D18" !CDS_LOCATION = "R7D18" #SEC = "1" !CDS_SEC = "1";
"A":   PN = "1"  !CDS_PN = "1";
"B":   PN = "2"  !CDS_PN = "2";
DRAWING = "@baseboard_fab2_lib.baseboard_fab2(sch_1):page135";
BODY = "RES","I107": #LOCATION = "R2P19" !CDS_LOCATION = "R2P19" #SEC = "1" !CDS_SEC = "1";
"A":   PN = "1"  !CDS_PN = "1";
"B":   PN = "2"  !CDS_PN = "2";
BODY = "RES","I112": #LOCATION = "R2N23" !CDS_LOCATION = "R2N23" &SEC = "1" #&CDS_SEC = "1";
"A":   PN = "1"  !CDS_PN = "1";
"B":   PN = "2"  !CDS_PN = "2";
BODY = "RES","I113": #LOCATION = "R2N24" !CDS_LOCATION = "R2N24" #SEC = "1" !CDS_SEC = "1";
"A":   PN = "1"  !CDS_PN = "1";
"B":   PN = "2"  !CDS_PN = "2";
BODY = "RES","I117": #LOCATION = "R9A12" !CDS_LOCATION = "R9A12" &SEC = "1" #&CDS_SEC = "1";
"A":   PN = "1"  !CDS_PN = "1";
"B":   PN = "2"  !CDS_PN = "2";
BODY = "RES","I118": #LOCATION = "R9A13" !CDS_LOCATION = "R9A13" &SEC = "1" #&CDS_SEC = "1";
"A":   PN = "1"  !CDS_PN = "1";
"B":   PN = "2"  !CDS_PN = "2";
BODY = "RES","I120": #LOCATION = "R8D21" !CDS_LOCATION = "R8D21" #SEC = "1" !CDS_SEC = "1";
"A":   PN = "1"  !CDS_PN = "1";
"B":   PN = "2"  !CDS_PN = "2";
BODY = "RES","I121": #LOCATION = "R7D30" !CDS_LOCATION = "R7D30" #SEC = "1" !CDS_SEC = "1";
"A":   PN = "1"  !CDS_PN = "1";
"B":   PN = "2"  !CDS_PN = "2";
BODY = "CONN12_C73564003","I124": #LOCATION = "J8G2" !CDS_LOCATION = "J8G2" #SEC = "1" !CDS_SEC = "1";
"IO1":   PN = "1"  !CDS_PN = "1";
"IO2":   PN = "2"  !CDS_PN = "2";
"IO3":   PN = "3"  !CDS_PN = "3";
"IO4":   PN = "4"  !CDS_PN = "4";
"IO5":   PN = "5"  !CDS_PN = "5";
"IO6":   PN = "6"  !CDS_PN = "6";
"IO7":   PN = "7"  !CDS_PN = "7";
"IO8":   PN = "8"  !CDS_PN = "8";
"IO9":   PN = "9"  !CDS_PN = "9";
"IO10":   PN = "10"  !CDS_PN = "10";
"IO11":   PN = "11"  !CDS_PN = "11";
"IO12":   PN = "12"  !CDS_PN = "12";
BODY = "RES","I129": #LOCATION = "R9A16" !CDS_LOCATION = "R9A16" &SEC = "1" #&CDS_SEC = "1";
"A":   PN = "1"  !CDS_PN = "1";
"B":   PN = "2"  !CDS_PN = "2";
BODY = "CONN4_D42317002","I131": #LOCATION = "J9A1" !CDS_LOCATION = "J9A1" &SEC = "1" #&CDS_SEC = "1";
"IO1":   PN = "1"  !CDS_PN = "1";
"IO2":   PN = "2"  !CDS_PN = "2";
"IO3":   PN = "3"  !CDS_PN = "3";
"IO4":   PN = "4"  !CDS_PN = "4";
DRAWING = "@baseboard_fab2_lib.baseboard_fab2(sch_1):page136";
BODY = "RES","I101": #LOCATION = "R7G26" !CDS_LOCATION = "R7G26" #SEC = "1" !CDS_SEC = "1";
"A":   PN = "1"  !CDS_PN = "1";
"B":   PN = "2"  !CDS_PN = "2";
BODY = "RES","I102": #LOCATION = "R7G28" !CDS_LOCATION = "R7G28" #SEC = "1" !CDS_SEC = "1";
"A":   PN = "1"  !CDS_PN = "1";
"B":   PN = "2"  !CDS_PN = "2";
BODY = "RES","I126": #LOCATION = "R8E20" !CDS_LOCATION = "R8E20" #SEC = "1" !CDS_SEC = "1";
"A":   PN = "1"  !CDS_PN = "1";
"B":   PN = "2"  !CDS_PN = "2";
BODY = "CAP_A","I128": #LOCATION = "C8E8" !CDS_LOCATION = "C8E8" #SEC = "1" !CDS_SEC = "1";
"A":   PN = "1"  !CDS_PN = "1";
"B":   PN = "2"  !CDS_PN = "2";
BODY = "TTL1G126_A","I130": #LOCATION = "U8E3" !CDS_LOCATION = "U8E3" #SEC = "1" !CDS_SEC = "1";
"A":   PN = "2"  !CDS_PN = "2";
"OE":   PN = "1"  !CDS_PN = "1";
"Y":   PN = "4"  !CDS_PN = "4";
BODY = "RES","I133": #LOCATION = "R8E14" !CDS_LOCATION = "R8E14" #SEC = "1" !CDS_SEC = "1";
"A":   PN = "1"  !CDS_PN = "1";
"B":   PN = "2"  !CDS_PN = "2";
BODY = "FET_N","I134": #LOCATION = "Q8E1" !CDS_LOCATION = "Q8E1" #SEC = "1" !CDS_SEC = "1";
"DRN":   PN = "3"  !CDS_PN = "3";
"GATE":   PN = "1"  !CDS_PN = "1";
"SRC":   PN = "2"  !CDS_PN = "2";
BODY = "RES","I139": #LOCATION = "R7G31" !CDS_LOCATION = "R7G31" #SEC = "1" !CDS_SEC = "1";
"A":   PN = "1"  !CDS_PN = "1";
"B":   PN = "2"  !CDS_PN = "2";
BODY = "RES","I140": #LOCATION = "R8E16" !CDS_LOCATION = "R8E16" #SEC = "1" !CDS_SEC = "1";
"A":   PN = "1"  !CDS_PN = "1";
"B":   PN = "2"  !CDS_PN = "2";
BODY = "RES","I147": #LOCATION = "R2N28" !CDS_LOCATION = "R2N28" #SEC = "1" !CDS_SEC = "1";
"A":   PN = "1"  !CDS_PN = "1";
"B":   PN = "2"  !CDS_PN = "2";
BODY = "RES","I148": #LOCATION = "R7G29" !CDS_LOCATION = "R7G29" #SEC = "1" !CDS_SEC = "1";
"A":   PN = "1"  !CDS_PN = "1";
"B":   PN = "2"  !CDS_PN = "2";
BODY = "RES","I155": #LOCATION = "R7G27" !CDS_LOCATION = "R7G27" #SEC = "1" !CDS_SEC = "1";
"A":   PN = "1"  !CDS_PN = "1";
"B":   PN = "2"  !CDS_PN = "2";
BODY = "RES","I156": #LOCATION = "R3T14" !CDS_LOCATION = "R3T14" #SEC = "1" !CDS_SEC = "1";
"A":   PN = "1"  !CDS_PN = "1";
"B":   PN = "2"  !CDS_PN = "2";
BODY = "CONN12_C73564003","I174": #LOCATION = "J7G3" !CDS_LOCATION = "J7G3" #SEC = "1" !CDS_SEC = "1";
"IO1":   PN = "1"  !CDS_PN = "1";
"IO2":   PN = "2"  !CDS_PN = "2";
"IO3":   PN = "3"  !CDS_PN = "3";
"IO4":   PN = "4"  !CDS_PN = "4";
"IO5":   PN = "5"  !CDS_PN = "5";
"IO6":   PN = "6"  !CDS_PN = "6";
"IO7":   PN = "7"  !CDS_PN = "7";
"IO8":   PN = "8"  !CDS_PN = "8";
"IO9":   PN = "9"  !CDS_PN = "9";
"IO10":   PN = "10"  !CDS_PN = "10";
"IO11":   PN = "11"  !CDS_PN = "11";
"IO12":   PN = "12"  !CDS_PN = "12";
DRAWING = "@baseboard_fab2_lib.baseboard_fab2(sch_1):page137";
BODY = "RES","I11": #LOCATION = "R7C11" !CDS_LOCATION = "R7C11" &SEC = "1" #&CDS_SEC = "1";
"A":   PN = "1"  !CDS_PN = "1";
"B":   PN = "2"  !CDS_PN = "2";
BODY = "RES","I13": #LOCATION = "R7C10" !CDS_LOCATION = "R7C10" #SEC = "1" !CDS_SEC = "1";
"A":   PN = "1"  !CDS_PN = "1";
"B":   PN = "2"  !CDS_PN = "2";
BODY = "CAP_A","I14": #LOCATION = "C7C19" !CDS_LOCATION = "C7C19" #SEC = "1" !CDS_SEC = "1";
"A":   PN = "1"  !CDS_PN = "1";
"B":   PN = "2"  !CDS_PN = "2";
BODY = "RES","I15": #LOCATION = "R1U63" !CDS_LOCATION = "R1U63" #SEC = "1" !CDS_SEC = "1";
"A":   PN = "1"  !CDS_PN = "1";
"B":   PN = "2"  !CDS_PN = "2";
BODY = "RES","I19": #LOCATION = "R3N4" !CDS_LOCATION = "R3N4" &SEC = "1" #&CDS_SEC = "1";
"A":   PN = "1"  !CDS_PN = "1";
"B":   PN = "2"  !CDS_PN = "2";
BODY = "CAP_A","I20": #LOCATION = "C3N32" !CDS_LOCATION = "C3N32" #SEC = "1" !CDS_SEC = "1";
"A":   PN = "1"  !CDS_PN = "1";
"B":   PN = "2"  !CDS_PN = "2";
BODY = "RES","I67": #LOCATION = "R7C13" !CDS_LOCATION = "R7C13" #SEC = "1" !CDS_SEC = "1";
"A":   PN = "1"  !CDS_PN = "1";
"B":   PN = "2"  !CDS_PN = "2";
BODY = "RES","I69": #LOCATION = "R1U64" !CDS_LOCATION = "R1U64" #SEC = "1" !CDS_SEC = "1";
"A":   PN = "1"  !CDS_PN = "1";
"B":   PN = "2"  !CDS_PN = "2";
BODY = "CONN12_C73564003","I128": #LOCATION = "J9G1" !CDS_LOCATION = "J9G1" #SEC = "1" !CDS_SEC = "1";
"IO1":   PN = "1"  !CDS_PN = "1";
"IO2":   PN = "2"  !CDS_PN = "2";
"IO3":   PN = "3"  !CDS_PN = "3";
"IO4":   PN = "4"  !CDS_PN = "4";
"IO5":   PN = "5"  !CDS_PN = "5";
"IO6":   PN = "6"  !CDS_PN = "6";
"IO7":   PN = "7"  !CDS_PN = "7";
"IO8":   PN = "8"  !CDS_PN = "8";
"IO9":   PN = "9"  !CDS_PN = "9";
"IO10":   PN = "10"  !CDS_PN = "10";
"IO11":   PN = "11"  !CDS_PN = "11";
"IO12":   PN = "12"  !CDS_PN = "12";
DRAWING = "@baseboard_fab2_lib.baseboard_fab2(sch_1):page138";
BODY = "RES","I83": #LOCATION = "R2T53" !CDS_LOCATION = "R2T53" #SEC = "1" !CDS_SEC = "1";
"A":   PN = "1"  !CDS_PN = "1";
"B":   PN = "2"  !CDS_PN = "2";
BODY = "RES","I84": #LOCATION = "R2T54" !CDS_LOCATION = "R2T54" #SEC = "1" !CDS_SEC = "1";
"A":   PN = "1"  !CDS_PN = "1";
"B":   PN = "2"  !CDS_PN = "2";
BODY = "RES","I87": #LOCATION = "R8D17" !CDS_LOCATION = "R8D17" &SEC = "1" #&CDS_SEC = "1";
"A":   PN = "1"  !CDS_PN = "1";
"B":   PN = "2"  !CDS_PN = "2";
BODY = "RES","I88": #LOCATION = "R8D15" !CDS_LOCATION = "R8D15" &SEC = "1" #&CDS_SEC = "1";
"A":   PN = "1"  !CDS_PN = "1";
"B":   PN = "2"  !CDS_PN = "2";
BODY = "RES","I89": #LOCATION = "R2N8" !CDS_LOCATION = "R2N8" #SEC = "1" !CDS_SEC = "1";
"A":   PN = "1"  !CDS_PN = "1";
"B":   PN = "2"  !CDS_PN = "2";
BODY = "RES","I90": #LOCATION = "R2N5" !CDS_LOCATION = "R2N5" #SEC = "1" !CDS_SEC = "1";
"A":   PN = "1"  !CDS_PN = "1";
"B":   PN = "2"  !CDS_PN = "2";
BODY = "RES","I91": #LOCATION = "R8C16" !CDS_LOCATION = "R8C16" &SEC = "1" #&CDS_SEC = "1";
"A":   PN = "1"  !CDS_PN = "1";
"B":   PN = "2"  !CDS_PN = "2";
BODY = "RES","I92": #LOCATION = "R8C15" !CDS_LOCATION = "R8C15" &SEC = "1" #&CDS_SEC = "1";
"A":   PN = "1"  !CDS_PN = "1";
"B":   PN = "2"  !CDS_PN = "2";
BODY = "RES","I95": #LOCATION = "R8B24" !CDS_LOCATION = "R8B24" #SEC = "1" !CDS_SEC = "1";
"A":   PN = "1"  !CDS_PN = "1";
"B":   PN = "2"  !CDS_PN = "2";
BODY = "RES","I96": #LOCATION = "R8B26" !CDS_LOCATION = "R8B26" #SEC = "1" !CDS_SEC = "1";
"A":   PN = "1"  !CDS_PN = "1";
"B":   PN = "2"  !CDS_PN = "2";
BODY = "RES","I97": #LOCATION = "R2U11" !CDS_LOCATION = "R2U11" #SEC = "1" !CDS_SEC = "1";
"A":   PN = "1"  !CDS_PN = "1";
"B":   PN = "2"  !CDS_PN = "2";
BODY = "RES","I98": #LOCATION = "R2U3" !CDS_LOCATION = "R2U3" #SEC = "1" !CDS_SEC = "1";
"A":   PN = "1"  !CDS_PN = "1";
"B":   PN = "2"  !CDS_PN = "2";
BODY = "RES","I116": #LOCATION = "R2T55" !CDS_LOCATION = "R2T55" #SEC = "1" !CDS_SEC = "1";
"A":   PN = "1"  !CDS_PN = "1";
"B":   PN = "2"  !CDS_PN = "2";
BODY = "RES","I158": #LOCATION = "R2U8" !CDS_LOCATION = "R2U8" &SEC = "1" #&CDS_SEC = "1";
"A":   PN = "1"  !CDS_PN = "1";
"B":   PN = "2"  !CDS_PN = "2";
BODY = "RES","I159": #LOCATION = "R2U12" !CDS_LOCATION = "R2U12" &SEC = "1" #&CDS_SEC = "1";
"A":   PN = "1"  !CDS_PN = "1";
"B":   PN = "2"  !CDS_PN = "2";
BODY = "RES","I160": #LOCATION = "R2T56" !CDS_LOCATION = "R2T56" #SEC = "1" !CDS_SEC = "1";
"A":   PN = "1"  !CDS_PN = "1";
"B":   PN = "2"  !CDS_PN = "2";
BODY = "RES","I161": #LOCATION = "R8D3" !CDS_LOCATION = "R8D3" #SEC = "1" !CDS_SEC = "1";
"A":   PN = "1"  !CDS_PN = "1";
"B":   PN = "2"  !CDS_PN = "2";
BODY = "RES","I162": #LOCATION = "R8D6" !CDS_LOCATION = "R8D6" #SEC = "1" !CDS_SEC = "1";
"A":   PN = "1"  !CDS_PN = "1";
"B":   PN = "2"  !CDS_PN = "2";
BODY = "RES","I163": #LOCATION = "R8D7" !CDS_LOCATION = "R8D7" #SEC = "1" !CDS_SEC = "1";
"A":   PN = "1"  !CDS_PN = "1";
"B":   PN = "2"  !CDS_PN = "2";
BODY = "RES","I164": #LOCATION = "R8D4" !CDS_LOCATION = "R8D4" #SEC = "1" !CDS_SEC = "1";
"A":   PN = "1"  !CDS_PN = "1";
"B":   PN = "2"  !CDS_PN = "2";
BODY = "RES","I165": #LOCATION = "R2U9" !CDS_LOCATION = "R2U9" #SEC = "1" !CDS_SEC = "1";
"A":   PN = "1"  !CDS_PN = "1";
"B":   PN = "2"  !CDS_PN = "2";
BODY = "RES","I166": #LOCATION = "R2U6" !CDS_LOCATION = "R2U6" #SEC = "1" !CDS_SEC = "1";
"A":   PN = "1"  !CDS_PN = "1";
"B":   PN = "2"  !CDS_PN = "2";
BODY = "RES","I167": #LOCATION = "R8C20" !CDS_LOCATION = "R8C20" #SEC = "1" !CDS_SEC = "1";
"A":   PN = "1"  !CDS_PN = "1";
"B":   PN = "2"  !CDS_PN = "2";
BODY = "RES","I168": #LOCATION = "R8C14" !CDS_LOCATION = "R8C14" #SEC = "1" !CDS_SEC = "1";
"A":   PN = "1"  !CDS_PN = "1";
"B":   PN = "2"  !CDS_PN = "2";
BODY = "RES","I169": #LOCATION = "R8C11" !CDS_LOCATION = "R8C11" #SEC = "1" !CDS_SEC = "1";
"A":   PN = "1"  !CDS_PN = "1";
"B":   PN = "2"  !CDS_PN = "2";
BODY = "RES","I170": #LOCATION = "R8C12" !CDS_LOCATION = "R8C12" #SEC = "1" !CDS_SEC = "1";
"A":   PN = "1"  !CDS_PN = "1";
"B":   PN = "2"  !CDS_PN = "2";
BODY = "RES","I171": #LOCATION = "R2N20" !CDS_LOCATION = "R2N20" #SEC = "1" !CDS_SEC = "1";
"A":   PN = "1"  !CDS_PN = "1";
"B":   PN = "2"  !CDS_PN = "2";
BODY = "RES","I173": #LOCATION = "R8B27" !CDS_LOCATION = "R8B27" #SEC = "1" !CDS_SEC = "1";
"A":   PN = "1"  !CDS_PN = "1";
"B":   PN = "2"  !CDS_PN = "2";
BODY = "RES","I174": #LOCATION = "R8B28" !CDS_LOCATION = "R8B28" #SEC = "1" !CDS_SEC = "1";
"A":   PN = "1"  !CDS_PN = "1";
"B":   PN = "2"  !CDS_PN = "2";
BODY = "RES","I175": #LOCATION = "R2N21" !CDS_LOCATION = "R2N21" #SEC = "1" !CDS_SEC = "1";
"A":   PN = "1"  !CDS_PN = "1";
"B":   PN = "2"  !CDS_PN = "2";
DRAWING = "@baseboard_fab2_lib.baseboard_fab2(sch_1):page139";
BODY = "SPRINGVILLE","I72": #LOCATION = "EU9E1" !CDS_LOCATION = "EU9E1" #SEC = "1" !CDS_SEC = "1";
"CBOT":   PN = "37"  !CDS_PN = "37";
"CTOP":   PN = "40"  !CDS_PN = "40";
"DEV_OFF_N":   PN = "28"  !CDS_PN = "28";
"GND":   PN = "65"  !CDS_PN = "65";
"JTAG_CLK":   PN = "19"  !CDS_PN = "19";
"JTAG_TDI":   PN = "29"  !CDS_PN = "29";
"JTAG_TDO":   PN = "4"  !CDS_PN = "4";
"JTAG_TMS":   PN = "18"  !CDS_PN = "18";
"LAN_PWR_GOOD":   PN = "1"  !CDS_PN = "1";
"LED0":   PN = "31"  !CDS_PN = "31";
"LED1":   PN = "30"  !CDS_PN = "30";
"LED2":   PN = "33"  !CDS_PN = "33";
"MDI_MINUS0_SFP_I2C_DATA":   PN = "57"  !CDS_PN = "57";
"MDI_MINUS1_SRDS_SIG_DET":   PN = "54"  !CDS_PN = "54";
"MDI_MINUS2_SETN":   PN = "52"  !CDS_PN = "52";
"MDI_MINUS3_SERN":   PN = "49"  !CDS_PN = "49";
"MDI_PLUS0_NC":   PN = "58"  !CDS_PN = "58";
"MDI_PLUS1_SFP_I2C_CLK":   PN = "55"  !CDS_PN = "55";
"MDI_PLUS2_SETP":   PN = "53"  !CDS_PN = "53";
"MDI_PLUS3_SERP":   PN = "50"  !CDS_PN = "50";
"NC":   PN = "22"  !CDS_PN = "22";
"NC_SI_ARB_IN":   PN = "43"  !CDS_PN = "43";
"NC_SI_ARB_OUT":   PN = "44"  !CDS_PN = "44";
"NC_SI_CLK_IN":   PN = "2"  !CDS_PN = "2";
"NC_SI_CRS_DV":   PN = "3"  !CDS_PN = "3";
"NC_SI_RXD0":   PN = "6"  !CDS_PN = "6";
"NC_SI_RXD1":   PN = "5"  !CDS_PN = "5";
"NC_SI_TX_EN":   PN = "7"  !CDS_PN = "7";
"NC_SI_TXD0":   PN = "9"  !CDS_PN = "9";
"NC_SI_TXD1":   PN = "8"  !CDS_PN = "8";
"NVM_CS_N":   PN = "15"  !CDS_PN = "15";
"NVM_SI":   PN = "12"  !CDS_PN = "12";
"NVM_SK":   PN = "13"  !CDS_PN = "13";
"NVM_SO":   PN = "14"  !CDS_PN = "14";
"PE_RN":   PN = "23"  !CDS_PN = "23";
"PE_RP":   PN = "24"  !CDS_PN = "24";
"PE_RST_N":   PN = "17"  !CDS_PN = "17";
"PE_TN":   PN = "20"  !CDS_PN = "20";
"PE_TP":   PN = "21"  !CDS_PN = "21";
"PE_WAKE_N":   PN = "16"  !CDS_PN = "16";
"PECLKN":   PN = "25"  !CDS_PN = "25";
"PECLKP":   PN = "26"  !CDS_PN = "26";
"RSET":   PN = "48"  !CDS_PN = "48";
"SDP0":   PN = "63"  !CDS_PN = "63";
"SDP1_PCIE_DIS_SDP1":   PN = "61"  !CDS_PN = "61";
"SDP2":   PN = "62"  !CDS_PN = "62";
"SDP3":   PN = "60"  !CDS_PN = "60";
"SMB_ALRT_N":   PN = "35"  !CDS_PN = "35";
"SMB_CLK":   PN = "34"  !CDS_PN = "34";
"SMB_DATA":   PN = "36"  !CDS_PN = "36";
"VDD0P9<0>":   PN = "59"  !CDS_PN = "59";
"VDD0P9<1>":   PN = "32"  !CDS_PN = "32";
"VDD0P9<2>":   PN = "11"  !CDS_PN = "11";
"VDD0P9<3>":   PN = "42"  !CDS_PN = "42";
"VDD0P9_OUT":   PN = "38"  !CDS_PN = "38";
"VDD1P5<0>":   PN = "56"  !CDS_PN = "56";
"VDD1P5<1>":   PN = "47"  !CDS_PN = "47";
"VDD1P5_OUT":   PN = "39"  !CDS_PN = "39";
"VDD3P3<0>":   PN = "64"  !CDS_PN = "64";
"VDD3P3<1>":   PN = "51"  !CDS_PN = "51";
"VDD3P3<2>":   PN = "41"  !CDS_PN = "41";
"VDD3P3<3>":   PN = "27"  !CDS_PN = "27";
"VDD3P3<4>":   PN = "10"  !CDS_PN = "10";
"XTAL1":   PN = "46"  !CDS_PN = "46";
"XTAL2":   PN = "45"  !CDS_PN = "45";
BODY = "CAP","I76": #LOCATION = "C9E7" !CDS_LOCATION = "C9E7" #SEC = "1" !CDS_SEC = "1";
"A":   PN = "1"  !CDS_PN = "1";
"B":   PN = "2"  !CDS_PN = "2";
BODY = "CAP_A","I87": #LOCATION = "C9E5" !CDS_LOCATION = "C9E5" #SEC = "1" !CDS_SEC = "1";
"A":   PN = "1"  !CDS_PN = "1";
"B":   PN = "2"  !CDS_PN = "2";
BODY = "CAP_A","I88": #LOCATION = "C9E4" !CDS_LOCATION = "C9E4" #SEC = "1" !CDS_SEC = "1";
"A":   PN = "1"  !CDS_PN = "1";
"B":   PN = "2"  !CDS_PN = "2";
BODY = "CAP_A","I89": #LOCATION = "C2M23" !CDS_LOCATION = "C2M23" #SEC = "1" !CDS_SEC = "1";
"A":   PN = "1"  !CDS_PN = "1";
"B":   PN = "2"  !CDS_PN = "2";
BODY = "CAP_A","I90": #LOCATION = "C2M24" !CDS_LOCATION = "C2M24" #SEC = "1" !CDS_SEC = "1";
"A":   PN = "1"  !CDS_PN = "1";
"B":   PN = "2"  !CDS_PN = "2";
BODY = "CRYSTAL","I109": #LOCATION = "Y9E1" !CDS_LOCATION = "Y9E1" #SEC = "1" !CDS_SEC = "1";
"A":   PN = "1"  !CDS_PN = "1";
"B":   PN = "3"  !CDS_PN = "3";
BODY = "RES","I110": #LOCATION = "R9E20" !CDS_LOCATION = "R9E20" #SEC = "1" !CDS_SEC = "1";
"A":   PN = "1"  !CDS_PN = "1";
"B":   PN = "2"  !CDS_PN = "2";
BODY = "CAP","I111": #LOCATION = "C9E8" !CDS_LOCATION = "C9E8" #SEC = "1" !CDS_SEC = "1";
"A":   PN = "1"  !CDS_PN = "1";
"B":   PN = "2"  !CDS_PN = "2";
BODY = "CAP","I112": #LOCATION = "C9E9" !CDS_LOCATION = "C9E9" #SEC = "1" !CDS_SEC = "1";
"A":   PN = "1"  !CDS_PN = "1";
"B":   PN = "2"  !CDS_PN = "2";
BODY = "RES","I128": #LOCATION = "R9E9" !CDS_LOCATION = "R9E9" #SEC = "1" !CDS_SEC = "1";
"A":   PN = "1"  !CDS_PN = "1";
"B":   PN = "2"  !CDS_PN = "2";
BODY = "RES","I129": #LOCATION = "R9E5" !CDS_LOCATION = "R9E5" #SEC = "1" !CDS_SEC = "1";
"A":   PN = "1"  !CDS_PN = "1";
"B":   PN = "2"  !CDS_PN = "2";
BODY = "RES","I130": #LOCATION = "R9E8" !CDS_LOCATION = "R9E8" #SEC = "1" !CDS_SEC = "1";
"A":   PN = "1"  !CDS_PN = "1";
"B":   PN = "2"  !CDS_PN = "2";
BODY = "CAP","I134": #LOCATION = "C1T4" !CDS_LOCATION = "C1T4" #SEC = "1" !CDS_SEC = "1";
"A":   PN = "1"  !CDS_PN = "1";
"B":   PN = "2"  !CDS_PN = "2";
BODY = "CAP","I135": #LOCATION = "C1R30" !CDS_LOCATION = "C1R30" #SEC = "1" !CDS_SEC = "1";
"A":   PN = "1"  !CDS_PN = "1";
"B":   PN = "2"  !CDS_PN = "2";
BODY = "CAP","I136": #LOCATION = "C1R22" !CDS_LOCATION = "C1R22" #SEC = "1" !CDS_SEC = "1";
"A":   PN = "1"  !CDS_PN = "1";
"B":   PN = "2"  !CDS_PN = "2";
BODY = "CAP","I140": #LOCATION = "C9F2" !CDS_LOCATION = "C9F2" &SEC = "1" #&CDS_SEC = "1";
"A":   PN = "1"  !CDS_PN = "1";
"B":   PN = "2"  !CDS_PN = "2";
BODY = "CAP","I142": #LOCATION = "C1R13" !CDS_LOCATION = "C1R13" &SEC = "1" #&CDS_SEC = "1";
"A":   PN = "1"  !CDS_PN = "1";
"B":   PN = "2"  !CDS_PN = "2";
BODY = "CAP_A","I143": #LOCATION = "C1R20" !CDS_LOCATION = "C1R20" &SEC = "1" #&CDS_SEC = "1";
"A":   PN = "1"  !CDS_PN = "1";
"B":   PN = "2"  !CDS_PN = "2";
BODY = "CAP_A","I144": #LOCATION = "C1T3" !CDS_LOCATION = "C1T3" &SEC = "1" #&CDS_SEC = "1";
"A":   PN = "1"  !CDS_PN = "1";
"B":   PN = "2"  !CDS_PN = "2";
BODY = "CAP_A","I145": #LOCATION = "C1R14" !CDS_LOCATION = "C1R14" &SEC = "1" #&CDS_SEC = "1";
"A":   PN = "1"  !CDS_PN = "1";
"B":   PN = "2"  !CDS_PN = "2";
BODY = "CAP_A","I146": #LOCATION = "C1R21" !CDS_LOCATION = "C1R21" &SEC = "1" #&CDS_SEC = "1";
"A":   PN = "1"  !CDS_PN = "1";
"B":   PN = "2"  !CDS_PN = "2";
BODY = "CAP_A","I149": #LOCATION = "C1R26" !CDS_LOCATION = "C1R26" &SEC = "1" #&CDS_SEC = "1";
"A":   PN = "1"  !CDS_PN = "1";
"B":   PN = "2"  !CDS_PN = "2";
BODY = "CAP_A","I150": #LOCATION = "C1R29" !CDS_LOCATION = "C1R29" &SEC = "1" #&CDS_SEC = "1";
"A":   PN = "1"  !CDS_PN = "1";
"B":   PN = "2"  !CDS_PN = "2";
BODY = "CAP_A","I151": #LOCATION = "C1R19" !CDS_LOCATION = "C1R19" &SEC = "1" #&CDS_SEC = "1";
"A":   PN = "1"  !CDS_PN = "1";
"B":   PN = "2"  !CDS_PN = "2";
BODY = "CAP_A","I152": #LOCATION = "C1R31" !CDS_LOCATION = "C1R31" &SEC = "1" #&CDS_SEC = "1";
"A":   PN = "1"  !CDS_PN = "1";
"B":   PN = "2"  !CDS_PN = "2";
BODY = "CAP","I153": #LOCATION = "C1R17" !CDS_LOCATION = "C1R17" &SEC = "1" #&CDS_SEC = "1";
"A":   PN = "1"  !CDS_PN = "1";
"B":   PN = "2"  !CDS_PN = "2";
BODY = "CAP","I155": #LOCATION = "C9E6" !CDS_LOCATION = "C9E6" &SEC = "1" #&CDS_SEC = "1";
"A":   PN = "1"  !CDS_PN = "1";
"B":   PN = "2"  !CDS_PN = "2";
BODY = "CAP_A","I157": #LOCATION = "C1R18" !CDS_LOCATION = "C1R18" &SEC = "1" #&CDS_SEC = "1";
"A":   PN = "1"  !CDS_PN = "1";
"B":   PN = "2"  !CDS_PN = "2";
BODY = "CAP_A","I158": #LOCATION = "C1T5" !CDS_LOCATION = "C1T5" &SEC = "1" #&CDS_SEC = "1";
"A":   PN = "1"  !CDS_PN = "1";
"B":   PN = "2"  !CDS_PN = "2";
BODY = "CAP_A","I159": #LOCATION = "C1R24" !CDS_LOCATION = "C1R24" &SEC = "1" #&CDS_SEC = "1";
"A":   PN = "1"  !CDS_PN = "1";
"B":   PN = "2"  !CDS_PN = "2";
BODY = "CAP_A","I160": #LOCATION = "C1R15" !CDS_LOCATION = "C1R15" &SEC = "1" #&CDS_SEC = "1";
"A":   PN = "1"  !CDS_PN = "1";
"B":   PN = "2"  !CDS_PN = "2";
BODY = "CAP","I161": #LOCATION = "C1R16" !CDS_LOCATION = "C1R16" &SEC = "1" #&CDS_SEC = "1";
"A":   PN = "1"  !CDS_PN = "1";
"B":   PN = "2"  !CDS_PN = "2";
BODY = "CAP_A","I163": #LOCATION = "C9E1" !CDS_LOCATION = "C9E1" #SEC = "1" !CDS_SEC = "1";
"A":   PN = "1"  !CDS_PN = "1";
"B":   PN = "2"  !CDS_PN = "2";
BODY = "RES","I173": #LOCATION = "R9F5" !CDS_LOCATION = "R9F5" &SEC = "1" #&CDS_SEC = "1";
"A":   PN = "1"  !CDS_PN = "1";
"B":   PN = "2"  !CDS_PN = "2";
BODY = "RES","I174": #LOCATION = "R9E23" !CDS_LOCATION = "R9E23" #SEC = "1" !CDS_SEC = "1";
"A":   PN = "1"  !CDS_PN = "1";
"B":   PN = "2"  !CDS_PN = "2";
BODY = "RES","I177": #LOCATION = "R9E2" !CDS_LOCATION = "R9E2" #SEC = "1" !CDS_SEC = "1";
"A":   PN = "1"  !CDS_PN = "1";
"B":   PN = "2"  !CDS_PN = "2";
BODY = "RES","I178": #LOCATION = "R9E3" !CDS_LOCATION = "R9E3" #SEC = "1" !CDS_SEC = "1";
"A":   PN = "1"  !CDS_PN = "1";
"B":   PN = "2"  !CDS_PN = "2";
BODY = "RES","I179": #LOCATION = "R9E1" !CDS_LOCATION = "R9E1" #SEC = "1" !CDS_SEC = "1";
"A":   PN = "1"  !CDS_PN = "1";
"B":   PN = "2"  !CDS_PN = "2";
BODY = "RES","I181": #LOCATION = "R9E22" !CDS_LOCATION = "R9E22" #SEC = "1" !CDS_SEC = "1";
"A":   PN = "1"  !CDS_PN = "1";
"B":   PN = "2"  !CDS_PN = "2";
BODY = "RES","I193": #LOCATION = "R9E7" !CDS_LOCATION = "R9E7" &SEC = "1" #&CDS_SEC = "1";
"A":   PN = "1"  !CDS_PN = "1";
"B":   PN = "2"  !CDS_PN = "2";
BODY = "RES","I195": #LOCATION = "R1R1" !CDS_LOCATION = "R1R1" #SEC = "1" !CDS_SEC = "1";
"A":   PN = "1"  !CDS_PN = "1";
"B":   PN = "2"  !CDS_PN = "2";
BODY = "RES","I200": #LOCATION = "R9E4" !CDS_LOCATION = "R9E4" #SEC = "1" !CDS_SEC = "1";
"A":   PN = "1"  !CDS_PN = "1";
"B":   PN = "2"  !CDS_PN = "2";
BODY = "RES","I201": #LOCATION = "R9E18" !CDS_LOCATION = "R9E18" #SEC = "1" !CDS_SEC = "1";
"A":   PN = "1"  !CDS_PN = "1";
"B":   PN = "2"  !CDS_PN = "2";
BODY = "RES","I212": #LOCATION = "R9E13" !CDS_LOCATION = "R9E13" &SEC = "1" #&CDS_SEC = "1";
"A":   PN = "1"  !CDS_PN = "1";
"B":   PN = "2"  !CDS_PN = "2";
BODY = "RES","I213": #LOCATION = "R1R12" !CDS_LOCATION = "R1R12" &SEC = "1" #&CDS_SEC = "1";
"A":   PN = "1"  !CDS_PN = "1";
"B":   PN = "2"  !CDS_PN = "2";
BODY = "RES","I214": #LOCATION = "R1T1" !CDS_LOCATION = "R1T1" &SEC = "1" #&CDS_SEC = "1";
"A":   PN = "1"  !CDS_PN = "1";
"B":   PN = "2"  !CDS_PN = "2";
BODY = "RES","I225": #LOCATION = "R9F1" !CDS_LOCATION = "R9F1" &SEC = "1" #&CDS_SEC = "1";
"A":   PN = "1"  !CDS_PN = "1";
"B":   PN = "2"  !CDS_PN = "2";
BODY = "RES","I228": #LOCATION = "R9E19" !CDS_LOCATION = "R9E19" #SEC = "1" !CDS_SEC = "1";
"A":   PN = "1"  !CDS_PN = "1";
"B":   PN = "2"  !CDS_PN = "2";
BODY = "RES","I229": #LOCATION = "R9E17" !CDS_LOCATION = "R9E17" #SEC = "1" !CDS_SEC = "1";
"A":   PN = "1"  !CDS_PN = "1";
"B":   PN = "2"  !CDS_PN = "2";
BODY = "RES","I235": #LOCATION = "R9E16" !CDS_LOCATION = "R9E16" #SEC = "1" !CDS_SEC = "1";
"A":   PN = "1"  !CDS_PN = "1";
"B":   PN = "2"  !CDS_PN = "2";
BODY = "RES","I237": #LOCATION = "R1R15" !CDS_LOCATION = "R1R15" #SEC = "1" !CDS_SEC = "1";
"A":   PN = "1"  !CDS_PN = "1";
"B":   PN = "2"  !CDS_PN = "2";
BODY = "RES","I238": #LOCATION = "R1T32" !CDS_LOCATION = "R1T32" #SEC = "1" !CDS_SEC = "1";
"A":   PN = "1"  !CDS_PN = "1";
"B":   PN = "2"  !CDS_PN = "2";
BODY = "RES","I239": #LOCATION = "R1T34" !CDS_LOCATION = "R1T34" #SEC = "1" !CDS_SEC = "1";
"A":   PN = "1"  !CDS_PN = "1";
"B":   PN = "2"  !CDS_PN = "2";
BODY = "RES","I240": #LOCATION = "R1T33" !CDS_LOCATION = "R1T33" #SEC = "1" !CDS_SEC = "1";
"A":   PN = "1"  !CDS_PN = "1";
"B":   PN = "2"  !CDS_PN = "2";
BODY = "CAP_A","I241": #LOCATION = "C9E12" !CDS_LOCATION = "C9E12" #SEC = "1" !CDS_SEC = "1";
"A":   PN = "1"  !CDS_PN = "1";
"B":   PN = "2"  !CDS_PN = "2";
DRAWING = "@baseboard_fab2_lib.baseboard_fab2(sch_1):page140";
BODY = "M25PE16","I1": #LOCATION = "U9E1" !CDS_LOCATION = "U9E1" #SEC = "1" !CDS_SEC = "1";
"C":   PN = "6"  !CDS_PN = "6";
"DQ0":   PN = "5"  !CDS_PN = "5";
"DQ1":   PN = "2"  !CDS_PN = "2";
"RESET_N":   PN = "7"  !CDS_PN = "7";
"S_N":   PN = "1"  !CDS_PN = "1";
"VCC":   PN = "8"  !CDS_PN = "8";
"VSS":   PN = "4"  !CDS_PN = "4";
"W_N":   PN = "3"  !CDS_PN = "3";
BODY = "CAP_A","I3": #LOCATION = "C1R25" !CDS_LOCATION = "C1R25" #SEC = "1" !CDS_SEC = "1";
"A":   PN = "1"  !CDS_PN = "1";
"B":   PN = "2"  !CDS_PN = "2";
BODY = "RES","I10": #LOCATION = "R1R9" !CDS_LOCATION = "R1R9" #SEC = "1" !CDS_SEC = "1";
"A":   PN = "1"  !CDS_PN = "1";
"B":   PN = "2"  !CDS_PN = "2";
BODY = "RES","I11": #LOCATION = "R1R3" !CDS_LOCATION = "R1R3" #SEC = "1" !CDS_SEC = "1";
"A":   PN = "1"  !CDS_PN = "1";
"B":   PN = "2"  !CDS_PN = "2";
BODY = "RES","I12": #LOCATION = "R1R7" !CDS_LOCATION = "R1R7" #SEC = "1" !CDS_SEC = "1";
"A":   PN = "1"  !CDS_PN = "1";
"B":   PN = "2"  !CDS_PN = "2";
BODY = "RES","I14": #LOCATION = "R1R6" !CDS_LOCATION = "R1R6" #SEC = "1" !CDS_SEC = "1";
"A":   PN = "1"  !CDS_PN = "1";
"B":   PN = "2"  !CDS_PN = "2";
BODY = "RES","I17": #LOCATION = "R9E6" !CDS_LOCATION = "R9E6" #SEC = "1" !CDS_SEC = "1";
"A":   PN = "1"  !CDS_PN = "1";
"B":   PN = "2"  !CDS_PN = "2";
DRAWING = "@baseboard_fab2_lib.baseboard_fab2(sch_1):page141";
BODY = "RES","I28": #LOCATION = "R9G3" !CDS_LOCATION = "R9G3" #SEC = "1" !CDS_SEC = "1";
"A":   PN = "1"  !CDS_PN = "1";
"B":   PN = "2"  !CDS_PN = "2";
BODY = "RES","I30": #LOCATION = "R9G2" !CDS_LOCATION = "R9G2" #SEC = "1" !CDS_SEC = "1";
"A":   PN = "1"  !CDS_PN = "1";
"B":   PN = "2"  !CDS_PN = "2";
BODY = "CAP_A","I33": #LOCATION = "C9G7" !CDS_LOCATION = "C9G7" #SEC = "1" !CDS_SEC = "1";
"A":   PN = "1"  !CDS_PN = "1";
"B":   PN = "2"  !CDS_PN = "2";
BODY = "CAP","I36": #LOCATION = "C9G2" !CDS_LOCATION = "C9G2" #SEC = "1" !CDS_SEC = "1";
"A":   PN = "1"  !CDS_PN = "1";
"B":   PN = "2"  !CDS_PN = "2";
BODY = "CAP_A","I46": #LOCATION = "C9G4" !CDS_LOCATION = "C9G4" #SEC = "1" !CDS_SEC = "1";
"A":   PN = "1"  !CDS_PN = "1";
"B":   PN = "2"  !CDS_PN = "2";
BODY = "CAP_A","I47": #LOCATION = "C9G6" !CDS_LOCATION = "C9G6" #SEC = "1" !CDS_SEC = "1";
"A":   PN = "1"  !CDS_PN = "1";
"B":   PN = "2"  !CDS_PN = "2";
BODY = "CAP","I48": #LOCATION = "C9G5" !CDS_LOCATION = "C9G5" #SEC = "1" !CDS_SEC = "1";
"A":   PN = "1"  !CDS_PN = "1";
"B":   PN = "2"  !CDS_PN = "2";
BODY = "RES","I54": #LOCATION = "R9G1" !CDS_LOCATION = "R9G1" #SEC = "1" !CDS_SEC = "1";
"A":   PN = "1"  !CDS_PN = "1";
"B":   PN = "2"  !CDS_PN = "2";
BODY = "RES","I56": #LOCATION = "R9G4" !CDS_LOCATION = "R9G4" #SEC = "1" !CDS_SEC = "1";
"A":   PN = "1"  !CDS_PN = "1";
"B":   PN = "2"  !CDS_PN = "2";
BODY = "CAP","I58": #LOCATION = "C9G1" !CDS_LOCATION = "C9G1" #SEC = "1" !CDS_SEC = "1";
"A":   PN = "1"  !CDS_PN = "1";
"B":   PN = "2"  !CDS_PN = "2";
BODY = "CAP","I59": #LOCATION = "C9G3" !CDS_LOCATION = "C9G3" #SEC = "1" !CDS_SEC = "1";
"A":   PN = "1"  !CDS_PN = "1";
"B":   PN = "2"  !CDS_PN = "2";
BODY = "CAP","I60": #LOCATION = "C9F22" !CDS_LOCATION = "C9F22" #SEC = "1" !CDS_SEC = "1";
"A":   PN = "1"  !CDS_PN = "1";
"B":   PN = "2"  !CDS_PN = "2";
BODY = "RES","I75": #LOCATION = "R9G9" !CDS_LOCATION = "R9G9" &SEC = "1" #&CDS_SEC = "1";
"A":   PN = "1"  !CDS_PN = "1";
"B":   PN = "2"  !CDS_PN = "2";
BODY = "RES","I76": #LOCATION = "R9G11" !CDS_LOCATION = "R9G11" &SEC = "1" #&CDS_SEC = "1";
"A":   PN = "1"  !CDS_PN = "1";
"B":   PN = "2"  !CDS_PN = "2";
BODY = "RES","I77": #LOCATION = "R9G18" !CDS_LOCATION = "R9G18" &SEC = "1" #&CDS_SEC = "1";
"A":   PN = "1"  !CDS_PN = "1";
"B":   PN = "2"  !CDS_PN = "2";
BODY = "RES","I78": #LOCATION = "R9G17" !CDS_LOCATION = "R9G17" &SEC = "1" #&CDS_SEC = "1";
"A":   PN = "1"  !CDS_PN = "1";
"B":   PN = "2"  !CDS_PN = "2";
BODY = "RES","I79": #LOCATION = "R9G19" !CDS_LOCATION = "R9G19" &SEC = "1" #&CDS_SEC = "1";
"A":   PN = "1"  !CDS_PN = "1";
"B":   PN = "2"  !CDS_PN = "2";
BODY = "RES","I80": #LOCATION = "R9G20" !CDS_LOCATION = "R9G20" &SEC = "1" #&CDS_SEC = "1";
"A":   PN = "1"  !CDS_PN = "1";
"B":   PN = "2"  !CDS_PN = "2";
BODY = "RES","I81": #LOCATION = "R9G24" !CDS_LOCATION = "R9G24" &SEC = "1" #&CDS_SEC = "1";
"A":   PN = "1"  !CDS_PN = "1";
"B":   PN = "2"  !CDS_PN = "2";
BODY = "RES","I82": #LOCATION = "R9G22" !CDS_LOCATION = "R9G22" &SEC = "1" #&CDS_SEC = "1";
"A":   PN = "1"  !CDS_PN = "1";
"B":   PN = "2"  !CDS_PN = "2";
BODY = "CAP","I99": #LOCATION = "C9G9" !CDS_LOCATION = "C9G9" &SEC = "1" #&CDS_SEC = "1";
"A":   PN = "1"  !CDS_PN = "1";
"B":   PN = "2"  !CDS_PN = "2";
BODY = "CAP","I100": #LOCATION = "C9G12" !CDS_LOCATION = "C9G12" &SEC = "1" #&CDS_SEC = "1";
"A":   PN = "1"  !CDS_PN = "1";
"B":   PN = "2"  !CDS_PN = "2";
BODY = "CAP","I101": #LOCATION = "C9G16" !CDS_LOCATION = "C9G16" &SEC = "1" #&CDS_SEC = "1";
"A":   PN = "1"  !CDS_PN = "1";
"B":   PN = "2"  !CDS_PN = "2";
BODY = "CAP","I102": #LOCATION = "C9G13" !CDS_LOCATION = "C9G13" &SEC = "1" #&CDS_SEC = "1";
"A":   PN = "1"  !CDS_PN = "1";
"B":   PN = "2"  !CDS_PN = "2";
BODY = "CONN17_H71061002","I109": #LOCATION = "JA9G1" !CDS_LOCATION = "JA9G1" &SEC = "1" #&CDS_SEC = "1";
"L1":   PN = "L1"  !CDS_PN = "L1";
"L2":   PN = "L2"  !CDS_PN = "L2";
"L3":   PN = "L3"  !CDS_PN = "L3";
"L4":   PN = "L4"  !CDS_PN = "L4";
"L5":   PN = "L5"  !CDS_PN = "L5";
"MH1":   PN = "MH1"  !CDS_PN = "MH1";
"MH2":   PN = "MH2"  !CDS_PN = "MH2";
"TRCT1":   PN = "R12"  !CDS_PN = "R12";
"TRCT2":   PN = "R6"  !CDS_PN = "R6";
"TRCT3":   PN = "R1"  !CDS_PN = "R1";
"TRCT4":   PN = "R7"  !CDS_PN = "R7";
"TRD1N":   PN = "R10"  !CDS_PN = "R10";
"TRD1P":   PN = "R11"  !CDS_PN = "R11";
"TRD2N":   PN = "R5"  !CDS_PN = "R5";
"TRD2P":   PN = "R4"  !CDS_PN = "R4";
"TRD3N":   PN = "R2"  !CDS_PN = "R2";
"TRD3P":   PN = "R3"  !CDS_PN = "R3";
"TRD4N":   PN = "R9"  !CDS_PN = "R9";
"TRD4P":   PN = "R8"  !CDS_PN = "R8";
BODY = "RES","I112": #LOCATION = "R1U51" !CDS_LOCATION = "R1U51" #SEC = "1" !CDS_SEC = "1";
"A":   PN = "1"  !CDS_PN = "1";
"B":   PN = "2"  !CDS_PN = "2";
BODY = "RES","I114": #LOCATION = "R1U3" !CDS_LOCATION = "R1U3" #SEC = "1" !CDS_SEC = "1";
"A":   PN = "1"  !CDS_PN = "1";
"B":   PN = "2"  !CDS_PN = "2";
DRAWING = "@baseboard_fab2_lib.baseboard_fab2(sch_1):page142";
BODY = "TTL1G126_A","I1": #LOCATION = "U8E4" !CDS_LOCATION = "U8E4" #SEC = "1" !CDS_SEC = "1";
"A":   PN = "2"  !CDS_PN = "2";
"OE":   PN = "1"  !CDS_PN = "1";
"Y":   PN = "4"  !CDS_PN = "4";
BODY = "RES","I2": #LOCATION = "R8E17" !CDS_LOCATION = "R8E17" #SEC = "1" !CDS_SEC = "1";
"A":   PN = "1"  !CDS_PN = "1";
"B":   PN = "2"  !CDS_PN = "2";
BODY = "RES","I3": #LOCATION = "R8E23" !CDS_LOCATION = "R8E23" #SEC = "1" !CDS_SEC = "1";
"A":   PN = "1"  !CDS_PN = "1";
"B":   PN = "2"  !CDS_PN = "2";
BODY = "RES","I18": #LOCATION = "R8E29" !CDS_LOCATION = "R8E29" #SEC = "1" !CDS_SEC = "1";
"A":   PN = "1"  !CDS_PN = "1";
"B":   PN = "2"  !CDS_PN = "2";
BODY = "CAP_A","I20": #LOCATION = "C8E5" !CDS_LOCATION = "C8E5" #SEC = "1" !CDS_SEC = "1";
"A":   PN = "1"  !CDS_PN = "1";
"B":   PN = "2"  !CDS_PN = "2";
BODY = "RES","I23": #LOCATION = "R8E30" !CDS_LOCATION = "R8E30" #SEC = "1" !CDS_SEC = "1";
"A":   PN = "1"  !CDS_PN = "1";
"B":   PN = "2"  !CDS_PN = "2";
BODY = "RES","I28": #LOCATION = "R8E36" !CDS_LOCATION = "R8E36" #SEC = "1" !CDS_SEC = "1";
"A":   PN = "1"  !CDS_PN = "1";
"B":   PN = "2"  !CDS_PN = "2";
BODY = "RES","I30": #LOCATION = "R8E26" !CDS_LOCATION = "R8E26" #SEC = "1" !CDS_SEC = "1";
"A":   PN = "1"  !CDS_PN = "1";
"B":   PN = "2"  !CDS_PN = "2";
BODY = "RES","I31": #LOCATION = "R8E28" !CDS_LOCATION = "R8E28" #SEC = "1" !CDS_SEC = "1";
"A":   PN = "1"  !CDS_PN = "1";
"B":   PN = "2"  !CDS_PN = "2";
BODY = "RES","I32": #LOCATION = "R8E27" !CDS_LOCATION = "R8E27" #SEC = "1" !CDS_SEC = "1";
"A":   PN = "1"  !CDS_PN = "1";
"B":   PN = "2"  !CDS_PN = "2";
BODY = "RES","I33": #LOCATION = "R8E21" !CDS_LOCATION = "R8E21" #SEC = "1" !CDS_SEC = "1";
"A":   PN = "1"  !CDS_PN = "1";
"B":   PN = "2"  !CDS_PN = "2";
DRAWING = "@baseboard_fab2_lib.baseboard_fab2(sch_1):page152";
BODY = "GTL2014","I1": #LOCATION = "U9G1" !CDS_LOCATION = "U9G1" #SEC = "1" !CDS_SEC = "1";
"A0":   PN = "13"  !CDS_PN = "13";
"A1":   PN = "12"  !CDS_PN = "12";
"A2":   PN = "10"  !CDS_PN = "10";
"A3":   PN = "9"  !CDS_PN = "9";
"B0":   PN = "2"  !CDS_PN = "2";
"B1":   PN = "3"  !CDS_PN = "3";
"B2":   PN = "5"  !CDS_PN = "5";
"B3":   PN = "6"  !CDS_PN = "6";
"DIR":   PN = "1"  !CDS_PN = "1";
"GND<0>":   PN = "7"  !CDS_PN = "7";
"GND<1>":   PN = "8"  !CDS_PN = "8";
"GND<2>":   PN = "11"  !CDS_PN = "11";
"VCC":   PN = "14"  !CDS_PN = "14";
"VREF":   PN = "4"  !CDS_PN = "4";
BODY = "RES","I2": #LOCATION = "R1U30" !CDS_LOCATION = "R1U30" #SEC = "1" !CDS_SEC = "1";
"A":   PN = "1"  !CDS_PN = "1";
"B":   PN = "2"  !CDS_PN = "2";
BODY = "RES","I6": #LOCATION = "R1U46" !CDS_LOCATION = "R1U46" #SEC = "1" !CDS_SEC = "1";
"A":   PN = "1"  !CDS_PN = "1";
"B":   PN = "2"  !CDS_PN = "2";
BODY = "RES","I14": #LOCATION = "R9G31" !CDS_LOCATION = "R9G31" #SEC = "1" !CDS_SEC = "1";
"A":   PN = "1"  !CDS_PN = "1";
"B":   PN = "2"  !CDS_PN = "2";
BODY = "RES","I15": #LOCATION = "R1U36" !CDS_LOCATION = "R1U36" #SEC = "1" !CDS_SEC = "1";
"A":   PN = "1"  !CDS_PN = "1";
"B":   PN = "2"  !CDS_PN = "2";
BODY = "RES","I16": #LOCATION = "R1U34" !CDS_LOCATION = "R1U34" #SEC = "1" !CDS_SEC = "1";
"A":   PN = "1"  !CDS_PN = "1";
"B":   PN = "2"  !CDS_PN = "2";
BODY = "CAP","I18": #LOCATION = "C1U19" !CDS_LOCATION = "C1U19" #SEC = "1" !CDS_SEC = "1";
"A":   PN = "1"  !CDS_PN = "1";
"B":   PN = "2"  !CDS_PN = "2";
BODY = "RES","I25": #LOCATION = "R1U43" !CDS_LOCATION = "R1U43" &SEC = "1" #&CDS_SEC = "1";
"A":   PN = "1"  !CDS_PN = "1";
"B":   PN = "2"  !CDS_PN = "2";
BODY = "RES","I26": #LOCATION = "R1U37" !CDS_LOCATION = "R1U37" &SEC = "1" #&CDS_SEC = "1";
"A":   PN = "1"  !CDS_PN = "1";
"B":   PN = "2"  !CDS_PN = "2";
BODY = "CAP_A","I27": #LOCATION = "C1U22" !CDS_LOCATION = "C1U22" &SEC = "1" #&CDS_SEC = "1";
"A":   PN = "1"  !CDS_PN = "1";
"B":   PN = "2"  !CDS_PN = "2";
BODY = "RES","I45": #LOCATION = "R9G34" !CDS_LOCATION = "R9G34" #SEC = "1" !CDS_SEC = "1";
"A":   PN = "1"  !CDS_PN = "1";
"B":   PN = "2"  !CDS_PN = "2";
BODY = "RES","I47": #LOCATION = "R9G27" !CDS_LOCATION = "R9G27" #SEC = "1" !CDS_SEC = "1";
"A":   PN = "1"  !CDS_PN = "1";
"B":   PN = "2"  !CDS_PN = "2";
BODY = "RES","I49": #LOCATION = "R1U58" !CDS_LOCATION = "R1U58" #SEC = "1" !CDS_SEC = "1";
"A":   PN = "1"  !CDS_PN = "1";
"B":   PN = "2"  !CDS_PN = "2";
BODY = "RES","I50": #LOCATION = "R1U56" !CDS_LOCATION = "R1U56" #SEC = "1" !CDS_SEC = "1";
"A":   PN = "1"  !CDS_PN = "1";
"B":   PN = "2"  !CDS_PN = "2";
BODY = "RES","I51": #LOCATION = "R2U51" !CDS_LOCATION = "R2U51" #SEC = "1" !CDS_SEC = "1";
"A":   PN = "1"  !CDS_PN = "1";
"B":   PN = "2"  !CDS_PN = "2";
BODY = "RES","I53": #LOCATION = "R2U40" !CDS_LOCATION = "R2U40" #SEC = "1" !CDS_SEC = "1";
"A":   PN = "1"  !CDS_PN = "1";
"B":   PN = "2"  !CDS_PN = "2";
BODY = "RES","I54": #LOCATION = "R2U41" !CDS_LOCATION = "R2U41" #SEC = "1" !CDS_SEC = "1";
"A":   PN = "1"  !CDS_PN = "1";
"B":   PN = "2"  !CDS_PN = "2";
BODY = "RES","I56": #LOCATION = "R1U41" !CDS_LOCATION = "R1U41" #SEC = "1" !CDS_SEC = "1";
"A":   PN = "1"  !CDS_PN = "1";
"B":   PN = "2"  !CDS_PN = "2";
BODY = "RES","I57": #LOCATION = "R1U35" !CDS_LOCATION = "R1U35" #SEC = "1" !CDS_SEC = "1";
"A":   PN = "1"  !CDS_PN = "1";
"B":   PN = "2"  !CDS_PN = "2";
BODY = "RES","I58": #LOCATION = "R4P17" !CDS_LOCATION = "R4P17" #SEC = "1" !CDS_SEC = "1";
"A":   PN = "1"  !CDS_PN = "1";
"B":   PN = "2"  !CDS_PN = "2";
BODY = "RES","I59": #LOCATION = "R4P20" !CDS_LOCATION = "R4P20" #SEC = "1" !CDS_SEC = "1";
"A":   PN = "1"  !CDS_PN = "1";
"B":   PN = "2"  !CDS_PN = "2";
BODY = "RES","I61": #LOCATION = "R7P5" !CDS_LOCATION = "R7P5" #SEC = "1" !CDS_SEC = "1";
"A":   PN = "1"  !CDS_PN = "1";
"B":   PN = "2"  !CDS_PN = "2";
BODY = "RES","I62": #LOCATION = "R7P21" !CDS_LOCATION = "R7P21" #SEC = "1" !CDS_SEC = "1";
"A":   PN = "1"  !CDS_PN = "1";
"B":   PN = "2"  !CDS_PN = "2";
BODY = "RES","I64": #LOCATION = "R1U53" !CDS_LOCATION = "R1U53" #SEC = "1" !CDS_SEC = "1";
"A":   PN = "1"  !CDS_PN = "1";
"B":   PN = "2"  !CDS_PN = "2";
BODY = "RES","I65": #LOCATION = "R1U60" !CDS_LOCATION = "R1U60" #SEC = "1" !CDS_SEC = "1";
"A":   PN = "1"  !CDS_PN = "1";
"B":   PN = "2"  !CDS_PN = "2";
BODY = "RES","I66": #LOCATION = "R2U49" !CDS_LOCATION = "R2U49" #SEC = "1" !CDS_SEC = "1";
"A":   PN = "1"  !CDS_PN = "1";
"B":   PN = "2"  !CDS_PN = "2";
BODY = "RES","I67": #LOCATION = "R1U55" !CDS_LOCATION = "R1U55" #SEC = "1" !CDS_SEC = "1";
"A":   PN = "1"  !CDS_PN = "1";
"B":   PN = "2"  !CDS_PN = "2";
BODY = "RES","I68": #LOCATION = "R1U62" !CDS_LOCATION = "R1U62" #SEC = "1" !CDS_SEC = "1";
"A":   PN = "1"  !CDS_PN = "1";
"B":   PN = "2"  !CDS_PN = "2";
BODY = "RES","I69": #LOCATION = "R1U57" !CDS_LOCATION = "R1U57" #SEC = "1" !CDS_SEC = "1";
"A":   PN = "1"  !CDS_PN = "1";
"B":   PN = "2"  !CDS_PN = "2";
BODY = "RES","I70": #LOCATION = "R1U61" !CDS_LOCATION = "R1U61" #SEC = "1" !CDS_SEC = "1";
"A":   PN = "1"  !CDS_PN = "1";
"B":   PN = "2"  !CDS_PN = "2";
BODY = "RES","I71": #LOCATION = "R9G28" !CDS_LOCATION = "R9G28" #SEC = "1" !CDS_SEC = "1";
"A":   PN = "1"  !CDS_PN = "1";
"B":   PN = "2"  !CDS_PN = "2";
BODY = "RES","I72": #LOCATION = "R9G32" !CDS_LOCATION = "R9G32" #SEC = "1" !CDS_SEC = "1";
"A":   PN = "1"  !CDS_PN = "1";
"B":   PN = "2"  !CDS_PN = "2";
BODY = "RES","I73": #LOCATION = "R9G33" !CDS_LOCATION = "R9G33" #SEC = "1" !CDS_SEC = "1";
"A":   PN = "1"  !CDS_PN = "1";
"B":   PN = "2"  !CDS_PN = "2";
BODY = "RES","I74": #LOCATION = "R1U59" !CDS_LOCATION = "R1U59" #SEC = "1" !CDS_SEC = "1";
"A":   PN = "1"  !CDS_PN = "1";
"B":   PN = "2"  !CDS_PN = "2";
BODY = "RES","I79": #LOCATION = "R2U47" !CDS_LOCATION = "R2U47" #SEC = "1" !CDS_SEC = "1";
"A":   PN = "1"  !CDS_PN = "1";
"B":   PN = "2"  !CDS_PN = "2";
BODY = "RES","I92": #LOCATION = "R9G29" !CDS_LOCATION = "R9G29" #SEC = "1" !CDS_SEC = "1";
"A":   PN = "1"  !CDS_PN = "1";
"B":   PN = "2"  !CDS_PN = "2";
BODY = "RES","I93": #LOCATION = "R1U54" !CDS_LOCATION = "R1U54" #SEC = "1" !CDS_SEC = "1";
"A":   PN = "1"  !CDS_PN = "1";
"B":   PN = "2"  !CDS_PN = "2";
BODY = "RES","I94": #LOCATION = "R2U46" !CDS_LOCATION = "R2U46" #SEC = "1" !CDS_SEC = "1";
"A":   PN = "1"  !CDS_PN = "1";
"B":   PN = "2"  !CDS_PN = "2";
BODY = "RES","I95": #LOCATION = "R3N30" !CDS_LOCATION = "R3N30" &SEC = "1" #&CDS_SEC = "1";
"A":   PN = "1"  !CDS_PN = "1";
"B":   PN = "2"  !CDS_PN = "2";
BODY = "RES","I98": #LOCATION = "R9G30" !CDS_LOCATION = "R9G30" &SEC = "1" #&CDS_SEC = "1";
"A":   PN = "1"  !CDS_PN = "1";
"B":   PN = "2"  !CDS_PN = "2";
BODY = "RES","I100": #LOCATION = "R3P63" !CDS_LOCATION = "R3P63" &SEC = "1" #&CDS_SEC = "1";
"A":   PN = "1"  !CDS_PN = "1";
"B":   PN = "2"  !CDS_PN = "2";
BODY = "RES","I102": #LOCATION = "R2U45" !CDS_LOCATION = "R2U45" &SEC = "1" #&CDS_SEC = "1";
"A":   PN = "1"  !CDS_PN = "1";
"B":   PN = "2"  !CDS_PN = "2";
DRAWING = "@baseboard_fab2_lib.baseboard_fab2(sch_1):page153";
BODY = "RES","I90": #LOCATION = "R7F6" !CDS_LOCATION = "R7F6" #SEC = "1" !CDS_SEC = "1";
"A":   PN = "1"  !CDS_PN = "1";
"B":   PN = "2"  !CDS_PN = "2";
BODY = "RES","I94": #LOCATION = "R7F5" !CDS_LOCATION = "R7F5" #SEC = "1" !CDS_SEC = "1";
"A":   PN = "1"  !CDS_PN = "1";
"B":   PN = "2"  !CDS_PN = "2";
BODY = "RES","I98": #LOCATION = "R7F4" !CDS_LOCATION = "R7F4" #SEC = "1" !CDS_SEC = "1";
"A":   PN = "1"  !CDS_PN = "1";
"B":   PN = "2"  !CDS_PN = "2";
BODY = "RES","I108": #LOCATION = "R7F37" !CDS_LOCATION = "R7F37" &SEC = "1" #&CDS_SEC = "1";
"A":   PN = "1"  !CDS_PN = "1";
"B":   PN = "2"  !CDS_PN = "2";
BODY = "RES","I109": #LOCATION = "R7F3" !CDS_LOCATION = "R7F3" &SEC = "1" #&CDS_SEC = "1";
"A":   PN = "1"  !CDS_PN = "1";
"B":   PN = "2"  !CDS_PN = "2";
BODY = "CAP_A","I130": #LOCATION = "C7F2" !CDS_LOCATION = "C7F2" #SEC = "1" !CDS_SEC = "1";
"A":   PN = "1"  !CDS_PN = "1";
"B":   PN = "2"  !CDS_PN = "2";
BODY = "CAP_A","I131": #LOCATION = "C7F1" !CDS_LOCATION = "C7F1" #SEC = "1" !CDS_SEC = "1";
"A":   PN = "1"  !CDS_PN = "1";
"B":   PN = "2"  !CDS_PN = "2";
BODY = "CAP_A","I136": #LOCATION = "C3T5" !CDS_LOCATION = "C3T5" #SEC = "1" !CDS_SEC = "1";
"A":   PN = "1"  !CDS_PN = "1";
"B":   PN = "2"  !CDS_PN = "2";
BODY = "CAP_A","I138": #LOCATION = "C3T4" !CDS_LOCATION = "C3T4" &SEC = "1" #&CDS_SEC = "1";
"A":   PN = "1"  !CDS_PN = "1";
"B":   PN = "2"  !CDS_PN = "2";
BODY = "RES","I140": #LOCATION = "R7F32" !CDS_LOCATION = "R7F32" #SEC = "1" !CDS_SEC = "1";
"A":   PN = "1"  !CDS_PN = "1";
"B":   PN = "2"  !CDS_PN = "2";
BODY = "W25Q256","I146": #LOCATION = "U7F1" !CDS_LOCATION = "U7F1" #SEC = "1" !CDS_SEC = "1";
"CLK":   PN = "16"  !CDS_PN = "16";
"CS_N":   PN = "7"  !CDS_PN = "7";
"DI_IO<0>":   PN = "15"  !CDS_PN = "15";
"DO_IO<1>":   PN = "8"  !CDS_PN = "8";
"GND":   PN = "10"  !CDS_PN = "10";
"HOLD_N_IO<3>":   PN = "1"  !CDS_PN = "1";
"NC<0>":   PN = "14"  !CDS_PN = "14";
"NC<1>":   PN = "13"  !CDS_PN = "13";
"NC<2>":   PN = "12"  !CDS_PN = "12";
"NC<3>":   PN = "11"  !CDS_PN = "11";
"NC<4>":   PN = "6"  !CDS_PN = "6";
"NC<5>":   PN = "5"  !CDS_PN = "5";
"NC<6>":   PN = "4"  !CDS_PN = "4";
"RESET_N":   PN = "3"  !CDS_PN = "3";
"VCC":   PN = "2"  !CDS_PN = "2";
"WP_N_IO<2>":   PN = "9"  !CDS_PN = "9";
BODY = "RES","I150": #LOCATION = "R3T3" !CDS_LOCATION = "R3T3" #SEC = "1" !CDS_SEC = "1";
"A":   PN = "1"  !CDS_PN = "1";
"B":   PN = "2"  !CDS_PN = "2";
BODY = "RES","I152": #LOCATION = "R3T5" !CDS_LOCATION = "R3T5" #SEC = "1" !CDS_SEC = "1";
"A":   PN = "1"  !CDS_PN = "1";
"B":   PN = "2"  !CDS_PN = "2";
BODY = "RES","I155": #LOCATION = "R3T2" !CDS_LOCATION = "R3T2" #SEC = "1" !CDS_SEC = "1";
"A":   PN = "1"  !CDS_PN = "1";
"B":   PN = "2"  !CDS_PN = "2";
BODY = "RES","I156": #LOCATION = "R3U1" !CDS_LOCATION = "R3U1" &SEC = "1" #&CDS_SEC = "1";
"A":   PN = "1"  !CDS_PN = "1";
"B":   PN = "2"  !CDS_PN = "2";
BODY = "RES","I157": #LOCATION = "R3T1" !CDS_LOCATION = "R3T1" &SEC = "1" #&CDS_SEC = "1";
"A":   PN = "1"  !CDS_PN = "1";
"B":   PN = "2"  !CDS_PN = "2";
BODY = "W25Q256","I165": #LOCATION = "U3T1" !CDS_LOCATION = "U3T1" #SEC = "1" !CDS_SEC = "1";
"CLK":   PN = "16"  !CDS_PN = "16";
"CS_N":   PN = "7"  !CDS_PN = "7";
"DI_IO<0>":   PN = "15"  !CDS_PN = "15";
"DO_IO<1>":   PN = "8"  !CDS_PN = "8";
"GND":   PN = "10"  !CDS_PN = "10";
"HOLD_N_IO<3>":   PN = "1"  !CDS_PN = "1";
"NC<0>":   PN = "14"  !CDS_PN = "14";
"NC<1>":   PN = "13"  !CDS_PN = "13";
"NC<2>":   PN = "12"  !CDS_PN = "12";
"NC<3>":   PN = "11"  !CDS_PN = "11";
"NC<4>":   PN = "6"  !CDS_PN = "6";
"NC<5>":   PN = "5"  !CDS_PN = "5";
"NC<6>":   PN = "4"  !CDS_PN = "4";
"RESET_N":   PN = "3"  !CDS_PN = "3";
"VCC":   PN = "2"  !CDS_PN = "2";
"WP_N_IO<2>":   PN = "9"  !CDS_PN = "9";
BODY = "RES","I166": #LOCATION = "R8F8" !CDS_LOCATION = "R8F8" &SEC = "1" #&CDS_SEC = "1";
"A":   PN = "1"  !CDS_PN = "1";
"B":   PN = "2"  !CDS_PN = "2";
BODY = "RES","I167": #LOCATION = "R8F7" !CDS_LOCATION = "R8F7" &SEC = "1" #&CDS_SEC = "1";
"A":   PN = "1"  !CDS_PN = "1";
"B":   PN = "2"  !CDS_PN = "2";
BODY = "RES","I168": #LOCATION = "R7F28" !CDS_LOCATION = "R7F28" #SEC = "1" !CDS_SEC = "1";
"A":   PN = "1"  !CDS_PN = "1";
"B":   PN = "2"  !CDS_PN = "2";
BODY = "RES","I170": #LOCATION = "R7F30" !CDS_LOCATION = "R7F30" #SEC = "1" !CDS_SEC = "1";
"A":   PN = "1"  !CDS_PN = "1";
"B":   PN = "2"  !CDS_PN = "2";
BODY = "RES","I174": #LOCATION = "R3T4" !CDS_LOCATION = "R3T4" #SEC = "1" !CDS_SEC = "1";
"A":   PN = "1"  !CDS_PN = "1";
"B":   PN = "2"  !CDS_PN = "2";
BODY = "RES","I178": #LOCATION = "R3T12" !CDS_LOCATION = "R3T12" #SEC = "1" !CDS_SEC = "1";
"A":   PN = "1"  !CDS_PN = "1";
"B":   PN = "2"  !CDS_PN = "2";
BODY = "RES","I179": #LOCATION = "R3T9" !CDS_LOCATION = "R3T9" #SEC = "1" !CDS_SEC = "1";
"A":   PN = "1"  !CDS_PN = "1";
"B":   PN = "2"  !CDS_PN = "2";
BODY = "RES","I181": #LOCATION = "R7F29" !CDS_LOCATION = "R7F29" #SEC = "1" !CDS_SEC = "1";
"A":   PN = "1"  !CDS_PN = "1";
"B":   PN = "2"  !CDS_PN = "2";
BODY = "RES","I184": #LOCATION = "R3T10" !CDS_LOCATION = "R3T10" #SEC = "1" !CDS_SEC = "1";
"A":   PN = "1"  !CDS_PN = "1";
"B":   PN = "2"  !CDS_PN = "2";
DRAWING = "@baseboard_fab2_lib.baseboard_fab2(sch_1):page154";
BODY = "CAP_A","I14": #LOCATION = "C8E18" !CDS_LOCATION = "C8E18" #SEC = "1" !CDS_SEC = "1";
"A":   PN = "1"  !CDS_PN = "1";
"B":   PN = "2"  !CDS_PN = "2";
BODY = "RES","I62": #LOCATION = "R2T9" !CDS_LOCATION = "R2T9" #SEC = "1" !CDS_SEC = "1";
"A":   PN = "1"  !CDS_PN = "1";
"B":   PN = "2"  !CDS_PN = "2";
BODY = "PI3B3257A","I74": #LOCATION = "U8F1" !CDS_LOCATION = "U8F1" #SEC = "1" !CDS_SEC = "1";
"EN":   PN = "15"  !CDS_PN = "15";
"GND":   PN = "8"  !CDS_PN = "8";
"IA0":   PN = "2"  !CDS_PN = "2";
"IA1":   PN = "3"  !CDS_PN = "3";
"IB0":   PN = "5"  !CDS_PN = "5";
"IB1":   PN = "6"  !CDS_PN = "6";
"IC0":   PN = "11"  !CDS_PN = "11";
"IC1":   PN = "10"  !CDS_PN = "10";
"ID0":   PN = "14"  !CDS_PN = "14";
"ID1":   PN = "13"  !CDS_PN = "13";
"S":   PN = "1"  !CDS_PN = "1";
"VCC":   PN = "16"  !CDS_PN = "16";
"YA":   PN = "4"  !CDS_PN = "4";
"YB":   PN = "7"  !CDS_PN = "7";
"YC":   PN = "9"  !CDS_PN = "9";
"YD":   PN = "12"  !CDS_PN = "12";
BODY = "PI3B3257A","I75": #LOCATION = "U2T1" !CDS_LOCATION = "U2T1" #SEC = "1" !CDS_SEC = "1";
"EN":   PN = "15"  !CDS_PN = "15";
"GND":   PN = "8"  !CDS_PN = "8";
"IA0":   PN = "2"  !CDS_PN = "2";
"IA1":   PN = "3"  !CDS_PN = "3";
"IB0":   PN = "5"  !CDS_PN = "5";
"IB1":   PN = "6"  !CDS_PN = "6";
"IC0":   PN = "11"  !CDS_PN = "11";
"IC1":   PN = "10"  !CDS_PN = "10";
"ID0":   PN = "14"  !CDS_PN = "14";
"ID1":   PN = "13"  !CDS_PN = "13";
"S":   PN = "1"  !CDS_PN = "1";
"VCC":   PN = "16"  !CDS_PN = "16";
"YA":   PN = "4"  !CDS_PN = "4";
"YB":   PN = "7"  !CDS_PN = "7";
"YC":   PN = "9"  !CDS_PN = "9";
"YD":   PN = "12"  !CDS_PN = "12";
BODY = "RES","I92": #LOCATION = "R2T2" !CDS_LOCATION = "R2T2" #SEC = "1" !CDS_SEC = "1";
"A":   PN = "1"  !CDS_PN = "1";
"B":   PN = "2"  !CDS_PN = "2";
BODY = "RES","I93": #LOCATION = "R2R12" !CDS_LOCATION = "R2R12" #SEC = "1" !CDS_SEC = "1";
"A":   PN = "1"  !CDS_PN = "1";
"B":   PN = "2"  !CDS_PN = "2";
BODY = "CAP_A","I94": #LOCATION = "C2T1" !CDS_LOCATION = "C2T1" #SEC = "1" !CDS_SEC = "1";
"A":   PN = "1"  !CDS_PN = "1";
"B":   PN = "2"  !CDS_PN = "2";
BODY = "TTL1G32_A","I99": #LOCATION = "U2T3" !CDS_LOCATION = "U2T3" #SEC = "1" !CDS_SEC = "1";
"A":   PN = "1"  !CDS_PN = "1";
"B":   PN = "2"  !CDS_PN = "2";
"Y":   PN = "4"  !CDS_PN = "4";
BODY = "TTL1G32_A","I100": #LOCATION = "U2T2" !CDS_LOCATION = "U2T2" #SEC = "1" !CDS_SEC = "1";
"A":   PN = "1"  !CDS_PN = "1";
"B":   PN = "2"  !CDS_PN = "2";
"Y":   PN = "4"  !CDS_PN = "4";
BODY = "RES","I101": #LOCATION = "R2T13" !CDS_LOCATION = "R2T13" #SEC = "1" !CDS_SEC = "1";
"A":   PN = "1"  !CDS_PN = "1";
"B":   PN = "2"  !CDS_PN = "2";
BODY = "RES","I105": #LOCATION = "R2T11" !CDS_LOCATION = "R2T11" #SEC = "1" !CDS_SEC = "1";
"A":   PN = "1"  !CDS_PN = "1";
"B":   PN = "2"  !CDS_PN = "2";
BODY = "RES","I106": #LOCATION = "R2T8" !CDS_LOCATION = "R2T8" #SEC = "1" !CDS_SEC = "1";
"A":   PN = "1"  !CDS_PN = "1";
"B":   PN = "2"  !CDS_PN = "2";
BODY = "RES","I119": #LOCATION = "R8F6" !CDS_LOCATION = "R8F6" &SEC = "1" #&CDS_SEC = "1";
"A":   PN = "1"  !CDS_PN = "1";
"B":   PN = "2"  !CDS_PN = "2";
BODY = "FET_N","I126": #LOCATION = "Q8F1" !CDS_LOCATION = "Q8F1" #SEC = "1" !CDS_SEC = "1";
"DRN":   PN = "3"  !CDS_PN = "3";
"GATE":   PN = "1"  !CDS_PN = "1";
"SRC":   PN = "2"  !CDS_PN = "2";
BODY = "RES","I127": #LOCATION = "R2T6" !CDS_LOCATION = "R2T6" &SEC = "1" #&CDS_SEC = "1";
"A":   PN = "1"  !CDS_PN = "1";
"B":   PN = "2"  !CDS_PN = "2";
BODY = "RES","I128": #LOCATION = "R1U6" !CDS_LOCATION = "R1U6" #SEC = "1" !CDS_SEC = "1";
"A":   PN = "1"  !CDS_PN = "1";
"B":   PN = "2"  !CDS_PN = "2";
BODY = "CAP_A","I132": #LOCATION = "C2T12" !CDS_LOCATION = "C2T12" #SEC = "1" !CDS_SEC = "1";
"A":   PN = "1"  !CDS_PN = "1";
"B":   PN = "2"  !CDS_PN = "2";
BODY = "CAP_A","I135": #LOCATION = "C2T8" !CDS_LOCATION = "C2T8" #SEC = "1" !CDS_SEC = "1";
"A":   PN = "1"  !CDS_PN = "1";
"B":   PN = "2"  !CDS_PN = "2";
DRAWING = "@baseboard_fab2_lib.baseboard_fab2(sch_1):page155";
BODY = "RES","I53": #LOCATION = "R9A8" !CDS_LOCATION = "R9A8" #SEC = "1" !CDS_SEC = "1";
"A":   PN = "1"  !CDS_PN = "1";
"B":   PN = "2"  !CDS_PN = "2";
BODY = "RES","I65": #LOCATION = "R1L32" !CDS_LOCATION = "R1L32" &SEC = "1" #&CDS_SEC = "1";
"A":   PN = "1"  !CDS_PN = "1";
"B":   PN = "2"  !CDS_PN = "2";
BODY = "RES","I66": #LOCATION = "R1L30" !CDS_LOCATION = "R1L30" &SEC = "1" #&CDS_SEC = "1";
"A":   PN = "1"  !CDS_PN = "1";
"B":   PN = "2"  !CDS_PN = "2";
BODY = "RES","I67": #LOCATION = "R1L25" !CDS_LOCATION = "R1L25" &SEC = "1" #&CDS_SEC = "1";
"A":   PN = "1"  !CDS_PN = "1";
"B":   PN = "2"  !CDS_PN = "2";
BODY = "RES","I68": #LOCATION = "R1L24" !CDS_LOCATION = "R1L24" &SEC = "1" #&CDS_SEC = "1";
"A":   PN = "1"  !CDS_PN = "1";
"B":   PN = "2"  !CDS_PN = "2";
BODY = "RES","I73": #LOCATION = "R1L20" !CDS_LOCATION = "R1L20" &SEC = "1" #&CDS_SEC = "1";
"A":   PN = "1"  !CDS_PN = "1";
"B":   PN = "2"  !CDS_PN = "2";
BODY = "RES","I74": #LOCATION = "R1L18" !CDS_LOCATION = "R1L18" &SEC = "1" #&CDS_SEC = "1";
"A":   PN = "1"  !CDS_PN = "1";
"B":   PN = "2"  !CDS_PN = "2";
BODY = "RES","I75": #LOCATION = "R1L14" !CDS_LOCATION = "R1L14" &SEC = "1" #&CDS_SEC = "1";
"A":   PN = "1"  !CDS_PN = "1";
"B":   PN = "2"  !CDS_PN = "2";
BODY = "RES","I76": #LOCATION = "R1L11" !CDS_LOCATION = "R1L11" &SEC = "1" #&CDS_SEC = "1";
"A":   PN = "1"  !CDS_PN = "1";
"B":   PN = "2"  !CDS_PN = "2";
BODY = "RES","I80": #LOCATION = "R9A7" !CDS_LOCATION = "R9A7" #SEC = "1" !CDS_SEC = "1";
"A":   PN = "1"  !CDS_PN = "1";
"B":   PN = "2"  !CDS_PN = "2";
BODY = "CAP_A","I127": #LOCATION = "C9A1" !CDS_LOCATION = "C9A1" &SEC = "1" #&CDS_SEC = "1";
"A":   PN = "1"  !CDS_PN = "1";
"B":   PN = "2"  !CDS_PN = "2";
BODY = "FUSE","I129": #LOCATION = "F1L1" !CDS_LOCATION = "F1L1" #SEC = "1" !CDS_SEC = "1";
"A<0>":   PN = "1"  !CDS_PN = "1";
"B<0>":   PN = "2"  !CDS_PN = "2";
BODY = "RES","I130": #LOCATION = "R1L9" !CDS_LOCATION = "R1L9" #SEC = "1" !CDS_SEC = "1";
"A":   PN = "1"  !CDS_PN = "1";
"B":   PN = "2"  !CDS_PN = "2";
BODY = "CONN14_H54902001","I171": #LOCATION = "J9A2" !CDS_LOCATION = "J9A2" &SEC = "1" #&CDS_SEC = "1";
"IO1":   PN = "1"  !CDS_PN = "1";
"IO2":   PN = "2"  !CDS_PN = "2";
"IO3":   PN = "3"  !CDS_PN = "3";
"IO4":   PN = "4"  !CDS_PN = "4";
"IO5":   PN = "5"  !CDS_PN = "5";
"IO6":   PN = "6"  !CDS_PN = "6";
"IO7":   PN = "7"  !CDS_PN = "7";
"IO8":   PN = "8"  !CDS_PN = "8";
"IO9":   PN = "9"  !CDS_PN = "9";
"IO10":   PN = "10"  !CDS_PN = "10";
"IO11":   PN = "11"  !CDS_PN = "11";
"IO12":   PN = "12"  !CDS_PN = "12";
"IO13":   PN = "13"  !CDS_PN = "13";
"IO14":   PN = "14"  !CDS_PN = "14";
BODY = "TTL1G07_A","I178": #LOCATION = "U9A1" !CDS_LOCATION = "U9A1" #SEC = "1" !CDS_SEC = "1";
"A":   PN = "2"  !CDS_PN = "2";
"Y":   PN = "4"  !CDS_PN = "4";
BODY = "CAP_A","I184": #LOCATION = "C1T56" !CDS_LOCATION = "C1T56" #SEC = "1" !CDS_SEC = "1";
"A":   PN = "1"  !CDS_PN = "1";
"B":   PN = "2"  !CDS_PN = "2";
BODY = "RES","I186": #LOCATION = "R1L2" !CDS_LOCATION = "R1L2" &SEC = "1" #&CDS_SEC = "1";
"A":   PN = "1"  !CDS_PN = "1";
"B":   PN = "2"  !CDS_PN = "2";
BODY = "FET_N_DUAL","I187": #LOCATION = "Q1L2" !CDS_LOCATION = "Q1L2" #SEC = "2" !CDS_SEC = "2";
"DRAIN<0>":   PN = "3"  !CDS_PN = "3";
"GATE<0>":   PN = "5"  !CDS_PN = "5";
"SOURCE<0>":   PN = "4"  !CDS_PN = "4";
BODY = "FET_N_DUAL","I188": #LOCATION = "Q1L2" !CDS_LOCATION = "Q1L2" #SEC = "1" !CDS_SEC = "1";
"DRAIN<0>":   PN = "6"  !CDS_PN = "6";
"GATE<0>":   PN = "2"  !CDS_PN = "2";
"SOURCE<0>":   PN = "1"  !CDS_PN = "1";
BODY = "RES","I191": #LOCATION = "R9A6" !CDS_LOCATION = "R9A6" &SEC = "1" #&CDS_SEC = "1";
"A":   PN = "1"  !CDS_PN = "1";
"B":   PN = "2"  !CDS_PN = "2";
BODY = "RES","I195": #LOCATION = "R9A5" !CDS_LOCATION = "R9A5" &SEC = "1" #&CDS_SEC = "1";
"A":   PN = "1"  !CDS_PN = "1";
"B":   PN = "2"  !CDS_PN = "2";
BODY = "RES","I196": #LOCATION = "R6W19" !CDS_LOCATION = "R6W19" &SEC = "1" #&CDS_SEC = "1";
"A":   PN = "1"  !CDS_PN = "1";
"B":   PN = "2"  !CDS_PN = "2";
DRAWING = "@baseboard_fab2_lib.baseboard_fab2(sch_1):page156";
BODY = "TTL2G07","I201": #LOCATION = "U8F3" !CDS_LOCATION = "U8F3" #SEC = "1" !CDS_SEC = "1";
"1A":   PN = "1"  !CDS_PN = "1";
"1Y":   PN = "6"  !CDS_PN = "6";
"2A":   PN = "3"  !CDS_PN = "3";
"2Y":   PN = "4"  !CDS_PN = "4";
BODY = "RES","I206": #LOCATION = "R2T34" !CDS_LOCATION = "R2T34" #SEC = "1" !CDS_SEC = "1";
"A":   PN = "1"  !CDS_PN = "1";
"B":   PN = "2"  !CDS_PN = "2";
BODY = "RES","I207": #LOCATION = "R2T35" !CDS_LOCATION = "R2T35" #SEC = "1" !CDS_SEC = "1";
"A":   PN = "1"  !CDS_PN = "1";
"B":   PN = "2"  !CDS_PN = "2";
BODY = "RES","I210": #LOCATION = "R2T22" !CDS_LOCATION = "R2T22" #SEC = "1" !CDS_SEC = "1";
"A":   PN = "1"  !CDS_PN = "1";
"B":   PN = "2"  !CDS_PN = "2";
BODY = "RES","I211": #LOCATION = "R8F26" !CDS_LOCATION = "R8F26" #SEC = "1" !CDS_SEC = "1";
"A":   PN = "1"  !CDS_PN = "1";
"B":   PN = "2"  !CDS_PN = "2";
BODY = "RES","I214": #LOCATION = "R8E24" !CDS_LOCATION = "R8E24" #SEC = "1" !CDS_SEC = "1";
"A":   PN = "1"  !CDS_PN = "1";
"B":   PN = "2"  !CDS_PN = "2";
BODY = "RES","I215": #LOCATION = "R8E22" !CDS_LOCATION = "R8E22" #SEC = "1" !CDS_SEC = "1";
"A":   PN = "1"  !CDS_PN = "1";
"B":   PN = "2"  !CDS_PN = "2";
BODY = "RES","I265": #LOCATION = "R2U2" !CDS_LOCATION = "R2U2" #SEC = "1" !CDS_SEC = "1";
"A":   PN = "1"  !CDS_PN = "1";
"B":   PN = "2"  !CDS_PN = "2";
BODY = "RES","I267": #LOCATION = "R8G2" !CDS_LOCATION = "R8G2" #SEC = "1" !CDS_SEC = "1";
"A":   PN = "1"  !CDS_PN = "1";
"B":   PN = "2"  !CDS_PN = "2";
BODY = "TTL2G07","I269": #LOCATION = "U8G1" !CDS_LOCATION = "U8G1" #SEC = "1" !CDS_SEC = "1";
"1A":   PN = "1"  !CDS_PN = "1";
"1Y":   PN = "6"  !CDS_PN = "6";
"2A":   PN = "3"  !CDS_PN = "3";
"2Y":   PN = "4"  !CDS_PN = "4";
BODY = "CAP_A","I273": #LOCATION = "C2T35" !CDS_LOCATION = "C2T35" #SEC = "1" !CDS_SEC = "1";
"A":   PN = "1"  !CDS_PN = "1";
"B":   PN = "2"  !CDS_PN = "2";
BODY = "CAP_A","I275": #LOCATION = "C8F16" !CDS_LOCATION = "C8F16" #SEC = "1" !CDS_SEC = "1";
"A":   PN = "1"  !CDS_PN = "1";
"B":   PN = "2"  !CDS_PN = "2";
BODY = "RES","I279": #LOCATION = "R8E11" !CDS_LOCATION = "R8E11" #SEC = "1" !CDS_SEC = "1";
"A":   PN = "1"  !CDS_PN = "1";
"B":   PN = "2"  !CDS_PN = "2";
BODY = "CONN3_C95678002","I281": #LOCATION = "J9B2" !CDS_LOCATION = "J9B2" #SEC = "1" !CDS_SEC = "1";
"IO1":   PN = "1"  !CDS_PN = "1";
"IO2":   PN = "2"  !CDS_PN = "2";
"IO3":   PN = "3"  !CDS_PN = "3";
BODY = "CONN3_C95678002","I285": #LOCATION = "J8C1" !CDS_LOCATION = "J8C1" #SEC = "1" !CDS_SEC = "1";
"IO1":   PN = "1"  !CDS_PN = "1";
"IO2":   PN = "2"  !CDS_PN = "2";
"IO3":   PN = "3"  !CDS_PN = "3";
BODY = "RES","I288": #LOCATION = "R2T18" !CDS_LOCATION = "R2T18" #SEC = "1" !CDS_SEC = "1";
"A":   PN = "1"  !CDS_PN = "1";
"B":   PN = "2"  !CDS_PN = "2";
BODY = "RES","I289": #LOCATION = "R2T28" !CDS_LOCATION = "R2T28" #SEC = "1" !CDS_SEC = "1";
"A":   PN = "1"  !CDS_PN = "1";
"B":   PN = "2"  !CDS_PN = "2";
BODY = "RES","I299": #LOCATION = "R6D16" !CDS_LOCATION = "R6D16" #SEC = "1" !CDS_SEC = "1";
"A":   PN = "1"  !CDS_PN = "1";
"B":   PN = "2"  !CDS_PN = "2";
BODY = "RES","I300": #LOCATION = "R3D31" !CDS_LOCATION = "R3D31" #SEC = "1" !CDS_SEC = "1";
"A":   PN = "1"  !CDS_PN = "1";
"B":   PN = "2"  !CDS_PN = "2";
BODY = "RES","I302": #LOCATION = "R6N14" !CDS_LOCATION = "R6N14" #SEC = "1" !CDS_SEC = "1";
"A":   PN = "1"  !CDS_PN = "1";
"B":   PN = "2"  !CDS_PN = "2";
BODY = "RES","I303": #LOCATION = "R6N13" !CDS_LOCATION = "R6N13" #SEC = "1" !CDS_SEC = "1";
"A":   PN = "1"  !CDS_PN = "1";
"B":   PN = "2"  !CDS_PN = "2";
BODY = "RES","I304": #LOCATION = "R6N15" !CDS_LOCATION = "R6N15" #SEC = "1" !CDS_SEC = "1";
"A":   PN = "1"  !CDS_PN = "1";
"B":   PN = "2"  !CDS_PN = "2";
BODY = "RES","I312": #LOCATION = "R1C32" !CDS_LOCATION = "R1C32" #SEC = "1" !CDS_SEC = "1";
"A":   PN = "1"  !CDS_PN = "1";
"B":   PN = "2"  !CDS_PN = "2";
BODY = "RES","I313": #LOCATION = "R1C33" !CDS_LOCATION = "R1C33" #SEC = "1" !CDS_SEC = "1";
"A":   PN = "1"  !CDS_PN = "1";
"B":   PN = "2"  !CDS_PN = "2";
BODY = "RES","I320": #LOCATION = "R1C34" !CDS_LOCATION = "R1C34" #SEC = "1" !CDS_SEC = "1";
"A":   PN = "1"  !CDS_PN = "1";
"B":   PN = "2"  !CDS_PN = "2";
BODY = "RES","I321": #LOCATION = "R9M21" !CDS_LOCATION = "R9M21" #SEC = "1" !CDS_SEC = "1";
"A":   PN = "1"  !CDS_PN = "1";
"B":   PN = "2"  !CDS_PN = "2";
BODY = "RES","I322": #LOCATION = "R4A8" !CDS_LOCATION = "R4A8" #SEC = "1" !CDS_SEC = "1";
"A":   PN = "1"  !CDS_PN = "1";
"B":   PN = "2"  !CDS_PN = "2";
BODY = "RES","I323": #LOCATION = "R9M20" !CDS_LOCATION = "R9M20" #SEC = "1" !CDS_SEC = "1";
"A":   PN = "1"  !CDS_PN = "1";
"B":   PN = "2"  !CDS_PN = "2";
BODY = "RES","I324": #LOCATION = "R4A9" !CDS_LOCATION = "R4A9" #SEC = "1" !CDS_SEC = "1";
"A":   PN = "1"  !CDS_PN = "1";
"B":   PN = "2"  !CDS_PN = "2";
BODY = "RES","I331": #LOCATION = "R3P54" !CDS_LOCATION = "R3P54" #SEC = "1" !CDS_SEC = "1";
"A":   PN = "1"  !CDS_PN = "1";
"B":   PN = "2"  !CDS_PN = "2";
BODY = "RES","I333": #LOCATION = "R3P56" !CDS_LOCATION = "R3P56" #SEC = "1" !CDS_SEC = "1";
"A":   PN = "1"  !CDS_PN = "1";
"B":   PN = "2"  !CDS_PN = "2";
BODY = "RES","I336": #LOCATION = "R1C35" !CDS_LOCATION = "R1C35" #SEC = "1" !CDS_SEC = "1";
"A":   PN = "1"  !CDS_PN = "1";
"B":   PN = "2"  !CDS_PN = "2";
BODY = "RES","I337": #LOCATION = "R1C36" !CDS_LOCATION = "R1C36" #SEC = "1" !CDS_SEC = "1";
"A":   PN = "1"  !CDS_PN = "1";
"B":   PN = "2"  !CDS_PN = "2";
DRAWING = "@baseboard_fab2_lib.baseboard_fab2(sch_1):page157";
BODY = "RES","I97": #LOCATION = "R2N27" !CDS_LOCATION = "R2N27" #SEC = "1" !CDS_SEC = "1";
"A":   PN = "1"  !CDS_PN = "1";
"B":   PN = "2"  !CDS_PN = "2";
BODY = "RES","I296": #LOCATION = "R8F23" !CDS_LOCATION = "R8F23" #SEC = "1" !CDS_SEC = "1";
"A":   PN = "1"  !CDS_PN = "1";
"B":   PN = "2"  !CDS_PN = "2";
BODY = "RES","I298": #LOCATION = "R2T29" !CDS_LOCATION = "R2T29" #SEC = "1" !CDS_SEC = "1";
"A":   PN = "1"  !CDS_PN = "1";
"B":   PN = "2"  !CDS_PN = "2";
BODY = "RES","I302": #LOCATION = "R2N25" !CDS_LOCATION = "R2N25" #SEC = "1" !CDS_SEC = "1";
"A":   PN = "1"  !CDS_PN = "1";
"B":   PN = "2"  !CDS_PN = "2";
BODY = "RES","I316": #LOCATION = "R8F24" !CDS_LOCATION = "R8F24" #SEC = "1" !CDS_SEC = "1";
"A":   PN = "1"  !CDS_PN = "1";
"B":   PN = "2"  !CDS_PN = "2";
BODY = "RES","I326": #LOCATION = "R2T5" !CDS_LOCATION = "R2T5" #SEC = "1" !CDS_SEC = "1";
"A":   PN = "1"  !CDS_PN = "1";
"B":   PN = "2"  !CDS_PN = "2";
BODY = "RES","I327": #LOCATION = "R2T7" !CDS_LOCATION = "R2T7" #SEC = "1" !CDS_SEC = "1";
"A":   PN = "1"  !CDS_PN = "1";
"B":   PN = "2"  !CDS_PN = "2";
BODY = "NPN","I330": #LOCATION = "Q2T1" !CDS_LOCATION = "Q2T1" #SEC = "1" !CDS_SEC = "1";
"B":   PN = "1"  !CDS_PN = "1";
"C":   PN = "3"  !CDS_PN = "3";
"E":   PN = "2"  !CDS_PN = "2";
BODY = "RES","I335": #LOCATION = "R8D25" !CDS_LOCATION = "R8D25" #SEC = "1" !CDS_SEC = "1";
"A":   PN = "1"  !CDS_PN = "1";
"B":   PN = "2"  !CDS_PN = "2";
BODY = "FET_N","I340": #LOCATION = "Q2T2" !CDS_LOCATION = "Q2T2" #SEC = "1" !CDS_SEC = "1";
"DRN":   PN = "3"  !CDS_PN = "3";
"GATE":   PN = "1"  !CDS_PN = "1";
"SRC":   PN = "2"  !CDS_PN = "2";
BODY = "RES","I342": #LOCATION = "R3N12" !CDS_LOCATION = "R3N12" #SEC = "1" !CDS_SEC = "1";
"A":   PN = "1"  !CDS_PN = "1";
"B":   PN = "2"  !CDS_PN = "2";
BODY = "RES","I344": #LOCATION = "R3N11" !CDS_LOCATION = "R3N11" #SEC = "1" !CDS_SEC = "1";
"A":   PN = "1"  !CDS_PN = "1";
"B":   PN = "2"  !CDS_PN = "2";
BODY = "RES","I346": #LOCATION = "R2M2" !CDS_LOCATION = "R2M2" #SEC = "1" !CDS_SEC = "1";
"A":   PN = "1"  !CDS_PN = "1";
"B":   PN = "2"  !CDS_PN = "2";
BODY = "RES","I348": #LOCATION = "R2M5" !CDS_LOCATION = "R2M5" #SEC = "1" !CDS_SEC = "1";
"A":   PN = "1"  !CDS_PN = "1";
"B":   PN = "2"  !CDS_PN = "2";
BODY = "SWITCH_D90553001","I351": #LOCATION = "S8E1" !CDS_LOCATION = "S8E1" #SEC = "1" !CDS_SEC = "1";
"A":   PN = "1"  !CDS_PN = "1";
"B":   PN = "2"  !CDS_PN = "2";
BODY = "RES","I352": #LOCATION = "R2R9" !CDS_LOCATION = "R2R9" #SEC = "1" !CDS_SEC = "1";
"A":   PN = "1"  !CDS_PN = "1";
"B":   PN = "2"  !CDS_PN = "2";
BODY = "CAP_A","I353": #LOCATION = "C2R12" !CDS_LOCATION = "C2R12" #SEC = "1" !CDS_SEC = "1";
"A":   PN = "1"  !CDS_PN = "1";
"B":   PN = "2"  !CDS_PN = "2";
BODY = "TTL2G14","I356": #LOCATION = "U2R1" !CDS_LOCATION = "U2R1" #SEC = "2" !CDS_SEC = "2";
"A<0>":   PN = "3"  !CDS_PN = "3";
"Y<0>":   PN = "4"  !CDS_PN = "4";
BODY = "TTL2G14","I357": #LOCATION = "U2R1" !CDS_LOCATION = "U2R1" #SEC = "1" !CDS_SEC = "1";
"A<0>":   PN = "1"  !CDS_PN = "1";
"Y<0>":   PN = "6"  !CDS_PN = "6";
BODY = "RES","I358": #LOCATION = "R2R10" !CDS_LOCATION = "R2R10" #SEC = "1" !CDS_SEC = "1";
"A":   PN = "1"  !CDS_PN = "1";
"B":   PN = "2"  !CDS_PN = "2";
BODY = "RES","I361": #LOCATION = "R8E19" !CDS_LOCATION = "R8E19" #SEC = "1" !CDS_SEC = "1";
"A":   PN = "1"  !CDS_PN = "1";
"B":   PN = "2"  !CDS_PN = "2";
BODY = "RES","I367": #LOCATION = "R2U4" !CDS_LOCATION = "R2U4" #SEC = "1" !CDS_SEC = "1";
"A":   PN = "1"  !CDS_PN = "1";
"B":   PN = "2"  !CDS_PN = "2";
BODY = "RES","I368": #LOCATION = "R4R1" !CDS_LOCATION = "R4R1" #SEC = "1" !CDS_SEC = "1";
"A":   PN = "1"  !CDS_PN = "1";
"B":   PN = "2"  !CDS_PN = "2";
BODY = "CAP_A","I370": #LOCATION = "C2T3" !CDS_LOCATION = "C2T3" #SEC = "1" !CDS_SEC = "1";
"A":   PN = "1"  !CDS_PN = "1";
"B":   PN = "2"  !CDS_PN = "2";
BODY = "TTL1G07_A","I374": #LOCATION = "U8D2" !CDS_LOCATION = "U8D2" #SEC = "1" !CDS_SEC = "1";
"A":   PN = "2"  !CDS_PN = "2";
"Y":   PN = "4"  !CDS_PN = "4";
BODY = "CAP_A","I376": #LOCATION = "C8D1" !CDS_LOCATION = "C8D1" #SEC = "1" !CDS_SEC = "1";
"A":   PN = "1"  !CDS_PN = "1";
"B":   PN = "2"  !CDS_PN = "2";
BODY = "RES","I379": #LOCATION = "R9E14" !CDS_LOCATION = "R9E14" #SEC = "1" !CDS_SEC = "1";
"A":   PN = "1"  !CDS_PN = "1";
"B":   PN = "2"  !CDS_PN = "2";
BODY = "RES","I382": #LOCATION = "R1L7" !CDS_LOCATION = "R1L7" #SEC = "1" !CDS_SEC = "1";
"A":   PN = "1"  !CDS_PN = "1";
"B":   PN = "2"  !CDS_PN = "2";
BODY = "RES","I385": #LOCATION = "R8E32" !CDS_LOCATION = "R8E32" #SEC = "1" !CDS_SEC = "1";
"A":   PN = "1"  !CDS_PN = "1";
"B":   PN = "2"  !CDS_PN = "2";
BODY = "RES","I386": #LOCATION = "R8D22" !CDS_LOCATION = "R8D22" #SEC = "1" !CDS_SEC = "1";
"A":   PN = "1"  !CDS_PN = "1";
"B":   PN = "2"  !CDS_PN = "2";
BODY = "RES","I388": #LOCATION = "R8D36" !CDS_LOCATION = "R8D36" #SEC = "1" !CDS_SEC = "1";
"A":   PN = "1"  !CDS_PN = "1";
"B":   PN = "2"  !CDS_PN = "2";
DRAWING = "@baseboard_fab2_lib.baseboard_fab2(sch_1):page158";
BODY = "CAP_A","I70": #LOCATION = "C1T10" !CDS_LOCATION = "C1T10" #SEC = "1" !CDS_SEC = "1";
"A":   PN = "1"  !CDS_PN = "1";
"B":   PN = "2"  !CDS_PN = "2";
BODY = "FSA3357","I74": #LOCATION = "U9F2" !CDS_LOCATION = "U9F2" #SEC = "1" !CDS_SEC = "1";
"A":   PN = "7"  !CDS_PN = "7";
"B0":   PN = "1"  !CDS_PN = "1";
"B1":   PN = "2"  !CDS_PN = "2";
"B2":   PN = "3"  !CDS_PN = "3";
"GND":   PN = "4"  !CDS_PN = "4";
"S1":   PN = "6"  !CDS_PN = "6";
"S2":   PN = "5"  !CDS_PN = "5";
"VCC":   PN = "8"  !CDS_PN = "8";
BODY = "FSA3357","I75": #LOCATION = "U9F1" !CDS_LOCATION = "U9F1" #SEC = "1" !CDS_SEC = "1";
"A":   PN = "7"  !CDS_PN = "7";
"B0":   PN = "1"  !CDS_PN = "1";
"B1":   PN = "2"  !CDS_PN = "2";
"B2":   PN = "3"  !CDS_PN = "3";
"GND":   PN = "4"  !CDS_PN = "4";
"S1":   PN = "6"  !CDS_PN = "6";
"S2":   PN = "5"  !CDS_PN = "5";
"VCC":   PN = "8"  !CDS_PN = "8";
BODY = "RES","I86": #LOCATION = "R9F25" !CDS_LOCATION = "R9F25" #SEC = "1" !CDS_SEC = "1";
"A":   PN = "1"  !CDS_PN = "1";
"B":   PN = "2"  !CDS_PN = "2";
BODY = "RES","I91": #LOCATION = "R9F27" !CDS_LOCATION = "R9F27" #SEC = "1" !CDS_SEC = "1";
"A":   PN = "1"  !CDS_PN = "1";
"B":   PN = "2"  !CDS_PN = "2";
BODY = "CAP_A","I97": #LOCATION = "C1T11" !CDS_LOCATION = "C1T11" #SEC = "1" !CDS_SEC = "1";
"A":   PN = "1"  !CDS_PN = "1";
"B":   PN = "2"  !CDS_PN = "2";
BODY = "RES","I99": #LOCATION = "R9F26" !CDS_LOCATION = "R9F26" #SEC = "1" !CDS_SEC = "1";
"A":   PN = "1"  !CDS_PN = "1";
"B":   PN = "2"  !CDS_PN = "2";
BODY = "RES","I100": #LOCATION = "R9F24" !CDS_LOCATION = "R9F24" #SEC = "1" !CDS_SEC = "1";
"A":   PN = "1"  !CDS_PN = "1";
"B":   PN = "2"  !CDS_PN = "2";
BODY = "LED","I130": #LOCATION = "DS9A4" !CDS_LOCATION = "DS9A4" #SEC = "1" !CDS_SEC = "1";
"A":   PN = "1"  !CDS_PN = "1";
"C":   PN = "2"  !CDS_PN = "2";
BODY = "RES","I131": #LOCATION = "R1L43" !CDS_LOCATION = "R1L43" #SEC = "1" !CDS_SEC = "1";
"A":   PN = "1"  !CDS_PN = "1";
"B":   PN = "2"  !CDS_PN = "2";
BODY = "LED","I134": #LOCATION = "DS9A7" !CDS_LOCATION = "DS9A7" #SEC = "1" !CDS_SEC = "1";
"A":   PN = "1"  !CDS_PN = "1";
"C":   PN = "2"  !CDS_PN = "2";
BODY = "RES","I136": #LOCATION = "R1L44" !CDS_LOCATION = "R1L44" #SEC = "1" !CDS_SEC = "1";
"A":   PN = "1"  !CDS_PN = "1";
"B":   PN = "2"  !CDS_PN = "2";
BODY = "RES","I148": #LOCATION = "R9F65" !CDS_LOCATION = "R9F65" &SEC = "1" #&CDS_SEC = "1";
"A":   PN = "1"  !CDS_PN = "1";
"B":   PN = "2"  !CDS_PN = "2";
BODY = "RES","I149": #LOCATION = "R9F68" !CDS_LOCATION = "R9F68" &SEC = "1" #&CDS_SEC = "1";
"A":   PN = "1"  !CDS_PN = "1";
"B":   PN = "2"  !CDS_PN = "2";
BODY = "RES","I150": #LOCATION = "R9F69" !CDS_LOCATION = "R9F69" #SEC = "1" !CDS_SEC = "1";
"A":   PN = "1"  !CDS_PN = "1";
"B":   PN = "2"  !CDS_PN = "2";
BODY = "RES","I152": #LOCATION = "R9F66" !CDS_LOCATION = "R9F66" &SEC = "1" #&CDS_SEC = "1";
"A":   PN = "1"  !CDS_PN = "1";
"B":   PN = "2"  !CDS_PN = "2";
DRAWING = "@baseboard_fab2_lib.baseboard_fab2(sch_1):page159";
BODY = "RES","I210": #LOCATION = "R8G3" !CDS_LOCATION = "R8G3" &SEC = "1" #&CDS_SEC = "1";
"A":   PN = "1"  !CDS_PN = "1";
"B":   PN = "2"  !CDS_PN = "2";
BODY = "RES","I212": #LOCATION = "R8G6" !CDS_LOCATION = "R8G6" &SEC = "1" #&CDS_SEC = "1";
"A":   PN = "1"  !CDS_PN = "1";
"B":   PN = "2"  !CDS_PN = "2";
BODY = "RES","I214": #LOCATION = "R2U5" !CDS_LOCATION = "R2U5" &SEC = "1" #&CDS_SEC = "1";
"A":   PN = "1"  !CDS_PN = "1";
"B":   PN = "2"  !CDS_PN = "2";
BODY = "RES","I216": #LOCATION = "R2U13" !CDS_LOCATION = "R2U13" &SEC = "1" #&CDS_SEC = "1";
"A":   PN = "1"  !CDS_PN = "1";
"B":   PN = "2"  !CDS_PN = "2";
BODY = "RES","I218": #LOCATION = "R2U1" !CDS_LOCATION = "R2U1" &SEC = "1" #&CDS_SEC = "1";
"A":   PN = "1"  !CDS_PN = "1";
"B":   PN = "2"  !CDS_PN = "2";
BODY = "RES","I219": #LOCATION = "R2T49" !CDS_LOCATION = "R2T49" &SEC = "1" #&CDS_SEC = "1";
"A":   PN = "1"  !CDS_PN = "1";
"B":   PN = "2"  !CDS_PN = "2";
BODY = "RES","I220": #LOCATION = "R2U7" !CDS_LOCATION = "R2U7" &SEC = "1" #&CDS_SEC = "1";
"A":   PN = "1"  !CDS_PN = "1";
"B":   PN = "2"  !CDS_PN = "2";
BODY = "RES","I221": #LOCATION = "R2U10" !CDS_LOCATION = "R2U10" &SEC = "1" #&CDS_SEC = "1";
"A":   PN = "1"  !CDS_PN = "1";
"B":   PN = "2"  !CDS_PN = "2";
BODY = "RES","I222": #LOCATION = "R1U11" !CDS_LOCATION = "R1U11" &SEC = "1" #&CDS_SEC = "1";
"A":   PN = "1"  !CDS_PN = "1";
"B":   PN = "2"  !CDS_PN = "2";
BODY = "RES","I223": #LOCATION = "R1U8" !CDS_LOCATION = "R1U8" &SEC = "1" #&CDS_SEC = "1";
"A":   PN = "1"  !CDS_PN = "1";
"B":   PN = "2"  !CDS_PN = "2";
BODY = "RES","I224": #LOCATION = "R9G12" !CDS_LOCATION = "R9G12" &SEC = "1" #&CDS_SEC = "1";
"A":   PN = "1"  !CDS_PN = "1";
"B":   PN = "2"  !CDS_PN = "2";
BODY = "RES","I225": #LOCATION = "R1U20" !CDS_LOCATION = "R1U20" &SEC = "1" #&CDS_SEC = "1";
"A":   PN = "1"  !CDS_PN = "1";
"B":   PN = "2"  !CDS_PN = "2";
BODY = "RES","I226": #LOCATION = "R1U19" !CDS_LOCATION = "R1U19" &SEC = "1" #&CDS_SEC = "1";
"A":   PN = "1"  !CDS_PN = "1";
"B":   PN = "2"  !CDS_PN = "2";
BODY = "RES","I227": #LOCATION = "R9G13" !CDS_LOCATION = "R9G13" &SEC = "1" #&CDS_SEC = "1";
"A":   PN = "1"  !CDS_PN = "1";
"B":   PN = "2"  !CDS_PN = "2";
BODY = "RES","I228": #LOCATION = "R8G5" !CDS_LOCATION = "R8G5" &SEC = "1" #&CDS_SEC = "1";
"A":   PN = "1"  !CDS_PN = "1";
"B":   PN = "2"  !CDS_PN = "2";
BODY = "RES","I229": #LOCATION = "R8G4" !CDS_LOCATION = "R8G4" &SEC = "1" #&CDS_SEC = "1";
"A":   PN = "1"  !CDS_PN = "1";
"B":   PN = "2"  !CDS_PN = "2";
BODY = "RES","I230": #LOCATION = "R2U34" !CDS_LOCATION = "R2U34" &SEC = "1" #&CDS_SEC = "1";
"A":   PN = "1"  !CDS_PN = "1";
"B":   PN = "2"  !CDS_PN = "2";
BODY = "RES","I231": #LOCATION = "R2U33" !CDS_LOCATION = "R2U33" &SEC = "1" #&CDS_SEC = "1";
"A":   PN = "1"  !CDS_PN = "1";
"B":   PN = "2"  !CDS_PN = "2";
BODY = "RES","I232": #LOCATION = "R1U9" !CDS_LOCATION = "R1U9" &SEC = "1" #&CDS_SEC = "1";
"A":   PN = "1"  !CDS_PN = "1";
"B":   PN = "2"  !CDS_PN = "2";
BODY = "RES","I233": #LOCATION = "R1U10" !CDS_LOCATION = "R1U10" &SEC = "1" #&CDS_SEC = "1";
"A":   PN = "1"  !CDS_PN = "1";
"B":   PN = "2"  !CDS_PN = "2";
DRAWING = "@baseboard_fab2_lib.baseboard_fab2(sch_1):page160";
BODY = "RES","I4": #LOCATION = "R1T8" !CDS_LOCATION = "R1T8" &SEC = "1" #&CDS_SEC = "1";
"A":   PN = "1"  !CDS_PN = "1";
"B":   PN = "2"  !CDS_PN = "2";
BODY = "RES","I46": #LOCATION = "R1T3" !CDS_LOCATION = "R1T3" &SEC = "1" #&CDS_SEC = "1";
"A":   PN = "1"  !CDS_PN = "1";
"B":   PN = "2"  !CDS_PN = "2";
BODY = "RES","I49": #LOCATION = "R1T2" !CDS_LOCATION = "R1T2" &SEC = "1" #&CDS_SEC = "1";
"A":   PN = "1"  !CDS_PN = "1";
"B":   PN = "2"  !CDS_PN = "2";
BODY = "RES","I50": #LOCATION = "R1T7" !CDS_LOCATION = "R1T7" &SEC = "1" #&CDS_SEC = "1";
"A":   PN = "1"  !CDS_PN = "1";
"B":   PN = "2"  !CDS_PN = "2";
BODY = "RES","I51": #LOCATION = "R9F23" !CDS_LOCATION = "R9F23" &SEC = "1" #&CDS_SEC = "1";
"A":   PN = "1"  !CDS_PN = "1";
"B":   PN = "2"  !CDS_PN = "2";
BODY = "RES","I52": #LOCATION = "R9F22" !CDS_LOCATION = "R9F22" &SEC = "1" #&CDS_SEC = "1";
"A":   PN = "1"  !CDS_PN = "1";
"B":   PN = "2"  !CDS_PN = "2";
DRAWING = "@baseboard_fab2_lib.baseboard_fab2(sch_1):page161";
BODY = "CONN6_C74770005","I1": #LOCATION = "J1F2" !CDS_LOCATION = "J1F2" #SEC = "1" !CDS_SEC = "1";
"IO1":   PN = "1"  !CDS_PN = "1";
"IO2":   PN = "2"  !CDS_PN = "2";
"IO3":   PN = "3"  !CDS_PN = "3";
"IO4":   PN = "4"  !CDS_PN = "4";
"IO5":   PN = "5"  !CDS_PN = "5";
"IO6":   PN = "6"  !CDS_PN = "6";
BODY = "CAP","I3": #LOCATION = "C1E21" !CDS_LOCATION = "C1E21" #SEC = "1" !CDS_SEC = "1";
"A":   PN = "1"  !CDS_PN = "1";
"B":   PN = "2"  !CDS_PN = "2";
BODY = "CAP_A","I4": #LOCATION = "C1E20" !CDS_LOCATION = "C1E20" #SEC = "1" !CDS_SEC = "1";
"A":   PN = "1"  !CDS_PN = "1";
"B":   PN = "2"  !CDS_PN = "2";
BODY = "CAP_A","I26": #LOCATION = "C9M5" !CDS_LOCATION = "C9M5" #SEC = "1" !CDS_SEC = "1";
"A":   PN = "1"  !CDS_PN = "1";
"B":   PN = "2"  !CDS_PN = "2";
BODY = "CAP","I27": #LOCATION = "C9M4" !CDS_LOCATION = "C9M4" #SEC = "1" !CDS_SEC = "1";
"A":   PN = "1"  !CDS_PN = "1";
"B":   PN = "2"  !CDS_PN = "2";
BODY = "CONN6_C74770005","I32": #LOCATION = "J1B2" !CDS_LOCATION = "J1B2" #SEC = "1" !CDS_SEC = "1";
"IO1":   PN = "1"  !CDS_PN = "1";
"IO2":   PN = "2"  !CDS_PN = "2";
"IO3":   PN = "3"  !CDS_PN = "3";
"IO4":   PN = "4"  !CDS_PN = "4";
"IO5":   PN = "5"  !CDS_PN = "5";
"IO6":   PN = "6"  !CDS_PN = "6";
BODY = "DIODE","I42": #LOCATION = "CR1F1" !CDS_LOCATION = "CR1F1" #SEC = "1" !CDS_SEC = "1";
"A":   PN = "2"  !CDS_PN = "2";
"C":   PN = "1"  !CDS_PN = "1";
BODY = "RES","I43": #LOCATION = "R1F2" !CDS_LOCATION = "R1F2" #SEC = "1" !CDS_SEC = "1";
"A":   PN = "1"  !CDS_PN = "1";
"B":   PN = "2"  !CDS_PN = "2";
BODY = "RES","I45": #LOCATION = "R1F1" !CDS_LOCATION = "R1F1" #SEC = "1" !CDS_SEC = "1";
"A":   PN = "1"  !CDS_PN = "1";
"B":   PN = "2"  !CDS_PN = "2";
BODY = "CAP_A","I46": #LOCATION = "C1F9" !CDS_LOCATION = "C1F9" #SEC = "1" !CDS_SEC = "1";
"A":   PN = "1"  !CDS_PN = "1";
"B":   PN = "2"  !CDS_PN = "2";
BODY = "DIODE","I50": #LOCATION = "CR1E1" !CDS_LOCATION = "CR1E1" #SEC = "1" !CDS_SEC = "1";
"A":   PN = "2"  !CDS_PN = "2";
"C":   PN = "1"  !CDS_PN = "1";
BODY = "RES","I51": #LOCATION = "R1E12" !CDS_LOCATION = "R1E12" #SEC = "1" !CDS_SEC = "1";
"A":   PN = "1"  !CDS_PN = "1";
"B":   PN = "2"  !CDS_PN = "2";
BODY = "DIODE","I62": #LOCATION = "CR1B2" !CDS_LOCATION = "CR1B2" #SEC = "1" !CDS_SEC = "1";
"A":   PN = "2"  !CDS_PN = "2";
"C":   PN = "1"  !CDS_PN = "1";
BODY = "DIODE","I64": #LOCATION = "CR1B1" !CDS_LOCATION = "CR1B1" #SEC = "1" !CDS_SEC = "1";
"A":   PN = "2"  !CDS_PN = "2";
"C":   PN = "1"  !CDS_PN = "1";
BODY = "RES","I65": #LOCATION = "R7F33" !CDS_LOCATION = "R7F33" #SEC = "1" !CDS_SEC = "1";
"A":   PN = "1"  !CDS_PN = "1";
"B":   PN = "2"  !CDS_PN = "2";
BODY = "RES","I67": #LOCATION = "R1B22" !CDS_LOCATION = "R1B22" #SEC = "1" !CDS_SEC = "1";
"A":   PN = "1"  !CDS_PN = "1";
"B":   PN = "2"  !CDS_PN = "2";
BODY = "CAP_A","I68": #LOCATION = "C1B15" !CDS_LOCATION = "C1B15" #SEC = "1" !CDS_SEC = "1";
"A":   PN = "1"  !CDS_PN = "1";
"B":   PN = "2"  !CDS_PN = "2";
BODY = "RES","I70": #LOCATION = "R1B21" !CDS_LOCATION = "R1B21" #SEC = "1" !CDS_SEC = "1";
"A":   PN = "1"  !CDS_PN = "1";
"B":   PN = "2"  !CDS_PN = "2";
BODY = "TTL1G07_A","I88": #LOCATION = "U8G2" !CDS_LOCATION = "U8G2" #SEC = "1" !CDS_SEC = "1";
"A":   PN = "2"  !CDS_PN = "2";
"Y":   PN = "4"  !CDS_PN = "4";
BODY = "CAP_A","I90": #LOCATION = "C2U27" !CDS_LOCATION = "C2U27" #SEC = "1" !CDS_SEC = "1";
"A":   PN = "1"  !CDS_PN = "1";
"B":   PN = "2"  !CDS_PN = "2";
BODY = "TTL1G07_A","I92": #LOCATION = "U8G3" !CDS_LOCATION = "U8G3" #SEC = "1" !CDS_SEC = "1";
"A":   PN = "2"  !CDS_PN = "2";
"Y":   PN = "4"  !CDS_PN = "4";
BODY = "CAP_A","I93": #LOCATION = "C2U28" !CDS_LOCATION = "C2U28" #SEC = "1" !CDS_SEC = "1";
"A":   PN = "1"  !CDS_PN = "1";
"B":   PN = "2"  !CDS_PN = "2";
BODY = "RES","I99": #LOCATION = "R2U42" !CDS_LOCATION = "R2U42" #SEC = "1" !CDS_SEC = "1";
"A":   PN = "1"  !CDS_PN = "1";
"B":   PN = "2"  !CDS_PN = "2";
BODY = "RES","I102": #LOCATION = "R2U44" !CDS_LOCATION = "R2U44" #SEC = "1" !CDS_SEC = "1";
"A":   PN = "1"  !CDS_PN = "1";
"B":   PN = "2"  !CDS_PN = "2";
BODY = "CAP_A","I113": #LOCATION = "C1E22" !CDS_LOCATION = "C1E22" #SEC = "1" !CDS_SEC = "1";
"A":   PN = "1"  !CDS_PN = "1";
"B":   PN = "2"  !CDS_PN = "2";
BODY = "RES","I120": #LOCATION = "R1E11" !CDS_LOCATION = "R1E11" #SEC = "1" !CDS_SEC = "1";
"A":   PN = "1"  !CDS_PN = "1";
"B":   PN = "2"  !CDS_PN = "2";
BODY = "TTL1G08","I121": #LOCATION = "U1E2" !CDS_LOCATION = "U1E2" #SEC = "1" !CDS_SEC = "1";
"A<0>":   PN = "1"  !CDS_PN = "1";
"B<0>":   PN = "2"  !CDS_PN = "2";
"Y<0>":   PN = "4"  !CDS_PN = "4";
BODY = "DIODE","I123": #LOCATION = "CR1B3" !CDS_LOCATION = "CR1B3" #SEC = "1" !CDS_SEC = "1";
"A":   PN = "2"  !CDS_PN = "2";
"C":   PN = "1"  !CDS_PN = "1";
BODY = "RES","I124": #LOCATION = "R1B23" !CDS_LOCATION = "R1B23" #SEC = "1" !CDS_SEC = "1";
"A":   PN = "1"  !CDS_PN = "1";
"B":   PN = "2"  !CDS_PN = "2";
BODY = "RES","I126": #LOCATION = "R1B24" !CDS_LOCATION = "R1B24" #SEC = "1" !CDS_SEC = "1";
"A":   PN = "1"  !CDS_PN = "1";
"B":   PN = "2"  !CDS_PN = "2";
BODY = "CAP_A","I128": #LOCATION = "C1B17" !CDS_LOCATION = "C1B17" #SEC = "1" !CDS_SEC = "1";
"A":   PN = "1"  !CDS_PN = "1";
"B":   PN = "2"  !CDS_PN = "2";
BODY = "DIODE","I133": #LOCATION = "CR1F2" !CDS_LOCATION = "CR1F2" #SEC = "1" !CDS_SEC = "1";
"A":   PN = "2"  !CDS_PN = "2";
"C":   PN = "1"  !CDS_PN = "1";
BODY = "RES","I134": #LOCATION = "R9T7" !CDS_LOCATION = "R9T7" #SEC = "1" !CDS_SEC = "1";
"A":   PN = "1"  !CDS_PN = "1";
"B":   PN = "2"  !CDS_PN = "2";
BODY = "RES","I135": #LOCATION = "R9T5" !CDS_LOCATION = "R9T5" #SEC = "1" !CDS_SEC = "1";
"A":   PN = "1"  !CDS_PN = "1";
"B":   PN = "2"  !CDS_PN = "2";
BODY = "CAP_A","I137": #LOCATION = "C9T1" !CDS_LOCATION = "C9T1" #SEC = "1" !CDS_SEC = "1";
"A":   PN = "1"  !CDS_PN = "1";
"B":   PN = "2"  !CDS_PN = "2";
DRAWING = "@baseboard_fab2_lib.baseboard_fab2(sch_1):page162";
BODY = "RES","I8": #LOCATION = "R8F16" !CDS_LOCATION = "R8F16" #SEC = "1" !CDS_SEC = "1";
"A":   PN = "1"  !CDS_PN = "1";
"B":   PN = "2"  !CDS_PN = "2";
BODY = "RES","I9": #LOCATION = "R8F14" !CDS_LOCATION = "R8F14" #SEC = "1" !CDS_SEC = "1";
"A":   PN = "1"  !CDS_PN = "1";
"B":   PN = "2"  !CDS_PN = "2";
BODY = "RES","I13": #LOCATION = "R8F12" !CDS_LOCATION = "R8F12" #SEC = "1" !CDS_SEC = "1";
"A":   PN = "1"  !CDS_PN = "1";
"B":   PN = "2"  !CDS_PN = "2";
BODY = "RES","I22": #LOCATION = "R8F34" !CDS_LOCATION = "R8F34" &SEC = "1" #&CDS_SEC = "1";
"A":   PN = "1"  !CDS_PN = "1";
"B":   PN = "2"  !CDS_PN = "2";
BODY = "RES","I23": #LOCATION = "R8F13" !CDS_LOCATION = "R8F13" &SEC = "1" #&CDS_SEC = "1";
"A":   PN = "1"  !CDS_PN = "1";
"B":   PN = "2"  !CDS_PN = "2";
BODY = "RES","I24": #LOCATION = "R8F35" !CDS_LOCATION = "R8F35" &SEC = "1" #&CDS_SEC = "1";
"A":   PN = "1"  !CDS_PN = "1";
"B":   PN = "2"  !CDS_PN = "2";
BODY = "CAP_A","I28": #LOCATION = "C8F5" !CDS_LOCATION = "C8F5" &SEC = "1" #&CDS_SEC = "1";
"A":   PN = "1"  !CDS_PN = "1";
"B":   PN = "2"  !CDS_PN = "2";
BODY = "CAP_A","I30": #LOCATION = "C8F4" !CDS_LOCATION = "C8F4" &SEC = "1" #&CDS_SEC = "1";
"A":   PN = "1"  !CDS_PN = "1";
"B":   PN = "2"  !CDS_PN = "2";
BODY = "W25Q128","I32": #LOCATION = "U8F2" !CDS_LOCATION = "U8F2" #SEC = "1" !CDS_SEC = "1";
"CLK":   PN = "16"  !CDS_PN = "16";
"CS_N":   PN = "7"  !CDS_PN = "7";
"DI_IO<0>":   PN = "15"  !CDS_PN = "15";
"DO_IO<1>":   PN = "8"  !CDS_PN = "8";
"GND":   PN = "10"  !CDS_PN = "10";
"HOLD_N_IO<3>":   PN = "1"  !CDS_PN = "1";
"NC<0>":   PN = "4"  !CDS_PN = "4";
"NC<1>":   PN = "5"  !CDS_PN = "5";
"NC<2>":   PN = "6"  !CDS_PN = "6";
"NC<3>":   PN = "11"  !CDS_PN = "11";
"NC<4>":   PN = "12"  !CDS_PN = "12";
"NC<5>":   PN = "13"  !CDS_PN = "13";
"NC<6>":   PN = "14"  !CDS_PN = "14";
"RESET_N":   PN = "3"  !CDS_PN = "3";
"VCC":   PN = "2"  !CDS_PN = "2";
"WP_N_IO<2>":   PN = "9"  !CDS_PN = "9";
DRAWING = "@baseboard_fab2_lib.baseboard_fab2(sch_1):page163";
BODY = "PCA9517","I1": #LOCATION = "U1B2" !CDS_LOCATION = "U1B2" #SEC = "1" !CDS_SEC = "1";
"EN":   PN = "5"  !CDS_PN = "5";
"SCLA":   PN = "2"  !CDS_PN = "2";
"SCLB":   PN = "7"  !CDS_PN = "7";
"SDAA":   PN = "3"  !CDS_PN = "3";
"SDAB":   PN = "6"  !CDS_PN = "6";
"VCCA":   PN = "1"  !CDS_PN = "1";
"VCCB":   PN = "8"  !CDS_PN = "8";
BODY = "RES","I2": #LOCATION = "R6N8" !CDS_LOCATION = "R6N8" #SEC = "1" !CDS_SEC = "1";
"A":   PN = "1"  !CDS_PN = "1";
"B":   PN = "2"  !CDS_PN = "2";
BODY = "RES","I3": #LOCATION = "R6N9" !CDS_LOCATION = "R6N9" #SEC = "1" !CDS_SEC = "1";
"A":   PN = "1"  !CDS_PN = "1";
"B":   PN = "2"  !CDS_PN = "2";
BODY = "RES","I6": #LOCATION = "R9M18" !CDS_LOCATION = "R9M18" #SEC = "1" !CDS_SEC = "1";
"A":   PN = "1"  !CDS_PN = "1";
"B":   PN = "2"  !CDS_PN = "2";
BODY = "RES","I7": #LOCATION = "R9M19" !CDS_LOCATION = "R9M19" #SEC = "1" !CDS_SEC = "1";
"A":   PN = "1"  !CDS_PN = "1";
"B":   PN = "2"  !CDS_PN = "2";
BODY = "CAP_A","I10": #LOCATION = "C9M8" !CDS_LOCATION = "C9M8" #SEC = "1" !CDS_SEC = "1";
"A":   PN = "1"  !CDS_PN = "1";
"B":   PN = "2"  !CDS_PN = "2";
BODY = "CAP_A","I12": #LOCATION = "C9M7" !CDS_LOCATION = "C9M7" #SEC = "1" !CDS_SEC = "1";
"A":   PN = "1"  !CDS_PN = "1";
"B":   PN = "2"  !CDS_PN = "2";
BODY = "RES","I15": #LOCATION = "R9M17" !CDS_LOCATION = "R9M17" #SEC = "1" !CDS_SEC = "1";
"A":   PN = "1"  !CDS_PN = "1";
"B":   PN = "2"  !CDS_PN = "2";
BODY = "RES","I16": #LOCATION = "R9M16" !CDS_LOCATION = "R9M16" #SEC = "1" !CDS_SEC = "1";
"A":   PN = "1"  !CDS_PN = "1";
"B":   PN = "2"  !CDS_PN = "2";
BODY = "RES","I20": #LOCATION = "R9M14" !CDS_LOCATION = "R9M14" &SEC = "1" #&CDS_SEC = "1";
"A":   PN = "1"  !CDS_PN = "1";
"B":   PN = "2"  !CDS_PN = "2";
BODY = "RES","I21": #LOCATION = "R9M13" !CDS_LOCATION = "R9M13" &SEC = "1" #&CDS_SEC = "1";
"A":   PN = "1"  !CDS_PN = "1";
"B":   PN = "2"  !CDS_PN = "2";
BODY = "RES","I24": #LOCATION = "R9M12" !CDS_LOCATION = "R9M12" &SEC = "1" #&CDS_SEC = "1";
"A":   PN = "1"  !CDS_PN = "1";
"B":   PN = "2"  !CDS_PN = "2";
BODY = "RES","I25": #LOCATION = "R9M15" !CDS_LOCATION = "R9M15" &SEC = "1" #&CDS_SEC = "1";
"A":   PN = "1"  !CDS_PN = "1";
"B":   PN = "2"  !CDS_PN = "2";
DRAWING = "@baseboard_fab2_lib.baseboard_fab2(sch_1):page164";
BODY = "RES","I5": #LOCATION = "R1T10" !CDS_LOCATION = "R1T10" #SEC = "1" !CDS_SEC = "1";
"A":   PN = "1"  !CDS_PN = "1";
"B":   PN = "2"  !CDS_PN = "2";
BODY = "RES","I6": #LOCATION = "R1T12" !CDS_LOCATION = "R1T12" #SEC = "1" !CDS_SEC = "1";
"A":   PN = "1"  !CDS_PN = "1";
"B":   PN = "2"  !CDS_PN = "2";
BODY = "RES","I7": #LOCATION = "R1T11" !CDS_LOCATION = "R1T11" #SEC = "1" !CDS_SEC = "1";
"A":   PN = "1"  !CDS_PN = "1";
"B":   PN = "2"  !CDS_PN = "2";
BODY = "RES","I11": #LOCATION = "R1T5" !CDS_LOCATION = "R1T5" #SEC = "1" !CDS_SEC = "1";
"A":   PN = "1"  !CDS_PN = "1";
"B":   PN = "2"  !CDS_PN = "2";
BODY = "RES","I13": #LOCATION = "R1T6" !CDS_LOCATION = "R1T6" #SEC = "1" !CDS_SEC = "1";
"A":   PN = "1"  !CDS_PN = "1";
"B":   PN = "2"  !CDS_PN = "2";
BODY = "RES","I14": #LOCATION = "R1T4" !CDS_LOCATION = "R1T4" #SEC = "1" !CDS_SEC = "1";
"A":   PN = "1"  !CDS_PN = "1";
"B":   PN = "2"  !CDS_PN = "2";
BODY = "RES","I19": #LOCATION = "R1U18" !CDS_LOCATION = "R1U18" #SEC = "1" !CDS_SEC = "1";
"A":   PN = "1"  !CDS_PN = "1";
"B":   PN = "2"  !CDS_PN = "2";
BODY = "RES","I20": #LOCATION = "R1U16" !CDS_LOCATION = "R1U16" #SEC = "1" !CDS_SEC = "1";
"A":   PN = "1"  !CDS_PN = "1";
"B":   PN = "2"  !CDS_PN = "2";
BODY = "RES","I21": #LOCATION = "R1U17" !CDS_LOCATION = "R1U17" #SEC = "1" !CDS_SEC = "1";
"A":   PN = "1"  !CDS_PN = "1";
"B":   PN = "2"  !CDS_PN = "2";
BODY = "RES","I22": #LOCATION = "R1U15" !CDS_LOCATION = "R1U15" #SEC = "1" !CDS_SEC = "1";
"A":   PN = "1"  !CDS_PN = "1";
"B":   PN = "2"  !CDS_PN = "2";
BODY = "RES","I24": #LOCATION = "R1U21" !CDS_LOCATION = "R1U21" #SEC = "1" !CDS_SEC = "1";
"A":   PN = "1"  !CDS_PN = "1";
"B":   PN = "2"  !CDS_PN = "2";
BODY = "RES","I25": #LOCATION = "R1U24" !CDS_LOCATION = "R1U24" #SEC = "1" !CDS_SEC = "1";
"A":   PN = "1"  !CDS_PN = "1";
"B":   PN = "2"  !CDS_PN = "2";
BODY = "RES","I27": #LOCATION = "R1U22" !CDS_LOCATION = "R1U22" #SEC = "1" !CDS_SEC = "1";
"A":   PN = "1"  !CDS_PN = "1";
"B":   PN = "2"  !CDS_PN = "2";
BODY = "RES","I28": #LOCATION = "R1U23" !CDS_LOCATION = "R1U23" #SEC = "1" !CDS_SEC = "1";
"A":   PN = "1"  !CDS_PN = "1";
"B":   PN = "2"  !CDS_PN = "2";
BODY = "RES","I29": #LOCATION = "R2N17" !CDS_LOCATION = "R2N17" &SEC = "1" #&CDS_SEC = "1";
"A":   PN = "1"  !CDS_PN = "1";
"B":   PN = "2"  !CDS_PN = "2";
BODY = "RES","I32": #LOCATION = "R2N18" !CDS_LOCATION = "R2N18" &SEC = "1" #&CDS_SEC = "1";
"A":   PN = "1"  !CDS_PN = "1";
"B":   PN = "2"  !CDS_PN = "2";
DRAWING = "@baseboard_fab2_lib.baseboard_fab2(sch_1):page165";
BODY = "ADC128D818","I52": #LOCATION = "EU9G1" !CDS_LOCATION = "EU9G1" #SEC = "1" !CDS_SEC = "1";
"A0":   PN = "7"  !CDS_PN = "7";
"A1":   PN = "8"  !CDS_PN = "8";
"GND":   PN = "4"  !CDS_PN = "4";
"IN0":   PN = "16"  !CDS_PN = "16";
"IN1":   PN = "15"  !CDS_PN = "15";
"IN2":   PN = "14"  !CDS_PN = "14";
"IN3":   PN = "13"  !CDS_PN = "13";
"IN4":   PN = "12"  !CDS_PN = "12";
"IN5":   PN = "11"  !CDS_PN = "11";
"IN6":   PN = "10"  !CDS_PN = "10";
"IN7":   PN = "9"  !CDS_PN = "9";
"INT_N":   PN = "6"  !CDS_PN = "6";
"SCL":   PN = "3"  !CDS_PN = "3";
"SDA":   PN = "2"  !CDS_PN = "2";
"VP":   PN = "5"  !CDS_PN = "5";
"VREF":   PN = "1"  !CDS_PN = "1";
BODY = "RES","I55": #LOCATION = "R1U45" !CDS_LOCATION = "R1U45" &SEC = "1" #&CDS_SEC = "1";
"A":   PN = "1"  !CDS_PN = "1";
"B":   PN = "2"  !CDS_PN = "2";
BODY = "RES","I56": #LOCATION = "R1U48" !CDS_LOCATION = "R1U48" &SEC = "1" #&CDS_SEC = "1";
"A":   PN = "1"  !CDS_PN = "1";
"B":   PN = "2"  !CDS_PN = "2";
BODY = "RES","I57": #LOCATION = "R9G23" !CDS_LOCATION = "R9G23" &SEC = "1" #&CDS_SEC = "1";
"A":   PN = "1"  !CDS_PN = "1";
"B":   PN = "2"  !CDS_PN = "2";
BODY = "RES","I58": #LOCATION = "R9G25" !CDS_LOCATION = "R9G25" &SEC = "1" #&CDS_SEC = "1";
"A":   PN = "1"  !CDS_PN = "1";
"B":   PN = "2"  !CDS_PN = "2";
BODY = "CAP_A","I61": #LOCATION = "C9G19" !CDS_LOCATION = "C9G19" &SEC = "1" #&CDS_SEC = "1";
"A":   PN = "1"  !CDS_PN = "1";
"B":   PN = "2"  !CDS_PN = "2";
BODY = "CAP","I67": #LOCATION = "C1U20" !CDS_LOCATION = "C1U20" &SEC = "1" #&CDS_SEC = "1";
"A":   PN = "1"  !CDS_PN = "1";
"B":   PN = "2"  !CDS_PN = "2";
BODY = "RES","I69": #LOCATION = "R9G21" !CDS_LOCATION = "R9G21" #SEC = "1" !CDS_SEC = "1";
"A":   PN = "1"  !CDS_PN = "1";
"B":   PN = "2"  !CDS_PN = "2";
BODY = "FERRITE","I79": #LOCATION = "FB1U2" !CDS_LOCATION = "FB1U2" #SEC = "1" !CDS_SEC = "1";
"A":   PN = "1"  !CDS_PN = "1";
"B":   PN = "2"  !CDS_PN = "2";
BODY = "RES","I81": #LOCATION = "R1U40" !CDS_LOCATION = "R1U40" #SEC = "1" !CDS_SEC = "1";
"A":   PN = "1"  !CDS_PN = "1";
"B":   PN = "2"  !CDS_PN = "2";
DRAWING = "@baseboard_fab2_lib.baseboard_fab2(sch_1):page166";
BODY = "RES","I11": #LOCATION = "R7C18" !CDS_LOCATION = "R7C18" #SEC = "1" !CDS_SEC = "1";
"A":   PN = "1"  !CDS_PN = "1";
"B":   PN = "2"  !CDS_PN = "2";
BODY = "RES","I14": #LOCATION = "R7C22" !CDS_LOCATION = "R7C22" #SEC = "1" !CDS_SEC = "1";
"A":   PN = "1"  !CDS_PN = "1";
"B":   PN = "2"  !CDS_PN = "2";
BODY = "RES","I15": #LOCATION = "R7C19" !CDS_LOCATION = "R7C19" #SEC = "1" !CDS_SEC = "1";
"A":   PN = "1"  !CDS_PN = "1";
"B":   PN = "2"  !CDS_PN = "2";
BODY = "RES","I28": #LOCATION = "R7C17" !CDS_LOCATION = "R7C17" #SEC = "1" !CDS_SEC = "1";
"A":   PN = "1"  !CDS_PN = "1";
"B":   PN = "2"  !CDS_PN = "2";
BODY = "RES","I32": #LOCATION = "R7D15" !CDS_LOCATION = "R7D15" #SEC = "1" !CDS_SEC = "1";
"A":   PN = "1"  !CDS_PN = "1";
"B":   PN = "2"  !CDS_PN = "2";
DRAWING = "@baseboard_fab2_lib.baseboard_fab2(sch_1):page167";
BODY = "TMP421","I1": #LOCATION = "U9B4" !CDS_LOCATION = "U9B4" #SEC = "1" !CDS_SEC = "1";
"A<0>":   PN = "4"  !CDS_PN = "4";
"A<1>":   PN = "3"  !CDS_PN = "3";
"DXN":   PN = "2"  !CDS_PN = "2";
"DXP":   PN = "1"  !CDS_PN = "1";
"GND":   PN = "5"  !CDS_PN = "5";
"SCL":   PN = "7"  !CDS_PN = "7";
"SDA":   PN = "6"  !CDS_PN = "6";
"VP":   PN = "8"  !CDS_PN = "8";
BODY = "PNP","I3": #LOCATION = "Q9B1" !CDS_LOCATION = "Q9B1" #SEC = "1" !CDS_SEC = "1";
"B":   PN = "1"  !CDS_PN = "1";
"C":   PN = "3"  !CDS_PN = "3";
"E":   PN = "2"  !CDS_PN = "2";
BODY = "RES","I5": #LOCATION = "R9B5" !CDS_LOCATION = "R9B5" #SEC = "1" !CDS_SEC = "1";
"A":   PN = "1"  !CDS_PN = "1";
"B":   PN = "2"  !CDS_PN = "2";
BODY = "RES","I6": #LOCATION = "R9B4" !CDS_LOCATION = "R9B4" #SEC = "1" !CDS_SEC = "1";
"A":   PN = "1"  !CDS_PN = "1";
"B":   PN = "2"  !CDS_PN = "2";
BODY = "CAP","I7": #LOCATION = "C1M4" !CDS_LOCATION = "C1M4" #SEC = "1" !CDS_SEC = "1";
"A":   PN = "1"  !CDS_PN = "1";
"B":   PN = "2"  !CDS_PN = "2";
BODY = "RES","I8": #LOCATION = "R1M9" !CDS_LOCATION = "R1M9" #SEC = "1" !CDS_SEC = "1";
"A":   PN = "1"  !CDS_PN = "1";
"B":   PN = "2"  !CDS_PN = "2";
BODY = "RES","I10": #LOCATION = "R9B8" !CDS_LOCATION = "R9B8" #SEC = "1" !CDS_SEC = "1";
"A":   PN = "1"  !CDS_PN = "1";
"B":   PN = "2"  !CDS_PN = "2";
BODY = "CAP","I24": #LOCATION = "C1E19" !CDS_LOCATION = "C1E19" #SEC = "1" !CDS_SEC = "1";
"A":   PN = "1"  !CDS_PN = "1";
"B":   PN = "2"  !CDS_PN = "2";
BODY = "RES","I25": #LOCATION = "R9R5" !CDS_LOCATION = "R9R5" #SEC = "1" !CDS_SEC = "1";
"A":   PN = "1"  !CDS_PN = "1";
"B":   PN = "2"  !CDS_PN = "2";
BODY = "RES","I26": #LOCATION = "R9R6" !CDS_LOCATION = "R9R6" #SEC = "1" !CDS_SEC = "1";
"A":   PN = "1"  !CDS_PN = "1";
"B":   PN = "2"  !CDS_PN = "2";
BODY = "PNP","I27": #LOCATION = "Q1E1" !CDS_LOCATION = "Q1E1" #SEC = "1" !CDS_SEC = "1";
"B":   PN = "1"  !CDS_PN = "1";
"C":   PN = "3"  !CDS_PN = "3";
"E":   PN = "2"  !CDS_PN = "2";
BODY = "TMP421","I30": #LOCATION = "U1E1" !CDS_LOCATION = "U1E1" #SEC = "1" !CDS_SEC = "1";
"A<0>":   PN = "4"  !CDS_PN = "4";
"A<1>":   PN = "3"  !CDS_PN = "3";
"DXN":   PN = "2"  !CDS_PN = "2";
"DXP":   PN = "1"  !CDS_PN = "1";
"GND":   PN = "5"  !CDS_PN = "5";
"SCL":   PN = "7"  !CDS_PN = "7";
"SDA":   PN = "6"  !CDS_PN = "6";
"VP":   PN = "8"  !CDS_PN = "8";
BODY = "RES","I34": #LOCATION = "R1E9" !CDS_LOCATION = "R1E9" #SEC = "1" !CDS_SEC = "1";
"A":   PN = "1"  !CDS_PN = "1";
"B":   PN = "2"  !CDS_PN = "2";
BODY = "RES","I35": #LOCATION = "R9B6" !CDS_LOCATION = "R9B6" #SEC = "1" !CDS_SEC = "1";
"A":   PN = "1"  !CDS_PN = "1";
"B":   PN = "2"  !CDS_PN = "2";
BODY = "RES","I38": #LOCATION = "R1E10" !CDS_LOCATION = "R1E10" #SEC = "1" !CDS_SEC = "1";
"A":   PN = "1"  !CDS_PN = "1";
"B":   PN = "2"  !CDS_PN = "2";
BODY = "CAP_A","I39": #LOCATION = "C9B7" !CDS_LOCATION = "C9B7" #SEC = "1" !CDS_SEC = "1";
"A":   PN = "1"  !CDS_PN = "1";
"B":   PN = "2"  !CDS_PN = "2";
BODY = "CAP_A","I41": #LOCATION = "C9R14" !CDS_LOCATION = "C9R14" #SEC = "1" !CDS_SEC = "1";
"A":   PN = "1"  !CDS_PN = "1";
"B":   PN = "2"  !CDS_PN = "2";
BODY = "CAP_A","I42": #LOCATION = "C9R13" !CDS_LOCATION = "C9R13" #SEC = "1" !CDS_SEC = "1";
"A":   PN = "1"  !CDS_PN = "1";
"B":   PN = "2"  !CDS_PN = "2";
BODY = "AT24C64","I49": #LOCATION = "U8D4" !CDS_LOCATION = "U8D4" #SEC = "1" !CDS_SEC = "1";
"A0":   PN = "1"  !CDS_PN = "1";
"A1":   PN = "2"  !CDS_PN = "2";
"A2":   PN = "3"  !CDS_PN = "3";
"SCL":   PN = "6"  !CDS_PN = "6";
"SDA":   PN = "5"  !CDS_PN = "5";
"WP":   PN = "7"  !CDS_PN = "7";
BODY = "RES","I50": #LOCATION = "R8D27" !CDS_LOCATION = "R8D27" #SEC = "1" !CDS_SEC = "1";
"A":   PN = "1"  !CDS_PN = "1";
"B":   PN = "2"  !CDS_PN = "2";
BODY = "RES","I58": #LOCATION = "R9G15" !CDS_LOCATION = "R9G15" &SEC = "1" #&CDS_SEC = "1";
"A":   PN = "1"  !CDS_PN = "1";
"B":   PN = "2"  !CDS_PN = "2";
BODY = "RES","I70": #LOCATION = "R8D28" !CDS_LOCATION = "R8D28" #SEC = "1" !CDS_SEC = "1";
"A":   PN = "1"  !CDS_PN = "1";
"B":   PN = "2"  !CDS_PN = "2";
BODY = "RES","I74": #LOCATION = "R1M8" !CDS_LOCATION = "R1M8" #SEC = "1" !CDS_SEC = "1";
"A":   PN = "1"  !CDS_PN = "1";
"B":   PN = "2"  !CDS_PN = "2";
BODY = "RES","I75": #LOCATION = "R9R7" !CDS_LOCATION = "R9R7" #SEC = "1" !CDS_SEC = "1";
"A":   PN = "1"  !CDS_PN = "1";
"B":   PN = "2"  !CDS_PN = "2";
BODY = "RES","I76": #LOCATION = "R9R8" !CDS_LOCATION = "R9R8" #SEC = "1" !CDS_SEC = "1";
"A":   PN = "1"  !CDS_PN = "1";
"B":   PN = "2"  !CDS_PN = "2";
BODY = "RES","I77": #LOCATION = "R9G14" !CDS_LOCATION = "R9G14" &SEC = "1" #&CDS_SEC = "1";
"A":   PN = "1"  !CDS_PN = "1";
"B":   PN = "2"  !CDS_PN = "2";
BODY = "RES","I78": #LOCATION = "R1U31" !CDS_LOCATION = "R1U31" &SEC = "1" #&CDS_SEC = "1";
"A":   PN = "1"  !CDS_PN = "1";
"B":   PN = "2"  !CDS_PN = "2";
BODY = "RES","I79": #LOCATION = "R1U25" !CDS_LOCATION = "R1U25" &SEC = "1" #&CDS_SEC = "1";
"A":   PN = "1"  !CDS_PN = "1";
"B":   PN = "2"  !CDS_PN = "2";
BODY = "RES","I80": #LOCATION = "R2U38" !CDS_LOCATION = "R2U38" #SEC = "1" !CDS_SEC = "1";
"A":   PN = "1"  !CDS_PN = "1";
"B":   PN = "2"  !CDS_PN = "2";
BODY = "RES","I83": #LOCATION = "R2U39" !CDS_LOCATION = "R2U39" #SEC = "1" !CDS_SEC = "1";
"A":   PN = "1"  !CDS_PN = "1";
"B":   PN = "2"  !CDS_PN = "2";
BODY = "RES","I84": #LOCATION = "R8D24" !CDS_LOCATION = "R8D24" #SEC = "1" !CDS_SEC = "1";
"A":   PN = "1"  !CDS_PN = "1";
"B":   PN = "2"  !CDS_PN = "2";
BODY = "RES","I85": #LOCATION = "R8D23" !CDS_LOCATION = "R8D23" &SEC = "1" #&CDS_SEC = "1";
"A":   PN = "1"  !CDS_PN = "1";
"B":   PN = "2"  !CDS_PN = "2";
DRAWING = "@baseboard_fab2_lib.baseboard_fab2(sch_1):page168";
BODY = "DIODE","I2": #LOCATION = "CR1L1" !CDS_LOCATION = "CR1L1" #SEC = "1" !CDS_SEC = "1";
"A":   PN = "2"  !CDS_PN = "2";
"C":   PN = "1"  !CDS_PN = "1";
BODY = "DIODE","I3": #LOCATION = "CR1L2" !CDS_LOCATION = "CR1L2" #SEC = "1" !CDS_SEC = "1";
"A":   PN = "2"  !CDS_PN = "2";
"C":   PN = "1"  !CDS_PN = "1";
BODY = "DIODE","I4": #LOCATION = "CR1L3" !CDS_LOCATION = "CR1L3" #SEC = "1" !CDS_SEC = "1";
"A":   PN = "2"  !CDS_PN = "2";
"C":   PN = "1"  !CDS_PN = "1";
BODY = "DIODE","I5": #LOCATION = "CR1L4" !CDS_LOCATION = "CR1L4" #SEC = "1" !CDS_SEC = "1";
"A":   PN = "2"  !CDS_PN = "2";
"C":   PN = "1"  !CDS_PN = "1";
BODY = "RES","I6": #LOCATION = "R1L6" !CDS_LOCATION = "R1L6" #SEC = "1" !CDS_SEC = "1";
"A":   PN = "1"  !CDS_PN = "1";
"B":   PN = "2"  !CDS_PN = "2";
BODY = "NPN","I8": #LOCATION = "Q1L3" !CDS_LOCATION = "Q1L3" #SEC = "1" !CDS_SEC = "1";
"B":   PN = "1"  !CDS_PN = "1";
"C":   PN = "3"  !CDS_PN = "3";
"E":   PN = "2"  !CDS_PN = "2";
BODY = "RES","I11": #LOCATION = "R1L36" !CDS_LOCATION = "R1L36" #SEC = "1" !CDS_SEC = "1";
"A":   PN = "1"  !CDS_PN = "1";
"B":   PN = "2"  !CDS_PN = "2";
BODY = "FET_N_DUAL","I18": #LOCATION = "Q1L4" !CDS_LOCATION = "Q1L4" #SEC = "2" !CDS_SEC = "2";
"DRAIN<0>":   PN = "3"  !CDS_PN = "3";
"GATE<0>":   PN = "5"  !CDS_PN = "5";
"SOURCE<0>":   PN = "4"  !CDS_PN = "4";
BODY = "FET_N_DUAL","I19": #LOCATION = "Q1L4" !CDS_LOCATION = "Q1L4" #SEC = "1" !CDS_SEC = "1";
"DRAIN<0>":   PN = "6"  !CDS_PN = "6";
"GATE<0>":   PN = "2"  !CDS_PN = "2";
"SOURCE<0>":   PN = "1"  !CDS_PN = "1";
BODY = "RES","I22": #LOCATION = "R1L38" !CDS_LOCATION = "R1L38" #SEC = "1" !CDS_SEC = "1";
"A":   PN = "1"  !CDS_PN = "1";
"B":   PN = "2"  !CDS_PN = "2";
BODY = "FET_N_DUAL","I30": #LOCATION = "Q6W2" !CDS_LOCATION = "Q6W2" &SEC = "1" #&CDS_SEC = "1";
"DRAIN<0>":   PN = "6"  !CDS_PN = "6";
"GATE<0>":   PN = "2"  !CDS_PN = "2";
"SOURCE<0>":   PN = "1"  !CDS_PN = "1";
BODY = "RES","I33": #LOCATION = "R6W14" !CDS_LOCATION = "R6W14" &SEC = "1" #&CDS_SEC = "1";
"A":   PN = "1"  !CDS_PN = "1";
"B":   PN = "2"  !CDS_PN = "2";
BODY = "RES","I34": #LOCATION = "R6W13" !CDS_LOCATION = "R6W13" &SEC = "1" #&CDS_SEC = "1";
"A":   PN = "1"  !CDS_PN = "1";
"B":   PN = "2"  !CDS_PN = "2";
BODY = "NPN","I37": #LOCATION = "Q6W3" !CDS_LOCATION = "Q6W3" #SEC = "1" !CDS_SEC = "1";
"B":   PN = "1"  !CDS_PN = "1";
"C":   PN = "3"  !CDS_PN = "3";
"E":   PN = "2"  !CDS_PN = "2";
BODY = "RES","I39": #LOCATION = "R6W16" !CDS_LOCATION = "R6W16" &SEC = "1" #&CDS_SEC = "1";
"A":   PN = "1"  !CDS_PN = "1";
"B":   PN = "2"  !CDS_PN = "2";
BODY = "RES","I40": #LOCATION = "R6W15" !CDS_LOCATION = "R6W15" &SEC = "1" #&CDS_SEC = "1";
"A":   PN = "1"  !CDS_PN = "1";
"B":   PN = "2"  !CDS_PN = "2";
DRAWING = "@baseboard_fab2_lib.baseboard_fab2(sch_1):page169";
BODY = "CAP","I56": #LOCATION = "C1U21" !CDS_LOCATION = "C1U21" #SEC = "1" !CDS_SEC = "1";
"A":   PN = "1"  !CDS_PN = "1";
"B":   PN = "2"  !CDS_PN = "2";
BODY = "FERRITE","I57": #LOCATION = "FB1U3" !CDS_LOCATION = "FB1U3" #SEC = "1" !CDS_SEC = "1";
"A":   PN = "1"  !CDS_PN = "1";
"B":   PN = "2"  !CDS_PN = "2";
BODY = "CAP","I68": #LOCATION = "C9G21" !CDS_LOCATION = "C9G21" #SEC = "1" !CDS_SEC = "1";
"A":   PN = "1"  !CDS_PN = "1";
"B":   PN = "2"  !CDS_PN = "2";
BODY = "CAP","I80": #LOCATION = "C9G17" !CDS_LOCATION = "C9G17" #SEC = "1" !CDS_SEC = "1";
"A":   PN = "1"  !CDS_PN = "1";
"B":   PN = "2"  !CDS_PN = "2";
BODY = "RES","I82": #LOCATION = "R1U32" !CDS_LOCATION = "R1U32" #SEC = "1" !CDS_SEC = "1";
"A":   PN = "1"  !CDS_PN = "1";
"B":   PN = "2"  !CDS_PN = "2";
BODY = "RES","I83": #LOCATION = "R1U33" !CDS_LOCATION = "R1U33" #SEC = "1" !CDS_SEC = "1";
"A":   PN = "1"  !CDS_PN = "1";
"B":   PN = "2"  !CDS_PN = "2";
BODY = "CAP","I86": #LOCATION = "C9G20" !CDS_LOCATION = "C9G20" #SEC = "1" !CDS_SEC = "1";
"A":   PN = "1"  !CDS_PN = "1";
"B":   PN = "2"  !CDS_PN = "2";
BODY = "RES","I88": #LOCATION = "R1U39" !CDS_LOCATION = "R1U39" #SEC = "1" !CDS_SEC = "1";
"A":   PN = "1"  !CDS_PN = "1";
"B":   PN = "2"  !CDS_PN = "2";
BODY = "RES","I106": #LOCATION = "R9G26" !CDS_LOCATION = "R9G26" #SEC = "1" !CDS_SEC = "1";
"A":   PN = "1"  !CDS_PN = "1";
"B":   PN = "2"  !CDS_PN = "2";
BODY = "CAP","I108": #LOCATION = "C9G22" !CDS_LOCATION = "C9G22" #SEC = "1" !CDS_SEC = "1";
"A":   PN = "1"  !CDS_PN = "1";
"B":   PN = "2"  !CDS_PN = "2";
BODY = "RES","I114": #LOCATION = "R1U38" !CDS_LOCATION = "R1U38" #SEC = "1" !CDS_SEC = "1";
"A":   PN = "1"  !CDS_PN = "1";
"B":   PN = "2"  !CDS_PN = "2";
BODY = "RES","I115": #LOCATION = "R1U47" !CDS_LOCATION = "R1U47" #SEC = "1" !CDS_SEC = "1";
"A":   PN = "1"  !CDS_PN = "1";
"B":   PN = "2"  !CDS_PN = "2";
BODY = "RES","I116": #LOCATION = "R1U44" !CDS_LOCATION = "R1U44" &SEC = "1" #&CDS_SEC = "1";
"A":   PN = "1"  !CDS_PN = "1";
"B":   PN = "2"  !CDS_PN = "2";
BODY = "RES","I126": #LOCATION = "R1U50" !CDS_LOCATION = "R1U50" #SEC = "1" !CDS_SEC = "1";
"A":   PN = "1"  !CDS_PN = "1";
"B":   PN = "2"  !CDS_PN = "2";
BODY = "CAP","I139": #LOCATION = "C9G15" !CDS_LOCATION = "C9G15" #SEC = "1" !CDS_SEC = "1";
"A":   PN = "1"  !CDS_PN = "1";
"B":   PN = "2"  !CDS_PN = "2";
BODY = "RES","I141": #LOCATION = "R1U29" !CDS_LOCATION = "R1U29" #SEC = "1" !CDS_SEC = "1";
"A":   PN = "1"  !CDS_PN = "1";
"B":   PN = "2"  !CDS_PN = "2";
BODY = "RES","I142": #LOCATION = "R1U28" !CDS_LOCATION = "R1U28" #SEC = "1" !CDS_SEC = "1";
"A":   PN = "1"  !CDS_PN = "1";
"B":   PN = "2"  !CDS_PN = "2";
BODY = "CAP","I146": #LOCATION = "C9G14" !CDS_LOCATION = "C9G14" #SEC = "1" !CDS_SEC = "1";
"A":   PN = "1"  !CDS_PN = "1";
"B":   PN = "2"  !CDS_PN = "2";
BODY = "RES","I148": #LOCATION = "R1U26" !CDS_LOCATION = "R1U26" #SEC = "1" !CDS_SEC = "1";
"A":   PN = "1"  !CDS_PN = "1";
"B":   PN = "2"  !CDS_PN = "2";
BODY = "RES","I149": #LOCATION = "R1U27" !CDS_LOCATION = "R1U27" #SEC = "1" !CDS_SEC = "1";
"A":   PN = "1"  !CDS_PN = "1";
"B":   PN = "2"  !CDS_PN = "2";
BODY = "CAP","I153": #LOCATION = "C9G18" !CDS_LOCATION = "C9G18" #SEC = "1" !CDS_SEC = "1";
"A":   PN = "1"  !CDS_PN = "1";
"B":   PN = "2"  !CDS_PN = "2";
BODY = "FERRITE","I155": #LOCATION = "FB1U4" !CDS_LOCATION = "FB1U4" #SEC = "1" !CDS_SEC = "1";
"A":   PN = "1"  !CDS_PN = "1";
"B":   PN = "2"  !CDS_PN = "2";
BODY = "FET_N_DUAL","I157": #LOCATION = "Q9G1" !CDS_LOCATION = "Q9G1" #SEC = "2" !CDS_SEC = "2";
"DRAIN<0>":   PN = "3"  !CDS_PN = "3";
"GATE<0>":   PN = "5"  !CDS_PN = "5";
"SOURCE<0>":   PN = "4"  !CDS_PN = "4";
BODY = "FET_N_DUAL","I162": #LOCATION = "Q9G1" !CDS_LOCATION = "Q9G1" #SEC = "1" !CDS_SEC = "1";
"DRAIN<0>":   PN = "6"  !CDS_PN = "6";
"GATE<0>":   PN = "2"  !CDS_PN = "2";
"SOURCE<0>":   PN = "1"  !CDS_PN = "1";
BODY = "RES","I163": #LOCATION = "R1U49" !CDS_LOCATION = "R1U49" #SEC = "1" !CDS_SEC = "1";
"A":   PN = "1"  !CDS_PN = "1";
"B":   PN = "2"  !CDS_PN = "2";
BODY = "RES","I164": #LOCATION = "R9G35" !CDS_LOCATION = "R9G35" #SEC = "1" !CDS_SEC = "1";
"A":   PN = "1"  !CDS_PN = "1";
"B":   PN = "2"  !CDS_PN = "2";
DRAWING = "@baseboard_fab2_lib.baseboard_fab2(sch_1):page170";
BODY = "RES","I2": #LOCATION = "R2P3" !CDS_LOCATION = "R2P3" #SEC = "1" !CDS_SEC = "1";
"A":   PN = "1"  !CDS_PN = "1";
"B":   PN = "2"  !CDS_PN = "2";
BODY = "TTL1G07_A","I4": #LOCATION = "U8D3" !CDS_LOCATION = "U8D3" &SEC = "1" #&CDS_SEC = "1";
"A":   PN = "2"  !CDS_PN = "2";
"Y":   PN = "4"  !CDS_PN = "4";
BODY = "CAP_A","I8": #LOCATION = "C2P1" !CDS_LOCATION = "C2P1" #SEC = "1" !CDS_SEC = "1";
"A":   PN = "1"  !CDS_PN = "1";
"B":   PN = "2"  !CDS_PN = "2";
BODY = "TTL08","I10": #LOCATION = "U8E1" !CDS_LOCATION = "U8E1" #SEC = "4" !CDS_SEC = "4";
"A<0>":   PN = "1"  !CDS_PN = "1";
"B<0>":   PN = "2"  !CDS_PN = "2";
"Y<0>":   PN = "3"  !CDS_PN = "3";
BODY = "TTL08","I11": #LOCATION = "U8E1" !CDS_LOCATION = "U8E1" #SEC = "3" !CDS_SEC = "3";
"A<0>":   PN = "4"  !CDS_PN = "4";
"B<0>":   PN = "5"  !CDS_PN = "5";
"Y<0>":   PN = "6"  !CDS_PN = "6";
BODY = "TTL08","I12": #LOCATION = "U8E1" !CDS_LOCATION = "U8E1" #SEC = "1" !CDS_SEC = "1";
"A<0>":   PN = "12"  !CDS_PN = "12";
"B<0>":   PN = "13"  !CDS_PN = "13";
"Y<0>":   PN = "11"  !CDS_PN = "11";
BODY = "TTL1G126_A","I20": #LOCATION = "U1R2" !CDS_LOCATION = "U1R2" #SEC = "1" !CDS_SEC = "1";
"A":   PN = "2"  !CDS_PN = "2";
"OE":   PN = "1"  !CDS_PN = "1";
"Y":   PN = "4"  !CDS_PN = "4";
BODY = "CAP_A","I30": #LOCATION = "C1R27" !CDS_LOCATION = "C1R27" #SEC = "1" !CDS_SEC = "1";
"A":   PN = "1"  !CDS_PN = "1";
"B":   PN = "2"  !CDS_PN = "2";
BODY = "CAP_A","I33": #LOCATION = "C8D2" !CDS_LOCATION = "C8D2" #SEC = "1" !CDS_SEC = "1";
"A":   PN = "1"  !CDS_PN = "1";
"B":   PN = "2"  !CDS_PN = "2";
BODY = "TTL1G126_A","I38": #LOCATION = "U8D5" !CDS_LOCATION = "U8D5" #SEC = "1" !CDS_SEC = "1";
"A":   PN = "2"  !CDS_PN = "2";
"OE":   PN = "1"  !CDS_PN = "1";
"Y":   PN = "4"  !CDS_PN = "4";
BODY = "CAP_A","I40": #LOCATION = "C8E2" !CDS_LOCATION = "C8E2" #SEC = "1" !CDS_SEC = "1";
"A":   PN = "1"  !CDS_PN = "1";
"B":   PN = "2"  !CDS_PN = "2";
BODY = "CAP","I42": #LOCATION = "C8D3" !CDS_LOCATION = "C8D3" #SEC = "1" !CDS_SEC = "1";
"A":   PN = "1"  !CDS_PN = "1";
"B":   PN = "2"  !CDS_PN = "2";
BODY = "TTL1G07_A","I46": #LOCATION = "U1R1" !CDS_LOCATION = "U1R1" #SEC = "1" !CDS_SEC = "1";
"A":   PN = "2"  !CDS_PN = "2";
"Y":   PN = "4"  !CDS_PN = "4";
BODY = "CAP_A","I49": #LOCATION = "C1R28" !CDS_LOCATION = "C1R28" #SEC = "1" !CDS_SEC = "1";
"A":   PN = "1"  !CDS_PN = "1";
"B":   PN = "2"  !CDS_PN = "2";
BODY = "RES","I51": #LOCATION = "R1R8" !CDS_LOCATION = "R1R8" #SEC = "1" !CDS_SEC = "1";
"A":   PN = "1"  !CDS_PN = "1";
"B":   PN = "2"  !CDS_PN = "2";
BODY = "RES","I52": #LOCATION = "R2P8" !CDS_LOCATION = "R2P8" #SEC = "1" !CDS_SEC = "1";
"A":   PN = "1"  !CDS_PN = "1";
"B":   PN = "2"  !CDS_PN = "2";
BODY = "RES","I54": #LOCATION = "R2T3" !CDS_LOCATION = "R2T3" #SEC = "1" !CDS_SEC = "1";
"A":   PN = "1"  !CDS_PN = "1";
"B":   PN = "2"  !CDS_PN = "2";
BODY = "RES","I56": #LOCATION = "R2P5" !CDS_LOCATION = "R2P5" #SEC = "1" !CDS_SEC = "1";
"A":   PN = "1"  !CDS_PN = "1";
"B":   PN = "2"  !CDS_PN = "2";
BODY = "FET_N","I58": #LOCATION = "Q2P1" !CDS_LOCATION = "Q2P1" #SEC = "1" !CDS_SEC = "1";
"DRN":   PN = "3"  !CDS_PN = "3";
"GATE":   PN = "1"  !CDS_PN = "1";
"SRC":   PN = "2"  !CDS_PN = "2";
BODY = "RES","I61": #LOCATION = "R2P13" !CDS_LOCATION = "R2P13" #SEC = "1" !CDS_SEC = "1";
"A":   PN = "1"  !CDS_PN = "1";
"B":   PN = "2"  !CDS_PN = "2";
BODY = "RES","I63": #LOCATION = "R2P11" !CDS_LOCATION = "R2P11" &SEC = "1" #&CDS_SEC = "1";
"A":   PN = "1"  !CDS_PN = "1";
"B":   PN = "2"  !CDS_PN = "2";
BODY = "RES","I65": #LOCATION = "R9F3" !CDS_LOCATION = "R9F3" #SEC = "1" !CDS_SEC = "1";
"A":   PN = "1"  !CDS_PN = "1";
"B":   PN = "2"  !CDS_PN = "2";
BODY = "FET_N","I67": #LOCATION = "Q8F2" !CDS_LOCATION = "Q8F2" #SEC = "1" !CDS_SEC = "1";
"DRN":   PN = "3"  !CDS_PN = "3";
"GATE":   PN = "1"  !CDS_PN = "1";
"SRC":   PN = "2"  !CDS_PN = "2";
BODY = "RES","I71": #LOCATION = "R8D26" !CDS_LOCATION = "R8D26" #SEC = "1" !CDS_SEC = "1";
"A":   PN = "1"  !CDS_PN = "1";
"B":   PN = "2"  !CDS_PN = "2";
BODY = "RES","I73": #LOCATION = "R1R5" !CDS_LOCATION = "R1R5" #SEC = "1" !CDS_SEC = "1";
"A":   PN = "1"  !CDS_PN = "1";
"B":   PN = "2"  !CDS_PN = "2";
BODY = "RES","I74": #LOCATION = "R2P4" !CDS_LOCATION = "R2P4" &SEC = "1" #&CDS_SEC = "1";
"A":   PN = "1"  !CDS_PN = "1";
"B":   PN = "2"  !CDS_PN = "2";
DRAWING = "@baseboard_fab2_lib.baseboard_fab2(sch_1):page172";
BODY = "CAP_A","I5": #LOCATION = "C2L49" !CDS_LOCATION = "C2L49" #SEC = "1" !CDS_SEC = "1";
"A":   PN = "1"  !CDS_PN = "1";
"B":   PN = "2"  !CDS_PN = "2";
BODY = "CAP_A","I6": #LOCATION = "C2L52" !CDS_LOCATION = "C2L52" #SEC = "1" !CDS_SEC = "1";
"A":   PN = "1"  !CDS_PN = "1";
"B":   PN = "2"  !CDS_PN = "2";
BODY = "CAP_A","I7": #LOCATION = "C2L50" !CDS_LOCATION = "C2L50" #SEC = "1" !CDS_SEC = "1";
"A":   PN = "1"  !CDS_PN = "1";
"B":   PN = "2"  !CDS_PN = "2";
BODY = "CAP_A","I8": #LOCATION = "C2L51" !CDS_LOCATION = "C2L51" #SEC = "1" !CDS_SEC = "1";
"A":   PN = "1"  !CDS_PN = "1";
"B":   PN = "2"  !CDS_PN = "2";
BODY = "CONN7_E82125014","I17": #LOCATION = "J8A3" !CDS_LOCATION = "J8A3" &SEC = "1" #&CDS_SEC = "1";
"GND<0>":   PN = "7"  !CDS_PN = "7";
"GND<1>":   PN = "4"  !CDS_PN = "4";
"GND<2>":   PN = "1"  !CDS_PN = "1";
"MH1":   PN = "MH1"  !CDS_PN = "MH1";
"MH2":   PN = "MH2"  !CDS_PN = "MH2";
"SATA_RXN":   PN = "5"  !CDS_PN = "5";
"SATA_RXP":   PN = "6"  !CDS_PN = "6";
"SATA_TXN":   PN = "3"  !CDS_PN = "3";
"SATA_TXP":   PN = "2"  !CDS_PN = "2";
BODY = "CONN4_H73295001","I25": #LOCATION = "J8A4" !CDS_LOCATION = "J8A4" #SEC = "1" !CDS_SEC = "1";
"IO1":   PN = "1"  !CDS_PN = "1";
"IO2":   PN = "2"  !CDS_PN = "2";
"IO3":   PN = "3"  !CDS_PN = "3";
"IO4":   PN = "4"  !CDS_PN = "4";
BODY = "CAP","I36": #LOCATION = "C9B2" !CDS_LOCATION = "C9B2" #SEC = "1" !CDS_SEC = "1";
"A":   PN = "1"  !CDS_PN = "1";
"B":   PN = "2"  !CDS_PN = "2";
BODY = "FUSE","I38": #LOCATION = "F9B1" !CDS_LOCATION = "F9B1" #SEC = "1" !CDS_SEC = "1";
"A<0>":   PN = "1"  !CDS_PN = "1";
"B<0>":   PN = "2"  !CDS_PN = "2";
BODY = "CAP","I39": #LOCATION = "C9B1" !CDS_LOCATION = "C9B1" #SEC = "1" !CDS_SEC = "1";
"A":   PN = "1"  !CDS_PN = "1";
"B":   PN = "2"  !CDS_PN = "2";
BODY = "FUSE","I41": #LOCATION = "F8B1" !CDS_LOCATION = "F8B1" #SEC = "1" !CDS_SEC = "1";
"A<0>":   PN = "1"  !CDS_PN = "1";
"B<0>":   PN = "2"  !CDS_PN = "2";
BODY = "CONN7_E82125014","I52": #LOCATION = "J2M1" !CDS_LOCATION = "J2M1" &SEC = "1" #&CDS_SEC = "1";
"GND<0>":   PN = "7"  !CDS_PN = "7";
"GND<1>":   PN = "4"  !CDS_PN = "4";
"GND<2>":   PN = "1"  !CDS_PN = "1";
"MH1":   PN = "MH1"  !CDS_PN = "MH1";
"MH2":   PN = "MH2"  !CDS_PN = "MH2";
"SATA_RXN":   PN = "5"  !CDS_PN = "5";
"SATA_RXP":   PN = "6"  !CDS_PN = "6";
"SATA_TXN":   PN = "3"  !CDS_PN = "3";
"SATA_TXP":   PN = "2"  !CDS_PN = "2";
BODY = "CONN4_H73295001","I53": #LOCATION = "J2L1" !CDS_LOCATION = "J2L1" #SEC = "1" !CDS_SEC = "1";
"IO1":   PN = "1"  !CDS_PN = "1";
"IO2":   PN = "2"  !CDS_PN = "2";
"IO3":   PN = "3"  !CDS_PN = "3";
"IO4":   PN = "4"  !CDS_PN = "4";
DRAWING = "@baseboard_fab2_lib.baseboard_fab2(sch_1):page173";
BODY = "CONN72_G97614002_A","I163": #LOCATION = "J8A1" !CDS_LOCATION = "J8A1" #SEC = "1" !CDS_SEC = "1";
"GND<0>":   PN = "2D9"  !CDS_PN = "2D9";
"GND<1>":   PN = "2D6"  !CDS_PN = "2D6";
"GND<2>":   PN = "2D3"  !CDS_PN = "2D3";
"GND<3>":   PN = "2C9"  !CDS_PN = "2C9";
"GND<4>":   PN = "2C6"  !CDS_PN = "2C6";
"GND<5>":   PN = "2C3"  !CDS_PN = "2C3";
"GND<6>":   PN = "2B9"  !CDS_PN = "2B9";
"GND<7>":   PN = "2B6"  !CDS_PN = "2B6";
"GND<8>":   PN = "2B3"  !CDS_PN = "2B3";
"GND<9>":   PN = "2A9"  !CDS_PN = "2A9";
"GND<10>":   PN = "2A6"  !CDS_PN = "2A6";
"GND<11>":   PN = "2A3"  !CDS_PN = "2A3";
"GND<12>":   PN = "1D9"  !CDS_PN = "1D9";
"GND<13>":   PN = "1D6"  !CDS_PN = "1D6";
"GND<14>":   PN = "1D3"  !CDS_PN = "1D3";
"GND<15>":   PN = "1C9"  !CDS_PN = "1C9";
"GND<16>":   PN = "1C6"  !CDS_PN = "1C6";
"GND<17>":   PN = "1C3"  !CDS_PN = "1C3";
"GND<18>":   PN = "1B9"  !CDS_PN = "1B9";
"GND<19>":   PN = "1B6"  !CDS_PN = "1B6";
"GND<20>":   PN = "1B3"  !CDS_PN = "1B3";
"GND<21>":   PN = "1A9"  !CDS_PN = "1A9";
"GND<22>":   PN = "1A6"  !CDS_PN = "1A6";
"GND<23>":   PN = "1A3"  !CDS_PN = "1A3";
"RXA0_DN":   PN = "1B5"  !CDS_PN = "1B5";
"RXA0_DP":   PN = "1B4"  !CDS_PN = "1B4";
"RXA1_DN":   PN = "1A5"  !CDS_PN = "1A5";
"RXA1_DP":   PN = "1A4"  !CDS_PN = "1A4";
"RXA2_DN":   PN = "1B8"  !CDS_PN = "1B8";
"RXA2_DP":   PN = "1B7"  !CDS_PN = "1B7";
"RXA3_DN":   PN = "1A8"  !CDS_PN = "1A8";
"RXA3_DP":   PN = "1A7"  !CDS_PN = "1A7";
"RXB0_DN":   PN = "2B5"  !CDS_PN = "2B5";
"RXB0_DP":   PN = "2B4"  !CDS_PN = "2B4";
"RXB1_DN":   PN = "2A5"  !CDS_PN = "2A5";
"RXB1_DP":   PN = "2A4"  !CDS_PN = "2A4";
"RXB2_DN":   PN = "2B8"  !CDS_PN = "2B8";
"RXB2_DP":   PN = "2B7"  !CDS_PN = "2B7";
"RXB3_DN":   PN = "2A8"  !CDS_PN = "2A8";
"RXB3_DP":   PN = "2A7"  !CDS_PN = "2A7";
"SIDEBANDA_0":   PN = "1A2"  !CDS_PN = "1A2";
"SIDEBANDA_1":   PN = "1B2"  !CDS_PN = "1B2";
"SIDEBANDA_2":   PN = "1C2"  !CDS_PN = "1C2";
"SIDEBANDA_3":   PN = "1B1"  !CDS_PN = "1B1";
"SIDEBANDA_4":   PN = "1C1"  !CDS_PN = "1C1";
"SIDEBANDA_5":   PN = "1D1"  !CDS_PN = "1D1";
"SIDEBANDA_6":   PN = "1D2"  !CDS_PN = "1D2";
"SIDEBANDA_7":   PN = "1A1"  !CDS_PN = "1A1";
"SIDEBANDB_0":   PN = "2A2"  !CDS_PN = "2A2";
"SIDEBANDB_1":   PN = "2B2"  !CDS_PN = "2B2";
"SIDEBANDB_2":   PN = "2C2"  !CDS_PN = "2C2";
"SIDEBANDB_3":   PN = "2B1"  !CDS_PN = "2B1";
"SIDEBANDB_4":   PN = "2C1"  !CDS_PN = "2C1";
"SIDEBANDB_5":   PN = "2D1"  !CDS_PN = "2D1";
"SIDEBANDB_6":   PN = "2D2"  !CDS_PN = "2D2";
"SIDEBANDB_7":   PN = "2A1"  !CDS_PN = "2A1";
"TXA0_DN":   PN = "1D5"  !CDS_PN = "1D5";
"TXA0_DP":   PN = "1D4"  !CDS_PN = "1D4";
"TXA1_DN":   PN = "1C5"  !CDS_PN = "1C5";
"TXA1_DP":   PN = "1C4"  !CDS_PN = "1C4";
"TXA2_DN":   PN = "1D8"  !CDS_PN = "1D8";
"TXA2_DP":   PN = "1D7"  !CDS_PN = "1D7";
"TXA3_DN":   PN = "1C8"  !CDS_PN = "1C8";
"TXA3_DP":   PN = "1C7"  !CDS_PN = "1C7";
"TXB0_DN":   PN = "2D5"  !CDS_PN = "2D5";
"TXB0_DP":   PN = "2D4"  !CDS_PN = "2D4";
"TXB1_DN":   PN = "2C5"  !CDS_PN = "2C5";
"TXB1_DP":   PN = "2C4"  !CDS_PN = "2C4";
"TXB2_DN":   PN = "2D8"  !CDS_PN = "2D8";
"TXB2_DP":   PN = "2D7"  !CDS_PN = "2D7";
"TXB3_DN":   PN = "2C8"  !CDS_PN = "2C8";
"TXB3_DP":   PN = "2C7"  !CDS_PN = "2C7";
BODY = "CAP_A","I165": #LOCATION = "C2L13" !CDS_LOCATION = "C2L13" #SEC = "1" !CDS_SEC = "1";
"A":   PN = "1"  !CDS_PN = "1";
"B":   PN = "2"  !CDS_PN = "2";
BODY = "CAP_A","I166": #LOCATION = "C2L6" !CDS_LOCATION = "C2L6" #SEC = "1" !CDS_SEC = "1";
"A":   PN = "1"  !CDS_PN = "1";
"B":   PN = "2"  !CDS_PN = "2";
BODY = "CAP_A","I172": #LOCATION = "C2L19" !CDS_LOCATION = "C2L19" #SEC = "1" !CDS_SEC = "1";
"A":   PN = "1"  !CDS_PN = "1";
"B":   PN = "2"  !CDS_PN = "2";
BODY = "CAP_A","I173": #LOCATION = "C2L10" !CDS_LOCATION = "C2L10" #SEC = "1" !CDS_SEC = "1";
"A":   PN = "1"  !CDS_PN = "1";
"B":   PN = "2"  !CDS_PN = "2";
BODY = "CAP_A","I174": #LOCATION = "C2L17" !CDS_LOCATION = "C2L17" #SEC = "1" !CDS_SEC = "1";
"A":   PN = "1"  !CDS_PN = "1";
"B":   PN = "2"  !CDS_PN = "2";
BODY = "CAP_A","I191": #LOCATION = "C2L15" !CDS_LOCATION = "C2L15" #SEC = "1" !CDS_SEC = "1";
"A":   PN = "1"  !CDS_PN = "1";
"B":   PN = "2"  !CDS_PN = "2";
BODY = "CAP_A","I192": #LOCATION = "C2L4" !CDS_LOCATION = "C2L4" #SEC = "1" !CDS_SEC = "1";
"A":   PN = "1"  !CDS_PN = "1";
"B":   PN = "2"  !CDS_PN = "2";
BODY = "CAP_A","I194": #LOCATION = "C2L3" !CDS_LOCATION = "C2L3" #SEC = "1" !CDS_SEC = "1";
"A":   PN = "1"  !CDS_PN = "1";
"B":   PN = "2"  !CDS_PN = "2";
BODY = "CAP_A","I195": #LOCATION = "C2L20" !CDS_LOCATION = "C2L20" #SEC = "1" !CDS_SEC = "1";
"A":   PN = "1"  !CDS_PN = "1";
"B":   PN = "2"  !CDS_PN = "2";
BODY = "CAP_A","I196": #LOCATION = "C2L12" !CDS_LOCATION = "C2L12" #SEC = "1" !CDS_SEC = "1";
"A":   PN = "1"  !CDS_PN = "1";
"B":   PN = "2"  !CDS_PN = "2";
BODY = "CAP_A","I197": #LOCATION = "C2L18" !CDS_LOCATION = "C2L18" #SEC = "1" !CDS_SEC = "1";
"A":   PN = "1"  !CDS_PN = "1";
"B":   PN = "2"  !CDS_PN = "2";
BODY = "CAP_A","I205": #LOCATION = "C2L16" !CDS_LOCATION = "C2L16" #SEC = "1" !CDS_SEC = "1";
"A":   PN = "1"  !CDS_PN = "1";
"B":   PN = "2"  !CDS_PN = "2";
BODY = "CAP_A","I206": #LOCATION = "C2L7" !CDS_LOCATION = "C2L7" #SEC = "1" !CDS_SEC = "1";
"A":   PN = "1"  !CDS_PN = "1";
"B":   PN = "2"  !CDS_PN = "2";
BODY = "CAP_A","I207": #LOCATION = "C2L9" !CDS_LOCATION = "C2L9" #SEC = "1" !CDS_SEC = "1";
"A":   PN = "1"  !CDS_PN = "1";
"B":   PN = "2"  !CDS_PN = "2";
BODY = "CAP_A","I208": #LOCATION = "C2L14" !CDS_LOCATION = "C2L14" #SEC = "1" !CDS_SEC = "1";
"A":   PN = "1"  !CDS_PN = "1";
"B":   PN = "2"  !CDS_PN = "2";
BODY = "CAP_A","I209": #LOCATION = "C2L5" !CDS_LOCATION = "C2L5" #SEC = "1" !CDS_SEC = "1";
"A":   PN = "1"  !CDS_PN = "1";
"B":   PN = "2"  !CDS_PN = "2";
BODY = "CAP_A","I220": #LOCATION = "C2L40" !CDS_LOCATION = "C2L40" #SEC = "1" !CDS_SEC = "1";
"A":   PN = "1"  !CDS_PN = "1";
"B":   PN = "2"  !CDS_PN = "2";
BODY = "CAP_A","I221": #LOCATION = "C2L39" !CDS_LOCATION = "C2L39" #SEC = "1" !CDS_SEC = "1";
"A":   PN = "1"  !CDS_PN = "1";
"B":   PN = "2"  !CDS_PN = "2";
BODY = "CAP_A","I222": #LOCATION = "C2L43" !CDS_LOCATION = "C2L43" #SEC = "1" !CDS_SEC = "1";
"A":   PN = "1"  !CDS_PN = "1";
"B":   PN = "2"  !CDS_PN = "2";
BODY = "CAP_A","I228": #LOCATION = "C2L44" !CDS_LOCATION = "C2L44" #SEC = "1" !CDS_SEC = "1";
"A":   PN = "1"  !CDS_PN = "1";
"B":   PN = "2"  !CDS_PN = "2";
BODY = "CAP_A","I233": #LOCATION = "C2L42" !CDS_LOCATION = "C2L42" #SEC = "1" !CDS_SEC = "1";
"A":   PN = "1"  !CDS_PN = "1";
"B":   PN = "2"  !CDS_PN = "2";
BODY = "CAP_A","I234": #LOCATION = "C2L22" !CDS_LOCATION = "C2L22" #SEC = "1" !CDS_SEC = "1";
"A":   PN = "1"  !CDS_PN = "1";
"B":   PN = "2"  !CDS_PN = "2";
BODY = "CAP_A","I238": #LOCATION = "C2L37" !CDS_LOCATION = "C2L37" #SEC = "1" !CDS_SEC = "1";
"A":   PN = "1"  !CDS_PN = "1";
"B":   PN = "2"  !CDS_PN = "2";
BODY = "CAP_A","I239": #LOCATION = "C2L47" !CDS_LOCATION = "C2L47" #SEC = "1" !CDS_SEC = "1";
"A":   PN = "1"  !CDS_PN = "1";
"B":   PN = "2"  !CDS_PN = "2";
BODY = "CAP_A","I240": #LOCATION = "C2L27" !CDS_LOCATION = "C2L27" #SEC = "1" !CDS_SEC = "1";
"A":   PN = "1"  !CDS_PN = "1";
"B":   PN = "2"  !CDS_PN = "2";
BODY = "CAP_A","I241": #LOCATION = "C2L23" !CDS_LOCATION = "C2L23" #SEC = "1" !CDS_SEC = "1";
"A":   PN = "1"  !CDS_PN = "1";
"B":   PN = "2"  !CDS_PN = "2";
BODY = "CAP_A","I242": #LOCATION = "C2L41" !CDS_LOCATION = "C2L41" #SEC = "1" !CDS_SEC = "1";
"A":   PN = "1"  !CDS_PN = "1";
"B":   PN = "2"  !CDS_PN = "2";
BODY = "CAP_A","I255": #LOCATION = "C2L26" !CDS_LOCATION = "C2L26" #SEC = "1" !CDS_SEC = "1";
"A":   PN = "1"  !CDS_PN = "1";
"B":   PN = "2"  !CDS_PN = "2";
BODY = "CAP_A","I256": #LOCATION = "C2L38" !CDS_LOCATION = "C2L38" #SEC = "1" !CDS_SEC = "1";
"A":   PN = "1"  !CDS_PN = "1";
"B":   PN = "2"  !CDS_PN = "2";
BODY = "CAP_A","I257": #LOCATION = "C2L48" !CDS_LOCATION = "C2L48" #SEC = "1" !CDS_SEC = "1";
"A":   PN = "1"  !CDS_PN = "1";
"B":   PN = "2"  !CDS_PN = "2";
BODY = "CAP_A","I258": #LOCATION = "C2L24" !CDS_LOCATION = "C2L24" #SEC = "1" !CDS_SEC = "1";
"A":   PN = "1"  !CDS_PN = "1";
"B":   PN = "2"  !CDS_PN = "2";
BODY = "CAP_A","I259": #LOCATION = "C2L21" !CDS_LOCATION = "C2L21" #SEC = "1" !CDS_SEC = "1";
"A":   PN = "1"  !CDS_PN = "1";
"B":   PN = "2"  !CDS_PN = "2";
BODY = "RES","I261": #LOCATION = "R2L23" !CDS_LOCATION = "R2L23" #SEC = "1" !CDS_SEC = "1";
"A":   PN = "1"  !CDS_PN = "1";
"B":   PN = "2"  !CDS_PN = "2";
BODY = "RES","I263": #LOCATION = "R2L21" !CDS_LOCATION = "R2L21" #SEC = "1" !CDS_SEC = "1";
"A":   PN = "1"  !CDS_PN = "1";
"B":   PN = "2"  !CDS_PN = "2";
BODY = "RES","I264": #LOCATION = "R2L22" !CDS_LOCATION = "R2L22" #SEC = "1" !CDS_SEC = "1";
"A":   PN = "1"  !CDS_PN = "1";
"B":   PN = "2"  !CDS_PN = "2";
BODY = "RES","I266": #LOCATION = "R2L18" !CDS_LOCATION = "R2L18" #SEC = "1" !CDS_SEC = "1";
"A":   PN = "1"  !CDS_PN = "1";
"B":   PN = "2"  !CDS_PN = "2";
DRAWING = "@baseboard_fab2_lib.baseboard_fab2(sch_1):page174";
BODY = "RES","I5": #LOCATION = "R1L3" !CDS_LOCATION = "R1L3" &SEC = "1" #&CDS_SEC = "1";
"A":   PN = "1"  !CDS_PN = "1";
"B":   PN = "2"  !CDS_PN = "2";
BODY = "CAP_A","I8": #LOCATION = "C1L3" !CDS_LOCATION = "C1L3" &SEC = "1" #&CDS_SEC = "1";
"A":   PN = "1"  !CDS_PN = "1";
"B":   PN = "2"  !CDS_PN = "2";
BODY = "CAP_A","I9": #LOCATION = "C1L2" !CDS_LOCATION = "C1L2" &SEC = "1" #&CDS_SEC = "1";
"A":   PN = "1"  !CDS_PN = "1";
"B":   PN = "2"  !CDS_PN = "2";
BODY = "CAP_A","I12": #LOCATION = "C1L7" !CDS_LOCATION = "C1L7" &SEC = "1" #&CDS_SEC = "1";
"A":   PN = "1"  !CDS_PN = "1";
"B":   PN = "2"  !CDS_PN = "2";
BODY = "CAP_A","I13": #LOCATION = "C1L6" !CDS_LOCATION = "C1L6" &SEC = "1" #&CDS_SEC = "1";
"A":   PN = "1"  !CDS_PN = "1";
"B":   PN = "2"  !CDS_PN = "2";
BODY = "CAP_A","I14": #LOCATION = "C1L13" !CDS_LOCATION = "C1L13" &SEC = "1" #&CDS_SEC = "1";
"A":   PN = "1"  !CDS_PN = "1";
"B":   PN = "2"  !CDS_PN = "2";
BODY = "CAP_A","I18": #LOCATION = "C1L15" !CDS_LOCATION = "C1L15" &SEC = "1" #&CDS_SEC = "1";
"A":   PN = "1"  !CDS_PN = "1";
"B":   PN = "2"  !CDS_PN = "2";
BODY = "CAP_A","I19": #LOCATION = "C1L12" !CDS_LOCATION = "C1L12" &SEC = "1" #&CDS_SEC = "1";
"A":   PN = "1"  !CDS_PN = "1";
"B":   PN = "2"  !CDS_PN = "2";
BODY = "CAP_A","I20": #LOCATION = "C1L14" !CDS_LOCATION = "C1L14" &SEC = "1" #&CDS_SEC = "1";
"A":   PN = "1"  !CDS_PN = "1";
"B":   PN = "2"  !CDS_PN = "2";
BODY = "RES","I25": #LOCATION = "R1L1" !CDS_LOCATION = "R1L1" &SEC = "1" #&CDS_SEC = "1";
"A":   PN = "1"  !CDS_PN = "1";
"B":   PN = "2"  !CDS_PN = "2";
BODY = "CONN36_G97614001","I26": #LOCATION = "J8A2" !CDS_LOCATION = "J8A2" &SEC = "1" #&CDS_SEC = "1";
"GND1":   PN = "A3"  !CDS_PN = "A3";
"GND2":   PN = "A6"  !CDS_PN = "A6";
"GND3":   PN = "A9"  !CDS_PN = "A9";
"GND4":   PN = "B3"  !CDS_PN = "B3";
"GND5":   PN = "B6"  !CDS_PN = "B6";
"GND6":   PN = "B9"  !CDS_PN = "B9";
"GND7":   PN = "C3"  !CDS_PN = "C3";
"GND8":   PN = "C6"  !CDS_PN = "C6";
"GND9":   PN = "C9"  !CDS_PN = "C9";
"GND10":   PN = "D3"  !CDS_PN = "D3";
"GND11":   PN = "D6"  !CDS_PN = "D6";
"GND12":   PN = "D9"  !CDS_PN = "D9";
"RXA0_DN":   PN = "B5"  !CDS_PN = "B5";
"RXA0_DP":   PN = "B4"  !CDS_PN = "B4";
"RXA1_DN":   PN = "A5"  !CDS_PN = "A5";
"RXA1_DP":   PN = "A4"  !CDS_PN = "A4";
"RXA2_DN":   PN = "B8"  !CDS_PN = "B8";
"RXA2_DP":   PN = "B7"  !CDS_PN = "B7";
"RXA3_DN":   PN = "A8"  !CDS_PN = "A8";
"RXA3_DP":   PN = "A7"  !CDS_PN = "A7";
"SIDEBAND0":   PN = "A2"  !CDS_PN = "A2";
"SIDEBAND1":   PN = "B2"  !CDS_PN = "B2";
"SIDEBAND2":   PN = "C2"  !CDS_PN = "C2";
"SIDEBAND3":   PN = "B1"  !CDS_PN = "B1";
"SIDEBAND4":   PN = "C1"  !CDS_PN = "C1";
"SIDEBAND5":   PN = "D1"  !CDS_PN = "D1";
"SIDEBAND6":   PN = "D2"  !CDS_PN = "D2";
"SIDEBAND7":   PN = "A1"  !CDS_PN = "A1";
"TXA0_DN":   PN = "D5"  !CDS_PN = "D5";
"TXA0_DP":   PN = "D4"  !CDS_PN = "D4";
"TXA1_DN":   PN = "C5"  !CDS_PN = "C5";
"TXA1_DP":   PN = "C4"  !CDS_PN = "C4";
"TXA2_DN":   PN = "D8"  !CDS_PN = "D8";
"TXA2_DP":   PN = "D7"  !CDS_PN = "D7";
"TXA3_DN":   PN = "C8"  !CDS_PN = "C8";
"TXA3_DP":   PN = "C7"  !CDS_PN = "C7";
BODY = "CAP_A","I28": #LOCATION = "C2L30" !CDS_LOCATION = "C2L30" &SEC = "1" #&CDS_SEC = "1";
"A":   PN = "1"  !CDS_PN = "1";
"B":   PN = "2"  !CDS_PN = "2";
BODY = "CAP_A","I29": #LOCATION = "C2L31" !CDS_LOCATION = "C2L31" &SEC = "1" #&CDS_SEC = "1";
"A":   PN = "1"  !CDS_PN = "1";
"B":   PN = "2"  !CDS_PN = "2";
BODY = "CAP_A","I30": #LOCATION = "C2L28" !CDS_LOCATION = "C2L28" &SEC = "1" #&CDS_SEC = "1";
"A":   PN = "1"  !CDS_PN = "1";
"B":   PN = "2"  !CDS_PN = "2";
BODY = "CAP_A","I31": #LOCATION = "C2L35" !CDS_LOCATION = "C2L35" &SEC = "1" #&CDS_SEC = "1";
"A":   PN = "1"  !CDS_PN = "1";
"B":   PN = "2"  !CDS_PN = "2";
BODY = "CAP_A","I32": #LOCATION = "C2L29" !CDS_LOCATION = "C2L29" &SEC = "1" #&CDS_SEC = "1";
"A":   PN = "1"  !CDS_PN = "1";
"B":   PN = "2"  !CDS_PN = "2";
BODY = "CAP_A","I39": #LOCATION = "C2L36" !CDS_LOCATION = "C2L36" &SEC = "1" #&CDS_SEC = "1";
"A":   PN = "1"  !CDS_PN = "1";
"B":   PN = "2"  !CDS_PN = "2";
BODY = "CAP_A","I40": #LOCATION = "C2L33" !CDS_LOCATION = "C2L33" &SEC = "1" #&CDS_SEC = "1";
"A":   PN = "1"  !CDS_PN = "1";
"B":   PN = "2"  !CDS_PN = "2";
BODY = "CAP_A","I41": #LOCATION = "C2L34" !CDS_LOCATION = "C2L34" &SEC = "1" #&CDS_SEC = "1";
"A":   PN = "1"  !CDS_PN = "1";
"B":   PN = "2"  !CDS_PN = "2";
DRAWING = "@baseboard_fab2_lib.baseboard_fab2(sch_1):page175";
BODY = "RES","I4": #LOCATION = "R1L31" !CDS_LOCATION = "R1L31" #SEC = "1" !CDS_SEC = "1";
"A":   PN = "1"  !CDS_PN = "1";
"B":   PN = "2"  !CDS_PN = "2";
BODY = "RES","I5": #LOCATION = "R1L27" !CDS_LOCATION = "R1L27" #SEC = "1" !CDS_SEC = "1";
"A":   PN = "1"  !CDS_PN = "1";
"B":   PN = "2"  !CDS_PN = "2";
BODY = "TTL2G14","I9": #LOCATION = "U9A4" !CDS_LOCATION = "U9A4" #SEC = "1" !CDS_SEC = "1";
"A<0>":   PN = "1"  !CDS_PN = "1";
"Y<0>":   PN = "6"  !CDS_PN = "6";
BODY = "TTL2G14","I10": #LOCATION = "U9A4" !CDS_LOCATION = "U9A4" #SEC = "2" !CDS_SEC = "2";
"A<0>":   PN = "3"  !CDS_PN = "3";
"Y<0>":   PN = "4"  !CDS_PN = "4";
BODY = "CAP_A","I11": #LOCATION = "C1L18" !CDS_LOCATION = "C1L18" #SEC = "1" !CDS_SEC = "1";
"A":   PN = "1"  !CDS_PN = "1";
"B":   PN = "2"  !CDS_PN = "2";
BODY = "RES","I13": #LOCATION = "R1L26" !CDS_LOCATION = "R1L26" #SEC = "1" !CDS_SEC = "1";
"A":   PN = "1"  !CDS_PN = "1";
"B":   PN = "2"  !CDS_PN = "2";
BODY = "TTL2G14","I15": #LOCATION = "U9A3" !CDS_LOCATION = "U9A3" #SEC = "2" !CDS_SEC = "2";
"A<0>":   PN = "3"  !CDS_PN = "3";
"Y<0>":   PN = "4"  !CDS_PN = "4";
BODY = "TTL2G14","I18": #LOCATION = "U9A3" !CDS_LOCATION = "U9A3" #SEC = "1" !CDS_SEC = "1";
"A<0>":   PN = "1"  !CDS_PN = "1";
"Y<0>":   PN = "6"  !CDS_PN = "6";
BODY = "CAP_A","I19": #LOCATION = "C1L10" !CDS_LOCATION = "C1L10" #SEC = "1" !CDS_SEC = "1";
"A":   PN = "1"  !CDS_PN = "1";
"B":   PN = "2"  !CDS_PN = "2";
BODY = "RES","I22": #LOCATION = "R1L22" !CDS_LOCATION = "R1L22" #SEC = "1" !CDS_SEC = "1";
"A":   PN = "1"  !CDS_PN = "1";
"B":   PN = "2"  !CDS_PN = "2";
BODY = "RES","I24": #LOCATION = "R1L19" !CDS_LOCATION = "R1L19" #SEC = "1" !CDS_SEC = "1";
"A":   PN = "1"  !CDS_PN = "1";
"B":   PN = "2"  !CDS_PN = "2";
BODY = "RES","I35": #LOCATION = "R9A9" !CDS_LOCATION = "R9A9" #SEC = "1" !CDS_SEC = "1";
"A":   PN = "1"  !CDS_PN = "1";
"B":   PN = "2"  !CDS_PN = "2";
BODY = "CAP_A","I37": #LOCATION = "C1L17" !CDS_LOCATION = "C1L17" #SEC = "1" !CDS_SEC = "1";
"A":   PN = "1"  !CDS_PN = "1";
"B":   PN = "2"  !CDS_PN = "2";
BODY = "CAP_A","I38": #LOCATION = "C1L9" !CDS_LOCATION = "C1L9" #SEC = "1" !CDS_SEC = "1";
"A":   PN = "1"  !CDS_PN = "1";
"B":   PN = "2"  !CDS_PN = "2";
BODY = "CAP_A","I40": #LOCATION = "C9A3" !CDS_LOCATION = "C9A3" #SEC = "1" !CDS_SEC = "1";
"A":   PN = "1"  !CDS_PN = "1";
"B":   PN = "2"  !CDS_PN = "2";
BODY = "RES","I45": #LOCATION = "R1L33" !CDS_LOCATION = "R1L33" #SEC = "1" !CDS_SEC = "1";
"A":   PN = "1"  !CDS_PN = "1";
"B":   PN = "2"  !CDS_PN = "2";
BODY = "FET_N","I49": #LOCATION = "Q9A3" !CDS_LOCATION = "Q9A3" #SEC = "1" !CDS_SEC = "1";
"DRN":   PN = "3"  !CDS_PN = "3";
"GATE":   PN = "1"  !CDS_PN = "1";
"SRC":   PN = "2"  !CDS_PN = "2";
BODY = "LED","I50": #LOCATION = "DS9A1" !CDS_LOCATION = "DS9A1" &SEC = "1" #&CDS_SEC = "1";
"A":   PN = "2"  !CDS_PN = "2";
"C":   PN = "1"  !CDS_PN = "1";
BODY = "TTL1G86","I57": #LOCATION = "U1L2" !CDS_LOCATION = "U1L2" &SEC = "1" #&CDS_SEC = "1";
"A":   PN = "1"  !CDS_PN = "1";
"B":   PN = "2"  !CDS_PN = "2";
"Y":   PN = "4"  !CDS_PN = "4";
BODY = "RES","I58": #LOCATION = "R1L8" !CDS_LOCATION = "R1L8" #SEC = "1" !CDS_SEC = "1";
"A":   PN = "1"  !CDS_PN = "1";
"B":   PN = "2"  !CDS_PN = "2";
BODY = "RES","I63": #LOCATION = "R1L12" !CDS_LOCATION = "R1L12" #SEC = "1" !CDS_SEC = "1";
"A":   PN = "1"  !CDS_PN = "1";
"B":   PN = "2"  !CDS_PN = "2";
BODY = "CAP_A","I64": #LOCATION = "C1L4" !CDS_LOCATION = "C1L4" #SEC = "1" !CDS_SEC = "1";
"A":   PN = "1"  !CDS_PN = "1";
"B":   PN = "2"  !CDS_PN = "2";
BODY = "LED","I67": #LOCATION = "DS9A3" !CDS_LOCATION = "DS9A3" #SEC = "1" !CDS_SEC = "1";
"A":   PN = "2"  !CDS_PN = "2";
"C":   PN = "1"  !CDS_PN = "1";
BODY = "SWITCH_D37771002","I78": #LOCATION = "S9A1" !CDS_LOCATION = "S9A1" #SEC = "1" !CDS_SEC = "1";
"PIN1":   PN = "1"  !CDS_PN = "1";
"PIN2":   PN = "2"  !CDS_PN = "2";
"PIN3":   PN = "3"  !CDS_PN = "3";
"PIN4":   PN = "4"  !CDS_PN = "4";
BODY = "SW_H67881001","I84": #LOCATION = "S9A2" !CDS_LOCATION = "S9A2" &SEC = "1" #&CDS_SEC = "1";
"IO1":   PN = "1"  !CDS_PN = "1";
"IO2":   PN = "2"  !CDS_PN = "2";
"IO3":   PN = "3"  !CDS_PN = "3";
"IO4":   PN = "4"  !CDS_PN = "4";
BODY = "0R2J-L-GP","I89": #LOCATION = "R1L45" !CDS_LOCATION = "R1L45" &SEC = "1" #&CDS_SEC = "1";
"1":   PN = "1"  !CDS_PN = "1";
"2":   PN = "2"  !CDS_PN = "2";
DRAWING = "@baseboard_fab2_lib.baseboard_fab2(sch_1):page176";
BODY = "RES","I16": #LOCATION = "R1M5" !CDS_LOCATION = "R1M5" #SEC = "1" !CDS_SEC = "1";
"A":   PN = "1"  !CDS_PN = "1";
"B":   PN = "2"  !CDS_PN = "2";
BODY = "CHOKE_4PIN","I30": #LOCATION = "L1M2" !CDS_LOCATION = "L1M2" #SEC = "1" !CDS_SEC = "1";
"A1":   PN = "1"  !CDS_PN = "1";
"A2":   PN = "2"  !CDS_PN = "2";
"B1":   PN = "3"  !CDS_PN = "3";
"B2":   PN = "4"  !CDS_PN = "4";
BODY = "RES","I31": #LOCATION = "R1M6" !CDS_LOCATION = "R1M6" #SEC = "1" !CDS_SEC = "1";
"A":   PN = "1"  !CDS_PN = "1";
"B":   PN = "2"  !CDS_PN = "2";
BODY = "CONN9_H51826001","I69": #LOCATION = "J9B1" !CDS_LOCATION = "J9B1" &SEC = "1" #&CDS_SEC = "1";
"DN":   PN = "2"  !CDS_PN = "2";
"DP":   PN = "3"  !CDS_PN = "3";
"GND":   PN = "4"  !CDS_PN = "4";
"GND_DRAIN":   PN = "7"  !CDS_PN = "7";
"MH1":   PN = "MH1"  !CDS_PN = "MH1";
"MH2":   PN = "MH2"  !CDS_PN = "MH2";
"MH3":   PN = "MH3"  !CDS_PN = "MH3";
"MH4":   PN = "MH4"  !CDS_PN = "MH4";
"STDA_SSRXN":   PN = "5"  !CDS_PN = "5";
"STDA_SSRXP":   PN = "6"  !CDS_PN = "6";
"STDA_SSTXN":   PN = "8"  !CDS_PN = "8";
"STDA_SSTXP":   PN = "9"  !CDS_PN = "9";
"VBUS":   PN = "1"  !CDS_PN = "1";
BODY = "DIODEAC_DUAL_ARRAY","I98": #LOCATION = "CR1M2" !CDS_LOCATION = "CR1M2" #SEC = "1" !CDS_SEC = "1";
"AC0":   PN = "1"  !CDS_PN = "1";
"AC1":   PN = "2"  !CDS_PN = "2";
"AC2":   PN = "4"  !CDS_PN = "4";
"AC3":   PN = "5"  !CDS_PN = "5";
"GND<0>":   PN = "3"  !CDS_PN = "3";
"OUT0":   PN = "9"  !CDS_PN = "9";
"OUT1":   PN = "8"  !CDS_PN = "8";
"OUT2":   PN = "7"  !CDS_PN = "7";
"OUT3":   PN = "6"  !CDS_PN = "6";
BODY = "TPS2061","I100": #LOCATION = "U1M3" !CDS_LOCATION = "U1M3" #SEC = "1" !CDS_SEC = "1";
"EN_N":   PN = "4"  !CDS_PN = "4";
"GND":   PN = "2"  !CDS_PN = "2";
"IN":   PN = "5"  !CDS_PN = "5";
"OC_N":   PN = "3"  !CDS_PN = "3";
"OUT":   PN = "1"  !CDS_PN = "1";
BODY = "RES","I105": #LOCATION = "R1M24" !CDS_LOCATION = "R1M24" #SEC = "1" !CDS_SEC = "1";
"A":   PN = "1"  !CDS_PN = "1";
"B":   PN = "2"  !CDS_PN = "2";
BODY = "CAP_A","I108": #LOCATION = "C1M38" !CDS_LOCATION = "C1M38" #SEC = "1" !CDS_SEC = "1";
"A":   PN = "1"  !CDS_PN = "1";
"B":   PN = "2"  !CDS_PN = "2";
BODY = "RES","I111": #LOCATION = "R1M25" !CDS_LOCATION = "R1M25" #SEC = "1" !CDS_SEC = "1";
"A":   PN = "1"  !CDS_PN = "1";
"B":   PN = "2"  !CDS_PN = "2";
BODY = "CAPP","I113": #LOCATION = "C9B8" !CDS_LOCATION = "C9B8" #SEC = "1" !CDS_SEC = "1";
"A":   PN = "1"  !CDS_PN = "1";
"B":   PN = "2"  !CDS_PN = "2";
BODY = "TTL1G08","I122": #LOCATION = "U6W10" !CDS_LOCATION = "U6W10" &SEC = "1" #&CDS_SEC = "1";
"A<0>":   PN = "1"  !CDS_PN = "1";
"B<0>":   PN = "2"  !CDS_PN = "2";
"Y<0>":   PN = "4"  !CDS_PN = "4";
BODY = "CAP","I124": #LOCATION = "C6W10" !CDS_LOCATION = "C6W10" &SEC = "1" #&CDS_SEC = "1";
"A":   PN = "1"  !CDS_PN = "1";
"B":   PN = "2"  !CDS_PN = "2";
DRAWING = "@baseboard_fab2_lib.baseboard_fab2(sch_1):page177";
BODY = "RES","I3": #LOCATION = "R1M13" !CDS_LOCATION = "R1M13" &SEC = "1" #&CDS_SEC = "1";
"A":   PN = "1"  !CDS_PN = "1";
"B":   PN = "2"  !CDS_PN = "2";
BODY = "RES","I6": #LOCATION = "R1M10" !CDS_LOCATION = "R1M10" &SEC = "1" #&CDS_SEC = "1";
"A":   PN = "1"  !CDS_PN = "1";
"B":   PN = "2"  !CDS_PN = "2";
BODY = "RES","I8": #LOCATION = "R1M12" !CDS_LOCATION = "R1M12" #SEC = "1" !CDS_SEC = "1";
"A":   PN = "1"  !CDS_PN = "1";
"B":   PN = "2"  !CDS_PN = "2";
BODY = "RES","I9": #LOCATION = "R1M11" !CDS_LOCATION = "R1M11" #SEC = "1" !CDS_SEC = "1";
"A":   PN = "1"  !CDS_PN = "1";
"B":   PN = "2"  !CDS_PN = "2";
BODY = "CAP_A","I20": #LOCATION = "C1M3" !CDS_LOCATION = "C1M3" &SEC = "1" #&CDS_SEC = "1";
"A":   PN = "1"  !CDS_PN = "1";
"B":   PN = "2"  !CDS_PN = "2";
BODY = "LED","I31": #LOCATION = "DS9A6" !CDS_LOCATION = "DS9A6" #SEC = "1" !CDS_SEC = "1";
"A":   PN = "1"  !CDS_PN = "1";
"C":   PN = "2"  !CDS_PN = "2";
BODY = "RES","I33": #LOCATION = "R1L37" !CDS_LOCATION = "R1L37" &SEC = "1" #&CDS_SEC = "1";
"A":   PN = "1"  !CDS_PN = "1";
"B":   PN = "2"  !CDS_PN = "2";
BODY = "LED","I42": #LOCATION = "DS9A2" !CDS_LOCATION = "DS9A2" #SEC = "1" !CDS_SEC = "1";
"A":   PN = "2"  !CDS_PN = "2";
"C":   PN = "1"  !CDS_PN = "1";
BODY = "RES","I43": #LOCATION = "R1L21" !CDS_LOCATION = "R1L21" #SEC = "1" !CDS_SEC = "1";
"A":   PN = "1"  !CDS_PN = "1";
"B":   PN = "2"  !CDS_PN = "2";
BODY = "TTL1G08","I70": #LOCATION = "U1M1" !CDS_LOCATION = "U1M1" #SEC = "1" !CDS_SEC = "1";
"A<0>":   PN = "1"  !CDS_PN = "1";
"B<0>":   PN = "2"  !CDS_PN = "2";
"Y<0>":   PN = "4"  !CDS_PN = "4";
BODY = "LED","I71": #LOCATION = "DS9F1" !CDS_LOCATION = "DS9F1" #SEC = "1" !CDS_SEC = "1";
"A":   PN = "1"  !CDS_PN = "1";
"C":   PN = "2"  !CDS_PN = "2";
BODY = "RES","I72": #LOCATION = "R9F28" !CDS_LOCATION = "R9F28" #SEC = "1" !CDS_SEC = "1";
"A":   PN = "1"  !CDS_PN = "1";
"B":   PN = "2"  !CDS_PN = "2";
BODY = "RES","I76": #LOCATION = "R9F30" !CDS_LOCATION = "R9F30" #SEC = "1" !CDS_SEC = "1";
"A":   PN = "1"  !CDS_PN = "1";
"B":   PN = "2"  !CDS_PN = "2";
BODY = "FET_N_DUAL","I79": #LOCATION = "Q9F1" !CDS_LOCATION = "Q9F1" #SEC = "2" !CDS_SEC = "2";
"DRAIN<0>":   PN = "3"  !CDS_PN = "3";
"GATE<0>":   PN = "5"  !CDS_PN = "5";
"SOURCE<0>":   PN = "4"  !CDS_PN = "4";
BODY = "FET_N_DUAL","I80": #LOCATION = "Q9F1" !CDS_LOCATION = "Q9F1" #SEC = "1" !CDS_SEC = "1";
"DRAIN<0>":   PN = "6"  !CDS_PN = "6";
"GATE<0>":   PN = "2"  !CDS_PN = "2";
"SOURCE<0>":   PN = "1"  !CDS_PN = "1";
BODY = "RES","I82": #LOCATION = "R9F52" !CDS_LOCATION = "R9F52" #SEC = "1" !CDS_SEC = "1";
"A":   PN = "1"  !CDS_PN = "1";
"B":   PN = "2"  !CDS_PN = "2";
DRAWING = "@baseboard_fab2_lib.baseboard_fab2(sch_1):page178";
BODY = "RES","I1": #LOCATION = "R8D20" !CDS_LOCATION = "R8D20" #SEC = "1" !CDS_SEC = "1";
"A":   PN = "1"  !CDS_PN = "1";
"B":   PN = "2"  !CDS_PN = "2";
BODY = "RES","I2": #LOCATION = "R2L12" !CDS_LOCATION = "R2L12" #SEC = "1" !CDS_SEC = "1";
"A":   PN = "1"  !CDS_PN = "1";
"B":   PN = "2"  !CDS_PN = "2";
BODY = "RES","I8": #LOCATION = "R8D19" !CDS_LOCATION = "R8D19" #SEC = "1" !CDS_SEC = "1";
"A":   PN = "1"  !CDS_PN = "1";
"B":   PN = "2"  !CDS_PN = "2";
BODY = "RES","I11": #LOCATION = "R2N31" !CDS_LOCATION = "R2N31" #SEC = "1" !CDS_SEC = "1";
"A":   PN = "1"  !CDS_PN = "1";
"B":   PN = "2"  !CDS_PN = "2";
BODY = "RES","I12": #LOCATION = "R2L15" !CDS_LOCATION = "R2L15" #SEC = "1" !CDS_SEC = "1";
"A":   PN = "1"  !CDS_PN = "1";
"B":   PN = "2"  !CDS_PN = "2";
BODY = "RES","I13": #LOCATION = "R2L11" !CDS_LOCATION = "R2L11" #SEC = "1" !CDS_SEC = "1";
"A":   PN = "1"  !CDS_PN = "1";
"B":   PN = "2"  !CDS_PN = "2";
BODY = "RES","I17": #LOCATION = "R2L6" !CDS_LOCATION = "R2L6" #SEC = "1" !CDS_SEC = "1";
"A":   PN = "1"  !CDS_PN = "1";
"B":   PN = "2"  !CDS_PN = "2";
BODY = "RES","I18": #LOCATION = "R2L4" !CDS_LOCATION = "R2L4" #SEC = "1" !CDS_SEC = "1";
"A":   PN = "1"  !CDS_PN = "1";
"B":   PN = "2"  !CDS_PN = "2";
BODY = "RES","I20": #LOCATION = "R2L5" !CDS_LOCATION = "R2L5" #SEC = "1" !CDS_SEC = "1";
"A":   PN = "1"  !CDS_PN = "1";
"B":   PN = "2"  !CDS_PN = "2";
BODY = "RES","I21": #LOCATION = "R8B29" !CDS_LOCATION = "R8B29" #SEC = "1" !CDS_SEC = "1";
"A":   PN = "1"  !CDS_PN = "1";
"B":   PN = "2"  !CDS_PN = "2";
BODY = "RES","I22": #LOCATION = "R2N19" !CDS_LOCATION = "R2N19" #SEC = "1" !CDS_SEC = "1";
"A":   PN = "1"  !CDS_PN = "1";
"B":   PN = "2"  !CDS_PN = "2";
BODY = "RES","I23": #LOCATION = "R2N22" !CDS_LOCATION = "R2N22" #SEC = "1" !CDS_SEC = "1";
"A":   PN = "1"  !CDS_PN = "1";
"B":   PN = "2"  !CDS_PN = "2";
DRAWING = "@baseboard_fab2_lib.baseboard_fab2(sch_1):page181";
BODY = "CONN76_H22707001","I111": #LOCATION = "J1F1" !CDS_LOCATION = "J1F1" #SEC = "1" !CDS_SEC = "1";
"GNDA2":   PN = "A2"  !CDS_PN = "A2";
"GNDA4":   PN = "A4"  !CDS_PN = "A4";
"GNDA6":   PN = "A6"  !CDS_PN = "A6";
"GNDA8":   PN = "A8"  !CDS_PN = "A8";
"GNDC1":   PN = "C1"  !CDS_PN = "C1";
"GNDC3":   PN = "C3"  !CDS_PN = "C3";
"GNDC5":   PN = "C5"  !CDS_PN = "C5";
"GNDC7":   PN = "C7"  !CDS_PN = "C7";
"GNDD2":   PN = "D2"  !CDS_PN = "D2";
"GNDD4":   PN = "D4"  !CDS_PN = "D4";
"GNDD6":   PN = "D6"  !CDS_PN = "D6";
"GNDD8":   PN = "D8"  !CDS_PN = "D8";
"GNDF1":   PN = "F1"  !CDS_PN = "F1";
"GNDF3":   PN = "F3"  !CDS_PN = "F3";
"GNDF5":   PN = "F5"  !CDS_PN = "F5";
"GNDF7":   PN = "F7"  !CDS_PN = "F7";
"GNDG2":   PN = "G2"  !CDS_PN = "G2";
"GNDG4":   PN = "G4"  !CDS_PN = "G4";
"GNDG6":   PN = "G6"  !CDS_PN = "G6";
"GNDG8":   PN = "G8"  !CDS_PN = "G8";
"GNDI1":   PN = "I1"  !CDS_PN = "I1";
"GNDI3":   PN = "I3"  !CDS_PN = "I3";
"GNDI5":   PN = "I5"  !CDS_PN = "I5";
"GNDI7":   PN = "I7"  !CDS_PN = "I7";
"GNDJ2":   PN = "J2"  !CDS_PN = "J2";
"GNDJ4":   PN = "J4"  !CDS_PN = "J4";
"GNDJ6":   PN = "J6"  !CDS_PN = "J6";
"GNDJ8":   PN = "J8"  !CDS_PN = "J8";
"IOA1":   PN = "A1"  !CDS_PN = "A1";
"IOA3":   PN = "A3"  !CDS_PN = "A3";
"IOA5":   PN = "A5"  !CDS_PN = "A5";
"IOA7":   PN = "A7"  !CDS_PN = "A7";
"IOB1":   PN = "B1"  !CDS_PN = "B1";
"IOB2":   PN = "B2"  !CDS_PN = "B2";
"IOB3":   PN = "B3"  !CDS_PN = "B3";
"IOB4":   PN = "B4"  !CDS_PN = "B4";
"IOB5":   PN = "B5"  !CDS_PN = "B5";
"IOB6":   PN = "B6"  !CDS_PN = "B6";
"IOB7":   PN = "B7"  !CDS_PN = "B7";
"IOB8":   PN = "B8"  !CDS_PN = "B8";
"IOC2":   PN = "C2"  !CDS_PN = "C2";
"IOC4":   PN = "C4"  !CDS_PN = "C4";
"IOC6":   PN = "C6"  !CDS_PN = "C6";
"IOC8":   PN = "C8"  !CDS_PN = "C8";
"IOD1":   PN = "D1"  !CDS_PN = "D1";
"IOD3":   PN = "D3"  !CDS_PN = "D3";
"IOD5":   PN = "D5"  !CDS_PN = "D5";
"IOD7":   PN = "D7"  !CDS_PN = "D7";
"IOE1":   PN = "E1"  !CDS_PN = "E1";
"IOE2":   PN = "E2"  !CDS_PN = "E2";
"IOE3":   PN = "E3"  !CDS_PN = "E3";
"IOE4":   PN = "E4"  !CDS_PN = "E4";
"IOE5":   PN = "E5"  !CDS_PN = "E5";
"IOE6":   PN = "E6"  !CDS_PN = "E6";
"IOE7":   PN = "E7"  !CDS_PN = "E7";
"IOE8":   PN = "E8"  !CDS_PN = "E8";
"IOF2":   PN = "F2"  !CDS_PN = "F2";
"IOF4":   PN = "F4"  !CDS_PN = "F4";
"IOF6":   PN = "F6"  !CDS_PN = "F6";
"IOF8":   PN = "F8"  !CDS_PN = "F8";
"IOG1":   PN = "G1"  !CDS_PN = "G1";
"IOG3":   PN = "G3"  !CDS_PN = "G3";
"IOG5":   PN = "G5"  !CDS_PN = "G5";
"IOG7":   PN = "G7"  !CDS_PN = "G7";
"IOH1":   PN = "H1"  !CDS_PN = "H1";
"IOH2":   PN = "H2"  !CDS_PN = "H2";
"IOH3":   PN = "H3"  !CDS_PN = "H3";
"IOH4":   PN = "H4"  !CDS_PN = "H4";
"IOH5":   PN = "H5"  !CDS_PN = "H5";
"IOH6":   PN = "H6"  !CDS_PN = "H6";
"IOH7":   PN = "H7"  !CDS_PN = "H7";
"IOH8":   PN = "H8"  !CDS_PN = "H8";
"IOI2":   PN = "I2"  !CDS_PN = "I2";
"IOI4":   PN = "I4"  !CDS_PN = "I4";
"IOI6":   PN = "I6"  !CDS_PN = "I6";
"IOI8":   PN = "I8"  !CDS_PN = "I8";
BODY = "CAP","I160": #LOCATION = "C1F4" !CDS_LOCATION = "C1F4" #SEC = "1" !CDS_SEC = "1";
"A":   PN = "1"  !CDS_PN = "1";
"B":   PN = "2"  !CDS_PN = "2";
BODY = "CAP","I161": #LOCATION = "C1F5" !CDS_LOCATION = "C1F5" #SEC = "1" !CDS_SEC = "1";
"A":   PN = "1"  !CDS_PN = "1";
"B":   PN = "2"  !CDS_PN = "2";
BODY = "CAP","I162": #LOCATION = "C1F2" !CDS_LOCATION = "C1F2" #SEC = "1" !CDS_SEC = "1";
"A":   PN = "1"  !CDS_PN = "1";
"B":   PN = "2"  !CDS_PN = "2";
BODY = "CAP","I163": #LOCATION = "C1F13" !CDS_LOCATION = "C1F13" #SEC = "1" !CDS_SEC = "1";
"A":   PN = "1"  !CDS_PN = "1";
"B":   PN = "2"  !CDS_PN = "2";
BODY = "CAP","I164": #LOCATION = "C1F10" !CDS_LOCATION = "C1F10" #SEC = "1" !CDS_SEC = "1";
"A":   PN = "1"  !CDS_PN = "1";
"B":   PN = "2"  !CDS_PN = "2";
BODY = "CAP","I165": #LOCATION = "C1F6" !CDS_LOCATION = "C1F6" #SEC = "1" !CDS_SEC = "1";
"A":   PN = "1"  !CDS_PN = "1";
"B":   PN = "2"  !CDS_PN = "2";
BODY = "CAP","I166": #LOCATION = "C1F20" !CDS_LOCATION = "C1F20" #SEC = "1" !CDS_SEC = "1";
"A":   PN = "1"  !CDS_PN = "1";
"B":   PN = "2"  !CDS_PN = "2";
BODY = "CAP","I167": #LOCATION = "C1F3" !CDS_LOCATION = "C1F3" #SEC = "1" !CDS_SEC = "1";
"A":   PN = "1"  !CDS_PN = "1";
"B":   PN = "2"  !CDS_PN = "2";
BODY = "CAP","I168": #LOCATION = "C1F12" !CDS_LOCATION = "C1F12" #SEC = "1" !CDS_SEC = "1";
"A":   PN = "1"  !CDS_PN = "1";
"B":   PN = "2"  !CDS_PN = "2";
BODY = "CAP","I169": #LOCATION = "C1F11" !CDS_LOCATION = "C1F11" #SEC = "1" !CDS_SEC = "1";
"A":   PN = "1"  !CDS_PN = "1";
"B":   PN = "2"  !CDS_PN = "2";
BODY = "CAP","I170": #LOCATION = "C1F8" !CDS_LOCATION = "C1F8" #SEC = "1" !CDS_SEC = "1";
"A":   PN = "1"  !CDS_PN = "1";
"B":   PN = "2"  !CDS_PN = "2";
BODY = "CAP","I171": #LOCATION = "C1F18" !CDS_LOCATION = "C1F18" #SEC = "1" !CDS_SEC = "1";
"A":   PN = "1"  !CDS_PN = "1";
"B":   PN = "2"  !CDS_PN = "2";
BODY = "CAP","I172": #LOCATION = "C1F16" !CDS_LOCATION = "C1F16" #SEC = "1" !CDS_SEC = "1";
"A":   PN = "1"  !CDS_PN = "1";
"B":   PN = "2"  !CDS_PN = "2";
BODY = "CAP","I173": #LOCATION = "C1F17" !CDS_LOCATION = "C1F17" #SEC = "1" !CDS_SEC = "1";
"A":   PN = "1"  !CDS_PN = "1";
"B":   PN = "2"  !CDS_PN = "2";
BODY = "CAP","I174": #LOCATION = "C1F15" !CDS_LOCATION = "C1F15" #SEC = "1" !CDS_SEC = "1";
"A":   PN = "1"  !CDS_PN = "1";
"B":   PN = "2"  !CDS_PN = "2";
BODY = "CAP","I175": #LOCATION = "C1F14" !CDS_LOCATION = "C1F14" #SEC = "1" !CDS_SEC = "1";
"A":   PN = "1"  !CDS_PN = "1";
"B":   PN = "2"  !CDS_PN = "2";
BODY = "RES","I177": #LOCATION = "R9T9" !CDS_LOCATION = "R9T9" #SEC = "1" !CDS_SEC = "1";
"A":   PN = "1"  !CDS_PN = "1";
"B":   PN = "2"  !CDS_PN = "2";
BODY = "DIODE","I178": #LOCATION = "CR1F4" !CDS_LOCATION = "CR1F4" #SEC = "1" !CDS_SEC = "1";
"A":   PN = "2"  !CDS_PN = "2";
"C":   PN = "1"  !CDS_PN = "1";
BODY = "DIODE","I180": #LOCATION = "CR1F3" !CDS_LOCATION = "CR1F3" #SEC = "1" !CDS_SEC = "1";
"A":   PN = "2"  !CDS_PN = "2";
"C":   PN = "1"  !CDS_PN = "1";
BODY = "NPN","I181": #LOCATION = "Q9T1" !CDS_LOCATION = "Q9T1" #SEC = "1" !CDS_SEC = "1";
"B":   PN = "1"  !CDS_PN = "1";
"C":   PN = "3"  !CDS_PN = "3";
"E":   PN = "2"  !CDS_PN = "2";
BODY = "RES","I183": #LOCATION = "R9T6" !CDS_LOCATION = "R9T6" #SEC = "1" !CDS_SEC = "1";
"A":   PN = "1"  !CDS_PN = "1";
"B":   PN = "2"  !CDS_PN = "2";
BODY = "RES","I185": #LOCATION = "R9T3" !CDS_LOCATION = "R9T3" #SEC = "1" !CDS_SEC = "1";
"A":   PN = "1"  !CDS_PN = "1";
"B":   PN = "2"  !CDS_PN = "2";
BODY = "CONN8_H62179001","I189": #LOCATION = "J1F3" !CDS_LOCATION = "J1F3" &SEC = "1" #&CDS_SEC = "1";
"IO1":   PN = "1"  !CDS_PN = "1";
"IO2":   PN = "2"  !CDS_PN = "2";
"IO3":   PN = "3"  !CDS_PN = "3";
"IO4":   PN = "4"  !CDS_PN = "4";
"IO5":   PN = "5"  !CDS_PN = "5";
"IO6":   PN = "6"  !CDS_PN = "6";
"IO7":   PN = "7"  !CDS_PN = "7";
"IO8":   PN = "8"  !CDS_PN = "8";
BODY = "RES","I199": #LOCATION = "R7D5" !CDS_LOCATION = "R7D5" #SEC = "1" !CDS_SEC = "1";
"A":   PN = "1"  !CDS_PN = "1";
"B":   PN = "2"  !CDS_PN = "2";
BODY = "RES","I200": #LOCATION = "R7D9" !CDS_LOCATION = "R7D9" #SEC = "1" !CDS_SEC = "1";
"A":   PN = "1"  !CDS_PN = "1";
"B":   PN = "2"  !CDS_PN = "2";
BODY = "RES","I201": #LOCATION = "R3P61" !CDS_LOCATION = "R3P61" #SEC = "1" !CDS_SEC = "1";
"A":   PN = "1"  !CDS_PN = "1";
"B":   PN = "2"  !CDS_PN = "2";
BODY = "RES","I218": #LOCATION = "R8E5" !CDS_LOCATION = "R8E5" #SEC = "1" !CDS_SEC = "1";
"A":   PN = "1"  !CDS_PN = "1";
"B":   PN = "2"  !CDS_PN = "2";
BODY = "CAP","I224": #LOCATION = "C2R6" !CDS_LOCATION = "C2R6" #SEC = "1" !CDS_SEC = "1";
"A":   PN = "1"  !CDS_PN = "1";
"B":   PN = "2"  !CDS_PN = "2";
BODY = "TTL08","I243": #LOCATION = "U8E1" !CDS_LOCATION = "U8E1" #SEC = "2" !CDS_SEC = "2";
"A<0>":   PN = "9"  !CDS_PN = "9";
"B<0>":   PN = "10"  !CDS_PN = "10";
"Y<0>":   PN = "8"  !CDS_PN = "8";
BODY = "CAP_A","I253": #LOCATION = "C8E1" !CDS_LOCATION = "C8E1" #SEC = "1" !CDS_SEC = "1";
"A":   PN = "1"  !CDS_PN = "1";
"B":   PN = "2"  !CDS_PN = "2";
BODY = "RES","I254": #LOCATION = "R9R9" !CDS_LOCATION = "R9R9" #SEC = "1" !CDS_SEC = "1";
"A":   PN = "1"  !CDS_PN = "1";
"B":   PN = "2"  !CDS_PN = "2";
BODY = "RES","I255": #LOCATION = "R9R12" !CDS_LOCATION = "R9R12" #SEC = "1" !CDS_SEC = "1";
"A":   PN = "1"  !CDS_PN = "1";
"B":   PN = "2"  !CDS_PN = "2";
BODY = "RES","I256": #LOCATION = "R9R10" !CDS_LOCATION = "R9R10" #SEC = "1" !CDS_SEC = "1";
"A":   PN = "1"  !CDS_PN = "1";
"B":   PN = "2"  !CDS_PN = "2";
BODY = "RES","I261": #LOCATION = "R9T1" !CDS_LOCATION = "R9T1" #SEC = "1" !CDS_SEC = "1";
"A":   PN = "1"  !CDS_PN = "1";
"B":   PN = "2"  !CDS_PN = "2";
BODY = "RES","I268": #LOCATION = "R1F8" !CDS_LOCATION = "R1F8" #SEC = "1" !CDS_SEC = "1";
"A":   PN = "1"  !CDS_PN = "1";
"B":   PN = "2"  !CDS_PN = "2";
BODY = "RES","I278": #LOCATION = "R9T8" !CDS_LOCATION = "R9T8" &SEC = "1" #&CDS_SEC = "1";
"A":   PN = "1"  !CDS_PN = "1";
"B":   PN = "2"  !CDS_PN = "2";
BODY = "RES","I279": #LOCATION = "R9F67" !CDS_LOCATION = "R9F67" &SEC = "1" #&CDS_SEC = "1";
"A":   PN = "1"  !CDS_PN = "1";
"B":   PN = "2"  !CDS_PN = "2";
BODY = "RES","I280": #LOCATION = "R9F70" !CDS_LOCATION = "R9F70" #SEC = "1" !CDS_SEC = "1";
"A":   PN = "1"  !CDS_PN = "1";
"B":   PN = "2"  !CDS_PN = "2";
BODY = "RES","I281": #LOCATION = "R9F64" !CDS_LOCATION = "R9F64" #SEC = "1" !CDS_SEC = "1";
"A":   PN = "1"  !CDS_PN = "1";
"B":   PN = "2"  !CDS_PN = "2";
BODY = "RES","I282": #LOCATION = "R9F63" !CDS_LOCATION = "R9F63" #SEC = "1" !CDS_SEC = "1";
"A":   PN = "1"  !CDS_PN = "1";
"B":   PN = "2"  !CDS_PN = "2";
DRAWING = "@baseboard_fab2_lib.baseboard_fab2(sch_1):page182";
BODY = "CAP","I9": #LOCATION = "C9N18" !CDS_LOCATION = "C9N18" #SEC = "1" !CDS_SEC = "1";
"A":   PN = "1"  !CDS_PN = "1";
"B":   PN = "2"  !CDS_PN = "2";
BODY = "CAP","I12": #LOCATION = "C9N17" !CDS_LOCATION = "C9N17" #SEC = "1" !CDS_SEC = "1";
"A":   PN = "1"  !CDS_PN = "1";
"B":   PN = "2"  !CDS_PN = "2";
BODY = "CAP","I13": #LOCATION = "C9N15" !CDS_LOCATION = "C9N15" #SEC = "1" !CDS_SEC = "1";
"A":   PN = "1"  !CDS_PN = "1";
"B":   PN = "2"  !CDS_PN = "2";
BODY = "CAP","I14": #LOCATION = "C9N1" !CDS_LOCATION = "C9N1" #SEC = "1" !CDS_SEC = "1";
"A":   PN = "1"  !CDS_PN = "1";
"B":   PN = "2"  !CDS_PN = "2";
BODY = "CAP","I15": #LOCATION = "C9N2" !CDS_LOCATION = "C9N2" #SEC = "1" !CDS_SEC = "1";
"A":   PN = "1"  !CDS_PN = "1";
"B":   PN = "2"  !CDS_PN = "2";
BODY = "CAP","I16": #LOCATION = "C9N12" !CDS_LOCATION = "C9N12" #SEC = "1" !CDS_SEC = "1";
"A":   PN = "1"  !CDS_PN = "1";
"B":   PN = "2"  !CDS_PN = "2";
BODY = "CONN76_H22707001","I18": #LOCATION = "J1C1" !CDS_LOCATION = "J1C1" #SEC = "1" !CDS_SEC = "1";
"GNDA2":   PN = "A2"  !CDS_PN = "A2";
"GNDA4":   PN = "A4"  !CDS_PN = "A4";
"GNDA6":   PN = "A6"  !CDS_PN = "A6";
"GNDA8":   PN = "A8"  !CDS_PN = "A8";
"GNDC1":   PN = "C1"  !CDS_PN = "C1";
"GNDC3":   PN = "C3"  !CDS_PN = "C3";
"GNDC5":   PN = "C5"  !CDS_PN = "C5";
"GNDC7":   PN = "C7"  !CDS_PN = "C7";
"GNDD2":   PN = "D2"  !CDS_PN = "D2";
"GNDD4":   PN = "D4"  !CDS_PN = "D4";
"GNDD6":   PN = "D6"  !CDS_PN = "D6";
"GNDD8":   PN = "D8"  !CDS_PN = "D8";
"GNDF1":   PN = "F1"  !CDS_PN = "F1";
"GNDF3":   PN = "F3"  !CDS_PN = "F3";
"GNDF5":   PN = "F5"  !CDS_PN = "F5";
"GNDF7":   PN = "F7"  !CDS_PN = "F7";
"GNDG2":   PN = "G2"  !CDS_PN = "G2";
"GNDG4":   PN = "G4"  !CDS_PN = "G4";
"GNDG6":   PN = "G6"  !CDS_PN = "G6";
"GNDG8":   PN = "G8"  !CDS_PN = "G8";
"GNDI1":   PN = "I1"  !CDS_PN = "I1";
"GNDI3":   PN = "I3"  !CDS_PN = "I3";
"GNDI5":   PN = "I5"  !CDS_PN = "I5";
"GNDI7":   PN = "I7"  !CDS_PN = "I7";
"GNDJ2":   PN = "J2"  !CDS_PN = "J2";
"GNDJ4":   PN = "J4"  !CDS_PN = "J4";
"GNDJ6":   PN = "J6"  !CDS_PN = "J6";
"GNDJ8":   PN = "J8"  !CDS_PN = "J8";
"IOA1":   PN = "A1"  !CDS_PN = "A1";
"IOA3":   PN = "A3"  !CDS_PN = "A3";
"IOA5":   PN = "A5"  !CDS_PN = "A5";
"IOA7":   PN = "A7"  !CDS_PN = "A7";
"IOB1":   PN = "B1"  !CDS_PN = "B1";
"IOB2":   PN = "B2"  !CDS_PN = "B2";
"IOB3":   PN = "B3"  !CDS_PN = "B3";
"IOB4":   PN = "B4"  !CDS_PN = "B4";
"IOB5":   PN = "B5"  !CDS_PN = "B5";
"IOB6":   PN = "B6"  !CDS_PN = "B6";
"IOB7":   PN = "B7"  !CDS_PN = "B7";
"IOB8":   PN = "B8"  !CDS_PN = "B8";
"IOC2":   PN = "C2"  !CDS_PN = "C2";
"IOC4":   PN = "C4"  !CDS_PN = "C4";
"IOC6":   PN = "C6"  !CDS_PN = "C6";
"IOC8":   PN = "C8"  !CDS_PN = "C8";
"IOD1":   PN = "D1"  !CDS_PN = "D1";
"IOD3":   PN = "D3"  !CDS_PN = "D3";
"IOD5":   PN = "D5"  !CDS_PN = "D5";
"IOD7":   PN = "D7"  !CDS_PN = "D7";
"IOE1":   PN = "E1"  !CDS_PN = "E1";
"IOE2":   PN = "E2"  !CDS_PN = "E2";
"IOE3":   PN = "E3"  !CDS_PN = "E3";
"IOE4":   PN = "E4"  !CDS_PN = "E4";
"IOE5":   PN = "E5"  !CDS_PN = "E5";
"IOE6":   PN = "E6"  !CDS_PN = "E6";
"IOE7":   PN = "E7"  !CDS_PN = "E7";
"IOE8":   PN = "E8"  !CDS_PN = "E8";
"IOF2":   PN = "F2"  !CDS_PN = "F2";
"IOF4":   PN = "F4"  !CDS_PN = "F4";
"IOF6":   PN = "F6"  !CDS_PN = "F6";
"IOF8":   PN = "F8"  !CDS_PN = "F8";
"IOG1":   PN = "G1"  !CDS_PN = "G1";
"IOG3":   PN = "G3"  !CDS_PN = "G3";
"IOG5":   PN = "G5"  !CDS_PN = "G5";
"IOG7":   PN = "G7"  !CDS_PN = "G7";
"IOH1":   PN = "H1"  !CDS_PN = "H1";
"IOH2":   PN = "H2"  !CDS_PN = "H2";
"IOH3":   PN = "H3"  !CDS_PN = "H3";
"IOH4":   PN = "H4"  !CDS_PN = "H4";
"IOH5":   PN = "H5"  !CDS_PN = "H5";
"IOH6":   PN = "H6"  !CDS_PN = "H6";
"IOH7":   PN = "H7"  !CDS_PN = "H7";
"IOH8":   PN = "H8"  !CDS_PN = "H8";
"IOI2":   PN = "I2"  !CDS_PN = "I2";
"IOI4":   PN = "I4"  !CDS_PN = "I4";
"IOI6":   PN = "I6"  !CDS_PN = "I6";
"IOI8":   PN = "I8"  !CDS_PN = "I8";
BODY = "CAP","I49": #LOCATION = "C9N9" !CDS_LOCATION = "C9N9" #SEC = "1" !CDS_SEC = "1";
"A":   PN = "1"  !CDS_PN = "1";
"B":   PN = "2"  !CDS_PN = "2";
BODY = "CAP","I50": #LOCATION = "C9N8" !CDS_LOCATION = "C9N8" #SEC = "1" !CDS_SEC = "1";
"A":   PN = "1"  !CDS_PN = "1";
"B":   PN = "2"  !CDS_PN = "2";
BODY = "CAP","I51": #LOCATION = "C9N3" !CDS_LOCATION = "C9N3" #SEC = "1" !CDS_SEC = "1";
"A":   PN = "1"  !CDS_PN = "1";
"B":   PN = "2"  !CDS_PN = "2";
BODY = "CAP","I52": #LOCATION = "C9N16" !CDS_LOCATION = "C9N16" #SEC = "1" !CDS_SEC = "1";
"A":   PN = "1"  !CDS_PN = "1";
"B":   PN = "2"  !CDS_PN = "2";
BODY = "CAP","I53": #LOCATION = "C9N10" !CDS_LOCATION = "C9N10" #SEC = "1" !CDS_SEC = "1";
"A":   PN = "1"  !CDS_PN = "1";
"B":   PN = "2"  !CDS_PN = "2";
BODY = "CAP","I54": #LOCATION = "C9N7" !CDS_LOCATION = "C9N7" #SEC = "1" !CDS_SEC = "1";
"A":   PN = "1"  !CDS_PN = "1";
"B":   PN = "2"  !CDS_PN = "2";
BODY = "CAP","I55": #LOCATION = "C9N4" !CDS_LOCATION = "C9N4" #SEC = "1" !CDS_SEC = "1";
"A":   PN = "1"  !CDS_PN = "1";
"B":   PN = "2"  !CDS_PN = "2";
BODY = "CAP","I56": #LOCATION = "C9N14" !CDS_LOCATION = "C9N14" #SEC = "1" !CDS_SEC = "1";
"A":   PN = "1"  !CDS_PN = "1";
"B":   PN = "2"  !CDS_PN = "2";
BODY = "CAP","I81": #LOCATION = "C9N6" !CDS_LOCATION = "C9N6" #SEC = "1" !CDS_SEC = "1";
"A":   PN = "1"  !CDS_PN = "1";
"B":   PN = "2"  !CDS_PN = "2";
BODY = "CAP","I83": #LOCATION = "C9N5" !CDS_LOCATION = "C9N5" #SEC = "1" !CDS_SEC = "1";
"A":   PN = "1"  !CDS_PN = "1";
"B":   PN = "2"  !CDS_PN = "2";
BODY = "RES","I97": #LOCATION = "R1C11" !CDS_LOCATION = "R1C11" #SEC = "1" !CDS_SEC = "1";
"A":   PN = "1"  !CDS_PN = "1";
"B":   PN = "2"  !CDS_PN = "2";
BODY = "RES","I101": #LOCATION = "R1C10" !CDS_LOCATION = "R1C10" #SEC = "1" !CDS_SEC = "1";
"A":   PN = "1"  !CDS_PN = "1";
"B":   PN = "2"  !CDS_PN = "2";
BODY = "RES","I104": #LOCATION = "R1C9" !CDS_LOCATION = "R1C9" #SEC = "1" !CDS_SEC = "1";
"A":   PN = "1"  !CDS_PN = "1";
"B":   PN = "2"  !CDS_PN = "2";
BODY = "RES","I107": #LOCATION = "R1F9" !CDS_LOCATION = "R1F9" #SEC = "1" !CDS_SEC = "1";
"A":   PN = "1"  !CDS_PN = "1";
"B":   PN = "2"  !CDS_PN = "2";
BODY = "RES","I110": #LOCATION = "R1C31" !CDS_LOCATION = "R1C31" #SEC = "1" !CDS_SEC = "1";
"A":   PN = "1"  !CDS_PN = "1";
"B":   PN = "2"  !CDS_PN = "2";
DRAWING = "@baseboard_fab2_lib.baseboard_fab2(sch_1):page183";
BODY = "PI7C9X1172","I1": #LOCATION = "EU9F3" !CDS_LOCATION = "EU9F3" &SEC = "1" #&CDS_SEC = "1";
"A0_CS_N":   PN = "30"  !CDS_PN = "30";
"A1_S1":   PN = "31"  !CDS_PN = "31";
"CTSA_N":   PN = "25"  !CDS_PN = "25";
"CTSB_N":   PN = "16"  !CDS_PN = "16";
"EN485_N":   PN = "19"  !CDS_PN = "19";
"ENIR_N":   PN = "18"  !CDS_PN = "18";
"GND":   PN = "12"  !CDS_PN = "12";
"GPIO0_DSRB_N":   PN = "13"  !CDS_PN = "13";
"GPIO1_DTRB_N":   PN = "23"  !CDS_PN = "23";
"GPIO2_CDB_N":   PN = "11"  !CDS_PN = "11";
"GPIO3_RIB_N":   PN = "14"  !CDS_PN = "14";
"GPIO4_DSRA_N":   PN = "26"  !CDS_PN = "26";
"GPIO5_DTRA_N":   PN = "22"  !CDS_PN = "22";
"GPIO6_CDA_N":   PN = "27"  !CDS_PN = "27";
"GPIO7_RIA_N":   PN = "28"  !CDS_PN = "28";
"I2C_SPI_N":   PN = "32"  !CDS_PN = "32";
"IRQ_N":   PN = "20"  !CDS_PN = "20";
"NC<0>":   PN = "1"  !CDS_PN = "1";
"NC<1>":   PN = "8"  !CDS_PN = "8";
"RESET_N":   PN = "24"  !CDS_PN = "24";
"RTSA_N":   PN = "21"  !CDS_PN = "21";
"RTSB_N":   PN = "15"  !CDS_PN = "15";
"RXA":   PN = "5"  !CDS_PN = "5";
"RXB":   PN = "4"  !CDS_PN = "4";
"SCL":   PN = "17"  !CDS_PN = "17";
"SDA":   PN = "3"  !CDS_PN = "3";
"SO":   PN = "2"  !CDS_PN = "2";
"THPAD":   PN = "33"  !CDS_PN = "33";
"TXA":   PN = "6"  !CDS_PN = "6";
"TXB":   PN = "7"  !CDS_PN = "7";
"VDD":   PN = "29"  !CDS_PN = "29";
"XTAL1":   PN = "9"  !CDS_PN = "9";
"XTAL2":   PN = "10"  !CDS_PN = "10";
BODY = "RES","I4": #LOCATION = "R9F47" !CDS_LOCATION = "R9F47" #SEC = "1" !CDS_SEC = "1";
"A":   PN = "1"  !CDS_PN = "1";
"B":   PN = "2"  !CDS_PN = "2";
BODY = "CAP_A","I7": #LOCATION = "C9F19" !CDS_LOCATION = "C9F19" #SEC = "1" !CDS_SEC = "1";
"A":   PN = "1"  !CDS_PN = "1";
"B":   PN = "2"  !CDS_PN = "2";
BODY = "RES","I11": #LOCATION = "R9F50" !CDS_LOCATION = "R9F50" &SEC = "1" #&CDS_SEC = "1";
"A":   PN = "1"  !CDS_PN = "1";
"B":   PN = "2"  !CDS_PN = "2";
BODY = "RES","I12": #LOCATION = "R9F51" !CDS_LOCATION = "R9F51" &SEC = "1" #&CDS_SEC = "1";
"A":   PN = "1"  !CDS_PN = "1";
"B":   PN = "2"  !CDS_PN = "2";
BODY = "RES","I13": #LOCATION = "R9F48" !CDS_LOCATION = "R9F48" #SEC = "1" !CDS_SEC = "1";
"A":   PN = "1"  !CDS_PN = "1";
"B":   PN = "2"  !CDS_PN = "2";
BODY = "RES","I14": #LOCATION = "R9F49" !CDS_LOCATION = "R9F49" #SEC = "1" !CDS_SEC = "1";
"A":   PN = "1"  !CDS_PN = "1";
"B":   PN = "2"  !CDS_PN = "2";
BODY = "CRYSTAL","I19": #LOCATION = "Y9F1" !CDS_LOCATION = "Y9F1" #SEC = "1" !CDS_SEC = "1";
"A":   PN = "1"  !CDS_PN = "1";
"B":   PN = "2"  !CDS_PN = "2";
BODY = "CAP","I20": #LOCATION = "C9F20" !CDS_LOCATION = "C9F20" &SEC = "1" #&CDS_SEC = "1";
"A":   PN = "1"  !CDS_PN = "1";
"B":   PN = "2"  !CDS_PN = "2";
BODY = "CAP","I21": #LOCATION = "C9F21" !CDS_LOCATION = "C9F21" &SEC = "1" #&CDS_SEC = "1";
"A":   PN = "1"  !CDS_PN = "1";
"B":   PN = "2"  !CDS_PN = "2";
BODY = "RES","I24": #LOCATION = "R9F58" !CDS_LOCATION = "R9F58" #SEC = "1" !CDS_SEC = "1";
"A":   PN = "1"  !CDS_PN = "1";
"B":   PN = "2"  !CDS_PN = "2";
BODY = "RES","I25": #LOCATION = "R9F59" !CDS_LOCATION = "R9F59" #SEC = "1" !CDS_SEC = "1";
"A":   PN = "1"  !CDS_PN = "1";
"B":   PN = "2"  !CDS_PN = "2";
BODY = "RES","I30": #LOCATION = "R9F55" !CDS_LOCATION = "R9F55" #SEC = "1" !CDS_SEC = "1";
"A":   PN = "1"  !CDS_PN = "1";
"B":   PN = "2"  !CDS_PN = "2";
BODY = "RES","I48": #LOCATION = "R9F57" !CDS_LOCATION = "R9F57" #SEC = "1" !CDS_SEC = "1";
"A":   PN = "1"  !CDS_PN = "1";
"B":   PN = "2"  !CDS_PN = "2";
BODY = "RES","I49": #LOCATION = "R9F56" !CDS_LOCATION = "R9F56" #SEC = "1" !CDS_SEC = "1";
"A":   PN = "1"  !CDS_PN = "1";
"B":   PN = "2"  !CDS_PN = "2";
BODY = "RES","I52": #LOCATION = "R9F54" !CDS_LOCATION = "R9F54" #SEC = "1" !CDS_SEC = "1";
"A":   PN = "1"  !CDS_PN = "1";
"B":   PN = "2"  !CDS_PN = "2";
BODY = "RES","I53": #LOCATION = "R9F53" !CDS_LOCATION = "R9F53" #SEC = "1" !CDS_SEC = "1";
"A":   PN = "1"  !CDS_PN = "1";
"B":   PN = "2"  !CDS_PN = "2";
DRAWING = "@baseboard_fab2_lib.baseboard_fab2(sch_1):page184";
BODY = "SCONN11_H67026001","I87": #LOCATION = "J8E1" !CDS_LOCATION = "J8E1" #SEC = "1" !CDS_SEC = "1";
"IO1":   PN = "1"  !CDS_PN = "1";
"IO2":   PN = "2"  !CDS_PN = "2";
"IO3":   PN = "3"  !CDS_PN = "3";
"IO4":   PN = "4"  !CDS_PN = "4";
"IO5":   PN = "5"  !CDS_PN = "5";
"IO6":   PN = "6"  !CDS_PN = "6";
"IO7":   PN = "7"  !CDS_PN = "7";
"IO8":   PN = "8"  !CDS_PN = "8";
"IO9":   PN = "9"  !CDS_PN = "9";
"IO10":   PN = "10"  !CDS_PN = "10";
"IO11":   PN = "11"  !CDS_PN = "11";
"MP1":   PN = "MP1"  !CDS_PN = "MP1";
"MP2":   PN = "MP2"  !CDS_PN = "MP2";
BODY = "RES","I88": #LOCATION = "R8E9" !CDS_LOCATION = "R8E9" #SEC = "1" !CDS_SEC = "1";
"A":   PN = "1"  !CDS_PN = "1";
"B":   PN = "2"  !CDS_PN = "2";
BODY = "RES","I92": #LOCATION = "R8D35" !CDS_LOCATION = "R8D35" #SEC = "1" !CDS_SEC = "1";
"A":   PN = "1"  !CDS_PN = "1";
"B":   PN = "2"  !CDS_PN = "2";
BODY = "RES","I93": #LOCATION = "R8E13" !CDS_LOCATION = "R8E13" #SEC = "1" !CDS_SEC = "1";
"A":   PN = "1"  !CDS_PN = "1";
"B":   PN = "2"  !CDS_PN = "2";
BODY = "RES","I95": #LOCATION = "R8E10" !CDS_LOCATION = "R8E10" #SEC = "1" !CDS_SEC = "1";
"A":   PN = "1"  !CDS_PN = "1";
"B":   PN = "2"  !CDS_PN = "2";
BODY = "RES","I99": #LOCATION = "R8E1" !CDS_LOCATION = "R8E1" &SEC = "1" #&CDS_SEC = "1";
"A":   PN = "1"  !CDS_PN = "1";
"B":   PN = "2"  !CDS_PN = "2";
BODY = "STANDOFF","I104": #LOCATION = "RM8D1" !CDS_LOCATION = "RM8D1" #SEC = "1" !CDS_SEC = "1";
"IO1":   PN = "1"  !CDS_PN = "1";
DRAWING = "@baseboard_fab2_lib.baseboard_fab2(sch_1):page185";
BODY = "SCONN75K_H17033002","I53": #LOCATION = "J8F1" !CDS_LOCATION = "J8F1" #SEC = "1" !CDS_SEC = "1";
"3_3V<0>":   PN = "2"  !CDS_PN = "2";
"3_3V<1>":   PN = "4"  !CDS_PN = "4";
"3_3V<2>":   PN = "12"  !CDS_PN = "12";
"3_3V<3>":   PN = "14"  !CDS_PN = "14";
"3_3V<4>":   PN = "16"  !CDS_PN = "16";
"3_3V<5>":   PN = "18"  !CDS_PN = "18";
"3_3V<6>":   PN = "70"  !CDS_PN = "70";
"3_3V<7>":   PN = "72"  !CDS_PN = "72";
"3_3V<8>":   PN = "74"  !CDS_PN = "74";
"CLKREQ_N_NC":   PN = "52"  !CDS_PN = "52";
"DAS_DSS_N":   PN = "10"  !CDS_PN = "10";
"DEVSLP":   PN = "38"  !CDS_PN = "38";
"GND<0>":   PN = "1"  !CDS_PN = "1";
"GND<1>":   PN = "3"  !CDS_PN = "3";
"GND<2>":   PN = "9"  !CDS_PN = "9";
"GND<3>":   PN = "15"  !CDS_PN = "15";
"GND<4>":   PN = "21"  !CDS_PN = "21";
"GND<5>":   PN = "27"  !CDS_PN = "27";
"GND<6>":   PN = "33"  !CDS_PN = "33";
"GND<7>":   PN = "39"  !CDS_PN = "39";
"GND<8>":   PN = "45"  !CDS_PN = "45";
"GND<9>":   PN = "51"  !CDS_PN = "51";
"GND<10>":   PN = "57"  !CDS_PN = "57";
"GND<11>":   PN = "71"  !CDS_PN = "71";
"GND<12>":   PN = "73"  !CDS_PN = "73";
"GND<13>":   PN = "75"  !CDS_PN = "75";
"MP1":   PN = "MP1"  !CDS_PN = "MP1";
"MP2":   PN = "MP2"  !CDS_PN = "MP2";
"NC<0>":   PN = "6"  !CDS_PN = "6";
"NC<1>":   PN = "8"  !CDS_PN = "8";
"NC<2>":   PN = "20"  !CDS_PN = "20";
"NC<3>":   PN = "22"  !CDS_PN = "22";
"NC<4>":   PN = "24"  !CDS_PN = "24";
"NC<5>":   PN = "26"  !CDS_PN = "26";
"NC<6>":   PN = "28"  !CDS_PN = "28";
"NC<7>":   PN = "30"  !CDS_PN = "30";
"NC<8>":   PN = "32"  !CDS_PN = "32";
"NC<9>":   PN = "34"  !CDS_PN = "34";
"NC<10>":   PN = "36"  !CDS_PN = "36";
"NC<11>":   PN = "40"  !CDS_PN = "40";
"NC<12>":   PN = "42"  !CDS_PN = "42";
"NC<13>":   PN = "44"  !CDS_PN = "44";
"NC<14>":   PN = "46"  !CDS_PN = "46";
"NC<15>":   PN = "48"  !CDS_PN = "48";
"NC<16>":   PN = "56"  !CDS_PN = "56";
"NC<17>":   PN = "58"  !CDS_PN = "58";
"NC<18>":   PN = "67"  !CDS_PN = "67";
"PEDET":   PN = "69"  !CDS_PN = "69";
"PERN0_SATA_BP":   PN = "41"  !CDS_PN = "41";
"PERN1":   PN = "29"  !CDS_PN = "29";
"PERN2":   PN = "17"  !CDS_PN = "17";
"PERN3":   PN = "5"  !CDS_PN = "5";
"PERP0_SATA_BN":   PN = "43"  !CDS_PN = "43";
"PERP1":   PN = "31"  !CDS_PN = "31";
"PERP2":   PN = "19"  !CDS_PN = "19";
"PERP3":   PN = "7"  !CDS_PN = "7";
"PERST_N_NC":   PN = "50"  !CDS_PN = "50";
"PETN0_SATA_AN":   PN = "47"  !CDS_PN = "47";
"PETN1":   PN = "35"  !CDS_PN = "35";
"PETN2":   PN = "23"  !CDS_PN = "23";
"PETN3":   PN = "11"  !CDS_PN = "11";
"PETP0_SATA_AP":   PN = "49"  !CDS_PN = "49";
"PETP1":   PN = "37"  !CDS_PN = "37";
"PETP2":   PN = "25"  !CDS_PN = "25";
"PETP3":   PN = "13"  !CDS_PN = "13";
"PEWAKE_N_NC":   PN = "54"  !CDS_PN = "54";
"REFCLKN":   PN = "53"  !CDS_PN = "53";
"REFCLKP":   PN = "55"  !CDS_PN = "55";
"SUSCLK":   PN = "68"  !CDS_PN = "68";
BODY = "CAP","I62": #LOCATION = "C2T11" !CDS_LOCATION = "C2T11" #SEC = "1" !CDS_SEC = "1";
"A":   PN = "1"  !CDS_PN = "1";
"B":   PN = "2"  !CDS_PN = "2";
BODY = "CAP","I63": #LOCATION = "C2T10" !CDS_LOCATION = "C2T10" #SEC = "1" !CDS_SEC = "1";
"A":   PN = "1"  !CDS_PN = "1";
"B":   PN = "2"  !CDS_PN = "2";
BODY = "CAP","I64": #LOCATION = "C2T13" !CDS_LOCATION = "C2T13" #SEC = "1" !CDS_SEC = "1";
"A":   PN = "1"  !CDS_PN = "1";
"B":   PN = "2"  !CDS_PN = "2";
BODY = "CAP","I65": #LOCATION = "C2T14" !CDS_LOCATION = "C2T14" #SEC = "1" !CDS_SEC = "1";
"A":   PN = "1"  !CDS_PN = "1";
"B":   PN = "2"  !CDS_PN = "2";
BODY = "CAP","I66": #LOCATION = "C2T20" !CDS_LOCATION = "C2T20" #SEC = "1" !CDS_SEC = "1";
"A":   PN = "1"  !CDS_PN = "1";
"B":   PN = "2"  !CDS_PN = "2";
BODY = "CAP","I67": #LOCATION = "C2T23" !CDS_LOCATION = "C2T23" #SEC = "1" !CDS_SEC = "1";
"A":   PN = "1"  !CDS_PN = "1";
"B":   PN = "2"  !CDS_PN = "2";
BODY = "CAP_A","I90": #LOCATION = "C8F15" !CDS_LOCATION = "C8F15" &SEC = "1" #&CDS_SEC = "1";
"A":   PN = "1"  !CDS_PN = "1";
"B":   PN = "2"  !CDS_PN = "2";
BODY = "CAP_A","I95": #LOCATION = "C8F6" !CDS_LOCATION = "C8F6" &SEC = "1" #&CDS_SEC = "1";
"A":   PN = "1"  !CDS_PN = "1";
"B":   PN = "2"  !CDS_PN = "2";
BODY = "CAP","I96": #LOCATION = "C8F7" !CDS_LOCATION = "C8F7" #SEC = "1" !CDS_SEC = "1";
"A":   PN = "1"  !CDS_PN = "1";
"B":   PN = "2"  !CDS_PN = "2";
BODY = "CAP_A","I97": #LOCATION = "C8F11" !CDS_LOCATION = "C8F11" &SEC = "1" #&CDS_SEC = "1";
"A":   PN = "1"  !CDS_PN = "1";
"B":   PN = "2"  !CDS_PN = "2";
BODY = "CAP","I98": #LOCATION = "C8F12" !CDS_LOCATION = "C8F12" #SEC = "1" !CDS_SEC = "1";
"A":   PN = "1"  !CDS_PN = "1";
"B":   PN = "2"  !CDS_PN = "2";
BODY = "CAP_A","I99": #LOCATION = "C8F13" !CDS_LOCATION = "C8F13" &SEC = "1" #&CDS_SEC = "1";
"A":   PN = "1"  !CDS_PN = "1";
"B":   PN = "2"  !CDS_PN = "2";
BODY = "RES","I105": #LOCATION = "R8F18" !CDS_LOCATION = "R8F18" #SEC = "1" !CDS_SEC = "1";
"A":   PN = "1"  !CDS_PN = "1";
"B":   PN = "2"  !CDS_PN = "2";
BODY = "RES","I106": #LOCATION = "R8F21" !CDS_LOCATION = "R8F21" #SEC = "1" !CDS_SEC = "1";
"A":   PN = "1"  !CDS_PN = "1";
"B":   PN = "2"  !CDS_PN = "2";
BODY = "TTL1G07_A","I110": #LOCATION = "U2P1" !CDS_LOCATION = "U2P1" #SEC = "1" !CDS_SEC = "1";
"A":   PN = "2"  !CDS_PN = "2";
"Y":   PN = "4"  !CDS_PN = "4";
BODY = "RES","I111": #LOCATION = "R2P15" !CDS_LOCATION = "R2P15" #SEC = "1" !CDS_SEC = "1";
"A":   PN = "1"  !CDS_PN = "1";
"B":   PN = "2"  !CDS_PN = "2";
BODY = "RES","I113": #LOCATION = "R2P16" !CDS_LOCATION = "R2P16" #SEC = "1" !CDS_SEC = "1";
"A":   PN = "1"  !CDS_PN = "1";
"B":   PN = "2"  !CDS_PN = "2";
BODY = "RES","I115": #LOCATION = "R2P14" !CDS_LOCATION = "R2P14" #SEC = "1" !CDS_SEC = "1";
"A":   PN = "1"  !CDS_PN = "1";
"B":   PN = "2"  !CDS_PN = "2";
BODY = "CAP_A","I117": #LOCATION = "C2P9" !CDS_LOCATION = "C2P9" #SEC = "1" !CDS_SEC = "1";
"A":   PN = "1"  !CDS_PN = "1";
"B":   PN = "2"  !CDS_PN = "2";
BODY = "CAP_A","I120": #LOCATION = "C2T29" !CDS_LOCATION = "C2T29" #SEC = "1" !CDS_SEC = "1";
"A":   PN = "1"  !CDS_PN = "1";
"B":   PN = "2"  !CDS_PN = "2";
BODY = "CAP_A","I123": #LOCATION = "C2T26" !CDS_LOCATION = "C2T26" #SEC = "1" !CDS_SEC = "1";
"A":   PN = "1"  !CDS_PN = "1";
"B":   PN = "2"  !CDS_PN = "2";
BODY = "CAP_A","I124": #LOCATION = "C2T21" !CDS_LOCATION = "C2T21" #SEC = "1" !CDS_SEC = "1";
"A":   PN = "1"  !CDS_PN = "1";
"B":   PN = "2"  !CDS_PN = "2";
BODY = "CAP_A","I126": #LOCATION = "C2T16" !CDS_LOCATION = "C2T16" #SEC = "1" !CDS_SEC = "1";
"A":   PN = "1"  !CDS_PN = "1";
"B":   PN = "2"  !CDS_PN = "2";
BODY = "CAP_A","I127": #LOCATION = "C2T15" !CDS_LOCATION = "C2T15" #SEC = "1" !CDS_SEC = "1";
"A":   PN = "1"  !CDS_PN = "1";
"B":   PN = "2"  !CDS_PN = "2";
BODY = "CAP_A","I129": #LOCATION = "C2T24" !CDS_LOCATION = "C2T24" #SEC = "1" !CDS_SEC = "1";
"A":   PN = "1"  !CDS_PN = "1";
"B":   PN = "2"  !CDS_PN = "2";
BODY = "CAP_A","I131": #LOCATION = "C2T2" !CDS_LOCATION = "C2T2" #SEC = "1" !CDS_SEC = "1";
"A":   PN = "1"  !CDS_PN = "1";
"B":   PN = "2"  !CDS_PN = "2";
BODY = "CAP_A","I132": #LOCATION = "C2T4" !CDS_LOCATION = "C2T4" #SEC = "1" !CDS_SEC = "1";
"A":   PN = "1"  !CDS_PN = "1";
"B":   PN = "2"  !CDS_PN = "2";
BODY = "CAP_A","I135": #LOCATION = "C2T5" !CDS_LOCATION = "C2T5" #SEC = "1" !CDS_SEC = "1";
"A":   PN = "1"  !CDS_PN = "1";
"B":   PN = "2"  !CDS_PN = "2";
BODY = "RES","I136": #LOCATION = "R8F36" !CDS_LOCATION = "R8F36" #SEC = "1" !CDS_SEC = "1";
"A":   PN = "1"  !CDS_PN = "1";
"B":   PN = "2"  !CDS_PN = "2";
DRAWING = "@baseboard_fab2_lib.baseboard_fab2(sch_1):page186";
BODY = "CAP","I3": #LOCATION = "C1M27" !CDS_LOCATION = "C1M27" #SEC = "1" !CDS_SEC = "1";
"A":   PN = "1"  !CDS_PN = "1";
"B":   PN = "2"  !CDS_PN = "2";
BODY = "CAP","I6": #LOCATION = "C1M26" !CDS_LOCATION = "C1M26" #SEC = "1" !CDS_SEC = "1";
"A":   PN = "1"  !CDS_PN = "1";
"B":   PN = "2"  !CDS_PN = "2";
BODY = "CAP_A","I7": #LOCATION = "C1M23" !CDS_LOCATION = "C1M23" #SEC = "1" !CDS_SEC = "1";
"A":   PN = "1"  !CDS_PN = "1";
"B":   PN = "2"  !CDS_PN = "2";
BODY = "CAP_A","I8": #LOCATION = "C1M22" !CDS_LOCATION = "C1M22" #SEC = "1" !CDS_SEC = "1";
"A":   PN = "1"  !CDS_PN = "1";
"B":   PN = "2"  !CDS_PN = "2";
BODY = "CAP_A","I10": #LOCATION = "C1M24" !CDS_LOCATION = "C1M24" #SEC = "1" !CDS_SEC = "1";
"A":   PN = "1"  !CDS_PN = "1";
"B":   PN = "2"  !CDS_PN = "2";
BODY = "RES","I220": #LOCATION = "R1M14" !CDS_LOCATION = "R1M14" #SEC = "1" !CDS_SEC = "1";
"A":   PN = "1"  !CDS_PN = "1";
"B":   PN = "2"  !CDS_PN = "2";
BODY = "RES","I222": #LOCATION = "R9B7" !CDS_LOCATION = "R9B7" #SEC = "1" !CDS_SEC = "1";
"A":   PN = "1"  !CDS_PN = "1";
"B":   PN = "2"  !CDS_PN = "2";
BODY = "CAP_A","I270": #LOCATION = "C1M20" !CDS_LOCATION = "C1M20" &SEC = "1" #&CDS_SEC = "1";
"A":   PN = "1"  !CDS_PN = "1";
"B":   PN = "2"  !CDS_PN = "2";
BODY = "CAP_A","I334": #LOCATION = "C1M21" !CDS_LOCATION = "C1M21" #SEC = "1" !CDS_SEC = "1";
"A":   PN = "1"  !CDS_PN = "1";
"B":   PN = "2"  !CDS_PN = "2";
BODY = "CAP_A","I335": #LOCATION = "C1M25" !CDS_LOCATION = "C1M25" #SEC = "1" !CDS_SEC = "1";
"A":   PN = "1"  !CDS_PN = "1";
"B":   PN = "2"  !CDS_PN = "2";
BODY = "SCONN120_A28699018","I336": #LOCATION = "J9B3" !CDS_LOCATION = "J9B3" #SEC = "1" !CDS_SEC = "1";
"IO1":   PN = "1"  !CDS_PN = "1";
"IO2":   PN = "2"  !CDS_PN = "2";
"IO3":   PN = "3"  !CDS_PN = "3";
"IO4":   PN = "4"  !CDS_PN = "4";
"IO5":   PN = "5"  !CDS_PN = "5";
"IO6":   PN = "6"  !CDS_PN = "6";
"IO7":   PN = "7"  !CDS_PN = "7";
"IO8":   PN = "8"  !CDS_PN = "8";
"IO9":   PN = "9"  !CDS_PN = "9";
"IO10":   PN = "10"  !CDS_PN = "10";
"IO11":   PN = "11"  !CDS_PN = "11";
"IO12":   PN = "12"  !CDS_PN = "12";
"IO13":   PN = "13"  !CDS_PN = "13";
"IO14":   PN = "14"  !CDS_PN = "14";
"IO15":   PN = "15"  !CDS_PN = "15";
"IO16":   PN = "16"  !CDS_PN = "16";
"IO17":   PN = "17"  !CDS_PN = "17";
"IO18":   PN = "18"  !CDS_PN = "18";
"IO19":   PN = "19"  !CDS_PN = "19";
"IO20":   PN = "20"  !CDS_PN = "20";
"IO21":   PN = "21"  !CDS_PN = "21";
"IO22":   PN = "22"  !CDS_PN = "22";
"IO23":   PN = "23"  !CDS_PN = "23";
"IO24":   PN = "24"  !CDS_PN = "24";
"IO25":   PN = "25"  !CDS_PN = "25";
"IO26":   PN = "26"  !CDS_PN = "26";
"IO27":   PN = "27"  !CDS_PN = "27";
"IO28":   PN = "28"  !CDS_PN = "28";
"IO29":   PN = "29"  !CDS_PN = "29";
"IO30":   PN = "30"  !CDS_PN = "30";
"IO31":   PN = "31"  !CDS_PN = "31";
"IO32":   PN = "32"  !CDS_PN = "32";
"IO33":   PN = "33"  !CDS_PN = "33";
"IO34":   PN = "34"  !CDS_PN = "34";
"IO35":   PN = "35"  !CDS_PN = "35";
"IO36":   PN = "36"  !CDS_PN = "36";
"IO37":   PN = "37"  !CDS_PN = "37";
"IO38":   PN = "38"  !CDS_PN = "38";
"IO39":   PN = "39"  !CDS_PN = "39";
"IO40":   PN = "40"  !CDS_PN = "40";
"IO41":   PN = "41"  !CDS_PN = "41";
"IO42":   PN = "42"  !CDS_PN = "42";
"IO43":   PN = "43"  !CDS_PN = "43";
"IO44":   PN = "44"  !CDS_PN = "44";
"IO45":   PN = "45"  !CDS_PN = "45";
"IO46":   PN = "46"  !CDS_PN = "46";
"IO47":   PN = "47"  !CDS_PN = "47";
"IO48":   PN = "48"  !CDS_PN = "48";
"IO49":   PN = "49"  !CDS_PN = "49";
"IO50":   PN = "50"  !CDS_PN = "50";
"IO51":   PN = "51"  !CDS_PN = "51";
"IO52":   PN = "52"  !CDS_PN = "52";
"IO53":   PN = "53"  !CDS_PN = "53";
"IO54":   PN = "54"  !CDS_PN = "54";
"IO55":   PN = "55"  !CDS_PN = "55";
"IO56":   PN = "56"  !CDS_PN = "56";
"IO57":   PN = "57"  !CDS_PN = "57";
"IO58":   PN = "58"  !CDS_PN = "58";
"IO59":   PN = "59"  !CDS_PN = "59";
"IO60":   PN = "60"  !CDS_PN = "60";
"IO61":   PN = "61"  !CDS_PN = "61";
"IO62":   PN = "62"  !CDS_PN = "62";
"IO63":   PN = "63"  !CDS_PN = "63";
"IO64":   PN = "64"  !CDS_PN = "64";
"IO65":   PN = "65"  !CDS_PN = "65";
"IO66":   PN = "66"  !CDS_PN = "66";
"IO67":   PN = "67"  !CDS_PN = "67";
"IO68":   PN = "68"  !CDS_PN = "68";
"IO69":   PN = "69"  !CDS_PN = "69";
"IO70":   PN = "70"  !CDS_PN = "70";
"IO71":   PN = "71"  !CDS_PN = "71";
"IO72":   PN = "72"  !CDS_PN = "72";
"IO73":   PN = "73"  !CDS_PN = "73";
"IO74":   PN = "74"  !CDS_PN = "74";
"IO75":   PN = "75"  !CDS_PN = "75";
"IO76":   PN = "76"  !CDS_PN = "76";
"IO77":   PN = "77"  !CDS_PN = "77";
"IO78":   PN = "78"  !CDS_PN = "78";
"IO79":   PN = "79"  !CDS_PN = "79";
"IO80":   PN = "80"  !CDS_PN = "80";
"IO81":   PN = "81"  !CDS_PN = "81";
"IO82":   PN = "82"  !CDS_PN = "82";
"IO83":   PN = "83"  !CDS_PN = "83";
"IO84":   PN = "84"  !CDS_PN = "84";
"IO85":   PN = "85"  !CDS_PN = "85";
"IO86":   PN = "86"  !CDS_PN = "86";
"IO87":   PN = "87"  !CDS_PN = "87";
"IO88":   PN = "88"  !CDS_PN = "88";
"IO89":   PN = "89"  !CDS_PN = "89";
"IO90":   PN = "90"  !CDS_PN = "90";
"IO91":   PN = "91"  !CDS_PN = "91";
"IO92":   PN = "92"  !CDS_PN = "92";
"IO93":   PN = "93"  !CDS_PN = "93";
"IO94":   PN = "94"  !CDS_PN = "94";
"IO95":   PN = "95"  !CDS_PN = "95";
"IO96":   PN = "96"  !CDS_PN = "96";
"IO97":   PN = "97"  !CDS_PN = "97";
"IO98":   PN = "98"  !CDS_PN = "98";
"IO99":   PN = "99"  !CDS_PN = "99";
"IO100":   PN = "100"  !CDS_PN = "100";
"IO101":   PN = "101"  !CDS_PN = "101";
"IO102":   PN = "102"  !CDS_PN = "102";
"IO103":   PN = "103"  !CDS_PN = "103";
"IO104":   PN = "104"  !CDS_PN = "104";
"IO105":   PN = "105"  !CDS_PN = "105";
"IO106":   PN = "106"  !CDS_PN = "106";
"IO107":   PN = "107"  !CDS_PN = "107";
"IO108":   PN = "108"  !CDS_PN = "108";
"IO109":   PN = "109"  !CDS_PN = "109";
"IO110":   PN = "110"  !CDS_PN = "110";
"IO111":   PN = "111"  !CDS_PN = "111";
"IO112":   PN = "112"  !CDS_PN = "112";
"IO113":   PN = "113"  !CDS_PN = "113";
"IO114":   PN = "114"  !CDS_PN = "114";
"IO115":   PN = "115"  !CDS_PN = "115";
"IO116":   PN = "116"  !CDS_PN = "116";
"IO117":   PN = "117"  !CDS_PN = "117";
"IO118":   PN = "118"  !CDS_PN = "118";
"IO119":   PN = "119"  !CDS_PN = "119";
"IO120":   PN = "120"  !CDS_PN = "120";
BODY = "RES","I337": #LOCATION = "R1M16" !CDS_LOCATION = "R1M16" #SEC = "1" !CDS_SEC = "1";
"A":   PN = "1"  !CDS_PN = "1";
"B":   PN = "2"  !CDS_PN = "2";
BODY = "RES","I338": #LOCATION = "R1M17" !CDS_LOCATION = "R1M17" #SEC = "1" !CDS_SEC = "1";
"A":   PN = "1"  !CDS_PN = "1";
"B":   PN = "2"  !CDS_PN = "2";
BODY = "RES","I339": #LOCATION = "R1M15" !CDS_LOCATION = "R1M15" #SEC = "1" !CDS_SEC = "1";
"A":   PN = "1"  !CDS_PN = "1";
"B":   PN = "2"  !CDS_PN = "2";
BODY = "RES","I340": #LOCATION = "R1M18" !CDS_LOCATION = "R1M18" #SEC = "1" !CDS_SEC = "1";
"A":   PN = "1"  !CDS_PN = "1";
"B":   PN = "2"  !CDS_PN = "2";
BODY = "CAP_A","I345": #LOCATION = "C9B10" !CDS_LOCATION = "C9B10" #SEC = "1" !CDS_SEC = "1";
"A":   PN = "1"  !CDS_PN = "1";
"B":   PN = "2"  !CDS_PN = "2";
BODY = "CAP_A","I347": #LOCATION = "C9B9" !CDS_LOCATION = "C9B9" #SEC = "1" !CDS_SEC = "1";
"A":   PN = "1"  !CDS_PN = "1";
"B":   PN = "2"  !CDS_PN = "2";
DRAWING = "@baseboard_fab2_lib.baseboard_fab2(sch_1):page187";
BODY = "RES","I18": #LOCATION = "R2R8" !CDS_LOCATION = "R2R8" #SEC = "1" !CDS_SEC = "1";
"A":   PN = "1"  !CDS_PN = "1";
"B":   PN = "2"  !CDS_PN = "2";
BODY = "SCONN80_E67482007","I119": #LOCATION = "J8E3" !CDS_LOCATION = "J8E3" #SEC = "1" !CDS_SEC = "1";
"IO1":   PN = "1"  !CDS_PN = "1";
"IO2":   PN = "2"  !CDS_PN = "2";
"IO3":   PN = "3"  !CDS_PN = "3";
"IO4":   PN = "4"  !CDS_PN = "4";
"IO5":   PN = "5"  !CDS_PN = "5";
"IO6":   PN = "6"  !CDS_PN = "6";
"IO7":   PN = "7"  !CDS_PN = "7";
"IO8":   PN = "8"  !CDS_PN = "8";
"IO9":   PN = "9"  !CDS_PN = "9";
"IO10":   PN = "10"  !CDS_PN = "10";
"IO11":   PN = "11"  !CDS_PN = "11";
"IO12":   PN = "12"  !CDS_PN = "12";
"IO13":   PN = "13"  !CDS_PN = "13";
"IO14":   PN = "14"  !CDS_PN = "14";
"IO15":   PN = "15"  !CDS_PN = "15";
"IO16":   PN = "16"  !CDS_PN = "16";
"IO17":   PN = "17"  !CDS_PN = "17";
"IO18":   PN = "18"  !CDS_PN = "18";
"IO19":   PN = "19"  !CDS_PN = "19";
"IO20":   PN = "20"  !CDS_PN = "20";
"IO21":   PN = "21"  !CDS_PN = "21";
"IO22":   PN = "22"  !CDS_PN = "22";
"IO23":   PN = "23"  !CDS_PN = "23";
"IO24":   PN = "24"  !CDS_PN = "24";
"IO25":   PN = "25"  !CDS_PN = "25";
"IO26":   PN = "26"  !CDS_PN = "26";
"IO27":   PN = "27"  !CDS_PN = "27";
"IO28":   PN = "28"  !CDS_PN = "28";
"IO29":   PN = "29"  !CDS_PN = "29";
"IO30":   PN = "30"  !CDS_PN = "30";
"IO31":   PN = "31"  !CDS_PN = "31";
"IO32":   PN = "32"  !CDS_PN = "32";
"IO33":   PN = "33"  !CDS_PN = "33";
"IO34":   PN = "34"  !CDS_PN = "34";
"IO35":   PN = "35"  !CDS_PN = "35";
"IO36":   PN = "36"  !CDS_PN = "36";
"IO37":   PN = "37"  !CDS_PN = "37";
"IO38":   PN = "38"  !CDS_PN = "38";
"IO39":   PN = "39"  !CDS_PN = "39";
"IO40":   PN = "40"  !CDS_PN = "40";
"IO41":   PN = "41"  !CDS_PN = "41";
"IO42":   PN = "42"  !CDS_PN = "42";
"IO43":   PN = "43"  !CDS_PN = "43";
"IO44":   PN = "44"  !CDS_PN = "44";
"IO45":   PN = "45"  !CDS_PN = "45";
"IO46":   PN = "46"  !CDS_PN = "46";
"IO47":   PN = "47"  !CDS_PN = "47";
"IO48":   PN = "48"  !CDS_PN = "48";
"IO49":   PN = "49"  !CDS_PN = "49";
"IO50":   PN = "50"  !CDS_PN = "50";
"IO51":   PN = "51"  !CDS_PN = "51";
"IO52":   PN = "52"  !CDS_PN = "52";
"IO53":   PN = "53"  !CDS_PN = "53";
"IO54":   PN = "54"  !CDS_PN = "54";
"IO55":   PN = "55"  !CDS_PN = "55";
"IO56":   PN = "56"  !CDS_PN = "56";
"IO57":   PN = "57"  !CDS_PN = "57";
"IO58":   PN = "58"  !CDS_PN = "58";
"IO59":   PN = "59"  !CDS_PN = "59";
"IO60":   PN = "60"  !CDS_PN = "60";
"IO61":   PN = "61"  !CDS_PN = "61";
"IO62":   PN = "62"  !CDS_PN = "62";
"IO63":   PN = "63"  !CDS_PN = "63";
"IO64":   PN = "64"  !CDS_PN = "64";
"IO65":   PN = "65"  !CDS_PN = "65";
"IO66":   PN = "66"  !CDS_PN = "66";
"IO67":   PN = "67"  !CDS_PN = "67";
"IO68":   PN = "68"  !CDS_PN = "68";
"IO69":   PN = "69"  !CDS_PN = "69";
"IO70":   PN = "70"  !CDS_PN = "70";
"IO71":   PN = "71"  !CDS_PN = "71";
"IO72":   PN = "72"  !CDS_PN = "72";
"IO73":   PN = "73"  !CDS_PN = "73";
"IO74":   PN = "74"  !CDS_PN = "74";
"IO75":   PN = "75"  !CDS_PN = "75";
"IO76":   PN = "76"  !CDS_PN = "76";
"IO77":   PN = "77"  !CDS_PN = "77";
"IO78":   PN = "78"  !CDS_PN = "78";
"IO79":   PN = "79"  !CDS_PN = "79";
"IO80":   PN = "80"  !CDS_PN = "80";
BODY = "RES","I145": #LOCATION = "R9E10" !CDS_LOCATION = "R9E10" #SEC = "1" !CDS_SEC = "1";
"A":   PN = "1"  !CDS_PN = "1";
"B":   PN = "2"  !CDS_PN = "2";
BODY = "RES","I150": #LOCATION = "R9E11" !CDS_LOCATION = "R9E11" #SEC = "1" !CDS_SEC = "1";
"A":   PN = "1"  !CDS_PN = "1";
"B":   PN = "2"  !CDS_PN = "2";
BODY = "RES","I153": #LOCATION = "R9E12" !CDS_LOCATION = "R9E12" #SEC = "1" !CDS_SEC = "1";
"A":   PN = "1"  !CDS_PN = "1";
"B":   PN = "2"  !CDS_PN = "2";
DRAWING = "@baseboard_fab2_lib.baseboard_fab2(sch_1):page188";
BODY = "CAP_A","I2": #LOCATION = "C2R15" !CDS_LOCATION = "C2R15" #SEC = "1" !CDS_SEC = "1";
"A":   PN = "1"  !CDS_PN = "1";
"B":   PN = "2"  !CDS_PN = "2";
BODY = "CAP_A","I3": #LOCATION = "C2R18" !CDS_LOCATION = "C2R18" &SEC = "1" #&CDS_SEC = "1";
"A":   PN = "1"  !CDS_PN = "1";
"B":   PN = "2"  !CDS_PN = "2";
BODY = "CAP_A","I21": #LOCATION = "C2P11" !CDS_LOCATION = "C2P11" #SEC = "1" !CDS_SEC = "1";
"A":   PN = "1"  !CDS_PN = "1";
"B":   PN = "2"  !CDS_PN = "2";
BODY = "CAP_A","I23": #LOCATION = "C2P12" !CDS_LOCATION = "C2P12" #SEC = "1" !CDS_SEC = "1";
"A":   PN = "1"  !CDS_PN = "1";
"B":   PN = "2"  !CDS_PN = "2";
BODY = "CAP_A","I25": #LOCATION = "C2R17" !CDS_LOCATION = "C2R17" &SEC = "1" #&CDS_SEC = "1";
"A":   PN = "1"  !CDS_PN = "1";
"B":   PN = "2"  !CDS_PN = "2";
BODY = "SCONN64_H87568002_A","I27": #LOCATION = "J8E4" !CDS_LOCATION = "J8E4" #SEC = "1" !CDS_SEC = "1";
"IO1":   PN = "1"  !CDS_PN = "1";
"IO2":   PN = "2"  !CDS_PN = "2";
"IO3":   PN = "3"  !CDS_PN = "3";
"IO4":   PN = "4"  !CDS_PN = "4";
"IO5":   PN = "5"  !CDS_PN = "5";
"IO6":   PN = "6"  !CDS_PN = "6";
"IO7":   PN = "7"  !CDS_PN = "7";
"IO8":   PN = "8"  !CDS_PN = "8";
"IO9":   PN = "9"  !CDS_PN = "9";
"IO10":   PN = "10"  !CDS_PN = "10";
"IO11":   PN = "11"  !CDS_PN = "11";
"IO12":   PN = "12"  !CDS_PN = "12";
"IO13":   PN = "13"  !CDS_PN = "13";
"IO14":   PN = "14"  !CDS_PN = "14";
"IO15":   PN = "15"  !CDS_PN = "15";
"IO16":   PN = "16"  !CDS_PN = "16";
"IO17":   PN = "17"  !CDS_PN = "17";
"IO18":   PN = "18"  !CDS_PN = "18";
"IO19":   PN = "19"  !CDS_PN = "19";
"IO20":   PN = "20"  !CDS_PN = "20";
"IO21":   PN = "21"  !CDS_PN = "21";
"IO22":   PN = "22"  !CDS_PN = "22";
"IO23":   PN = "23"  !CDS_PN = "23";
"IO24":   PN = "24"  !CDS_PN = "24";
"IO25":   PN = "25"  !CDS_PN = "25";
"IO26":   PN = "26"  !CDS_PN = "26";
"IO27":   PN = "27"  !CDS_PN = "27";
"IO28":   PN = "28"  !CDS_PN = "28";
"IO29":   PN = "29"  !CDS_PN = "29";
"IO30":   PN = "30"  !CDS_PN = "30";
"IO31":   PN = "31"  !CDS_PN = "31";
"IO32":   PN = "32"  !CDS_PN = "32";
"IO33":   PN = "33"  !CDS_PN = "33";
"IO34":   PN = "34"  !CDS_PN = "34";
"IO35":   PN = "35"  !CDS_PN = "35";
"IO36":   PN = "36"  !CDS_PN = "36";
"IO37":   PN = "37"  !CDS_PN = "37";
"IO38":   PN = "38"  !CDS_PN = "38";
"IO39":   PN = "39"  !CDS_PN = "39";
"IO40":   PN = "40"  !CDS_PN = "40";
"IO41":   PN = "41"  !CDS_PN = "41";
"IO42":   PN = "42"  !CDS_PN = "42";
"IO43":   PN = "43"  !CDS_PN = "43";
"IO44":   PN = "44"  !CDS_PN = "44";
"IO45":   PN = "45"  !CDS_PN = "45";
"IO46":   PN = "46"  !CDS_PN = "46";
"IO47":   PN = "47"  !CDS_PN = "47";
"IO48":   PN = "48"  !CDS_PN = "48";
"IO49":   PN = "49"  !CDS_PN = "49";
"IO50":   PN = "50"  !CDS_PN = "50";
"IO51":   PN = "51"  !CDS_PN = "51";
"IO52":   PN = "52"  !CDS_PN = "52";
"IO53":   PN = "53"  !CDS_PN = "53";
"IO54":   PN = "54"  !CDS_PN = "54";
"IO55":   PN = "55"  !CDS_PN = "55";
"IO56":   PN = "56"  !CDS_PN = "56";
"IO57":   PN = "57"  !CDS_PN = "57";
"IO58":   PN = "58"  !CDS_PN = "58";
"IO59":   PN = "59"  !CDS_PN = "59";
"IO60":   PN = "60"  !CDS_PN = "60";
"IO61":   PN = "61"  !CDS_PN = "61";
"IO62":   PN = "62"  !CDS_PN = "62";
"IO63":   PN = "63"  !CDS_PN = "63";
"IO64":   PN = "64"  !CDS_PN = "64";
BODY = "CAP_A","I40": #LOCATION = "C2R16" !CDS_LOCATION = "C2R16" &SEC = "1" #&CDS_SEC = "1";
"A":   PN = "1"  !CDS_PN = "1";
"B":   PN = "2"  !CDS_PN = "2";
BODY = "CAP","I41": #LOCATION = "C2P10" !CDS_LOCATION = "C2P10" #SEC = "1" !CDS_SEC = "1";
"A":   PN = "1"  !CDS_PN = "1";
"B":   PN = "2"  !CDS_PN = "2";
BODY = "CAP_A","I53": #LOCATION = "C2P16" !CDS_LOCATION = "C2P16" &SEC = "1" #&CDS_SEC = "1";
"A":   PN = "1"  !CDS_PN = "1";
"B":   PN = "2"  !CDS_PN = "2";
BODY = "CAP_A","I55": #LOCATION = "C2P15" !CDS_LOCATION = "C2P15" &SEC = "1" #&CDS_SEC = "1";
"A":   PN = "1"  !CDS_PN = "1";
"B":   PN = "2"  !CDS_PN = "2";
BODY = "CAP_A","I56": #LOCATION = "C2P14" !CDS_LOCATION = "C2P14" &SEC = "1" #&CDS_SEC = "1";
"A":   PN = "1"  !CDS_PN = "1";
"B":   PN = "2"  !CDS_PN = "2";
BODY = "CAP_A","I57": #LOCATION = "C2P13" !CDS_LOCATION = "C2P13" &SEC = "1" #&CDS_SEC = "1";
"A":   PN = "1"  !CDS_PN = "1";
"B":   PN = "2"  !CDS_PN = "2";
BODY = "CAP_A","I64": #LOCATION = "C8C8" !CDS_LOCATION = "C8C8" #SEC = "1" !CDS_SEC = "1";
"A":   PN = "1"  !CDS_PN = "1";
"B":   PN = "2"  !CDS_PN = "2";
BODY = "CAP_A","I68": #LOCATION = "C8C9" !CDS_LOCATION = "C8C9" #SEC = "1" !CDS_SEC = "1";
"A":   PN = "1"  !CDS_PN = "1";
"B":   PN = "2"  !CDS_PN = "2";
BODY = "CAP_A","I72": #LOCATION = "C8C11" !CDS_LOCATION = "C8C11" #SEC = "1" !CDS_SEC = "1";
"A":   PN = "1"  !CDS_PN = "1";
"B":   PN = "2"  !CDS_PN = "2";
BODY = "CAP_A","I73": #LOCATION = "C8C10" !CDS_LOCATION = "C8C10" #SEC = "1" !CDS_SEC = "1";
"A":   PN = "1"  !CDS_PN = "1";
"B":   PN = "2"  !CDS_PN = "2";
BODY = "CAP_A","I80": #LOCATION = "C8C12" !CDS_LOCATION = "C8C12" #SEC = "1" !CDS_SEC = "1";
"A":   PN = "1"  !CDS_PN = "1";
"B":   PN = "2"  !CDS_PN = "2";
BODY = "CAP_A","I81": #LOCATION = "C8C13" !CDS_LOCATION = "C8C13" #SEC = "1" !CDS_SEC = "1";
"A":   PN = "1"  !CDS_PN = "1";
"B":   PN = "2"  !CDS_PN = "2";
BODY = "CAP_A","I82": #LOCATION = "C8C15" !CDS_LOCATION = "C8C15" #SEC = "1" !CDS_SEC = "1";
"A":   PN = "1"  !CDS_PN = "1";
"B":   PN = "2"  !CDS_PN = "2";
BODY = "CAP_A","I86": #LOCATION = "C8C14" !CDS_LOCATION = "C8C14" #SEC = "1" !CDS_SEC = "1";
"A":   PN = "1"  !CDS_PN = "1";
"B":   PN = "2"  !CDS_PN = "2";
BODY = "RES","I88": #LOCATION = "R1R18" !CDS_LOCATION = "R1R18" #SEC = "1" !CDS_SEC = "1";
"A":   PN = "1"  !CDS_PN = "1";
"B":   PN = "2"  !CDS_PN = "2";
BODY = "RES","I89": #LOCATION = "R1R19" !CDS_LOCATION = "R1R19" #SEC = "1" !CDS_SEC = "1";
"A":   PN = "1"  !CDS_PN = "1";
"B":   PN = "2"  !CDS_PN = "2";
BODY = "RES","I90": #LOCATION = "R1R21" !CDS_LOCATION = "R1R21" #SEC = "1" !CDS_SEC = "1";
"A":   PN = "1"  !CDS_PN = "1";
"B":   PN = "2"  !CDS_PN = "2";
BODY = "RES","I91": #LOCATION = "R1R20" !CDS_LOCATION = "R1R20" #SEC = "1" !CDS_SEC = "1";
"A":   PN = "1"  !CDS_PN = "1";
"B":   PN = "2"  !CDS_PN = "2";
BODY = "RES","I92": #LOCATION = "R1R22" !CDS_LOCATION = "R1R22" #SEC = "1" !CDS_SEC = "1";
"A":   PN = "1"  !CDS_PN = "1";
"B":   PN = "2"  !CDS_PN = "2";
BODY = "RES","I93": #LOCATION = "R1R16" !CDS_LOCATION = "R1R16" #SEC = "1" !CDS_SEC = "1";
"A":   PN = "1"  !CDS_PN = "1";
"B":   PN = "2"  !CDS_PN = "2";
BODY = "RES","I94": #LOCATION = "R1R17" !CDS_LOCATION = "R1R17" #SEC = "1" !CDS_SEC = "1";
"A":   PN = "1"  !CDS_PN = "1";
"B":   PN = "2"  !CDS_PN = "2";
BODY = "RES","I95": #LOCATION = "R1R23" !CDS_LOCATION = "R1R23" #SEC = "1" !CDS_SEC = "1";
"A":   PN = "1"  !CDS_PN = "1";
"B":   PN = "2"  !CDS_PN = "2";
DRAWING = "@baseboard_fab2_lib.baseboard_fab2(sch_1):page189";
BODY = "RES","I7": #LOCATION = "R8G10" !CDS_LOCATION = "R8G10" #SEC = "1" !CDS_SEC = "1";
"A":   PN = "1"  !CDS_PN = "1";
"B":   PN = "2"  !CDS_PN = "2";
BODY = "RES","I8": #LOCATION = "R7G19" !CDS_LOCATION = "R7G19" #SEC = "1" !CDS_SEC = "1";
"A":   PN = "1"  !CDS_PN = "1";
"B":   PN = "2"  !CDS_PN = "2";
BODY = "RES","I9": #LOCATION = "R8G9" !CDS_LOCATION = "R8G9" &SEC = "1" #&CDS_SEC = "1";
"A":   PN = "1"  !CDS_PN = "1";
"B":   PN = "2"  !CDS_PN = "2";
BODY = "RES","I13": #LOCATION = "R7G18" !CDS_LOCATION = "R7G18" #SEC = "1" !CDS_SEC = "1";
"A":   PN = "1"  !CDS_PN = "1";
"B":   PN = "2"  !CDS_PN = "2";
BODY = "RES","I17": #LOCATION = "R8G8" !CDS_LOCATION = "R8G8" #SEC = "1" !CDS_SEC = "1";
"A":   PN = "1"  !CDS_PN = "1";
"B":   PN = "2"  !CDS_PN = "2";
BODY = "RES","I18": #LOCATION = "R8G7" !CDS_LOCATION = "R8G7" #SEC = "1" !CDS_SEC = "1";
"A":   PN = "1"  !CDS_PN = "1";
"B":   PN = "2"  !CDS_PN = "2";
BODY = "RES","I19": #LOCATION = "R8G11" !CDS_LOCATION = "R8G11" #SEC = "1" !CDS_SEC = "1";
"A":   PN = "1"  !CDS_PN = "1";
"B":   PN = "2"  !CDS_PN = "2";
BODY = "RES","I20": #LOCATION = "R8G14" !CDS_LOCATION = "R8G14" #SEC = "1" !CDS_SEC = "1";
"A":   PN = "1"  !CDS_PN = "1";
"B":   PN = "2"  !CDS_PN = "2";
BODY = "RES","I21": #LOCATION = "R8G12" !CDS_LOCATION = "R8G12" #SEC = "1" !CDS_SEC = "1";
"A":   PN = "1"  !CDS_PN = "1";
"B":   PN = "2"  !CDS_PN = "2";
BODY = "RES","I22": #LOCATION = "R8G16" !CDS_LOCATION = "R8G16" #SEC = "1" !CDS_SEC = "1";
"A":   PN = "1"  !CDS_PN = "1";
"B":   PN = "2"  !CDS_PN = "2";
BODY = "RES","I23": #LOCATION = "R8G13" !CDS_LOCATION = "R8G13" #SEC = "1" !CDS_SEC = "1";
"A":   PN = "1"  !CDS_PN = "1";
"B":   PN = "2"  !CDS_PN = "2";
BODY = "RES","I24": #LOCATION = "R8G15" !CDS_LOCATION = "R8G15" #SEC = "1" !CDS_SEC = "1";
"A":   PN = "1"  !CDS_PN = "1";
"B":   PN = "2"  !CDS_PN = "2";
BODY = "RES","I25": #LOCATION = "R8G17" !CDS_LOCATION = "R8G17" #SEC = "1" !CDS_SEC = "1";
"A":   PN = "1"  !CDS_PN = "1";
"B":   PN = "2"  !CDS_PN = "2";
BODY = "RES","I26": #LOCATION = "R8G18" !CDS_LOCATION = "R8G18" #SEC = "1" !CDS_SEC = "1";
"A":   PN = "1"  !CDS_PN = "1";
"B":   PN = "2"  !CDS_PN = "2";
BODY = "RES","I27": #LOCATION = "R7G16" !CDS_LOCATION = "R7G16" #SEC = "1" !CDS_SEC = "1";
"A":   PN = "1"  !CDS_PN = "1";
"B":   PN = "2"  !CDS_PN = "2";
BODY = "RES","I36": #LOCATION = "R7G15" !CDS_LOCATION = "R7G15" #SEC = "1" !CDS_SEC = "1";
"A":   PN = "1"  !CDS_PN = "1";
"B":   PN = "2"  !CDS_PN = "2";
BODY = "RES","I37": #LOCATION = "R7G17" !CDS_LOCATION = "R7G17" #SEC = "1" !CDS_SEC = "1";
"A":   PN = "1"  !CDS_PN = "1";
"B":   PN = "2"  !CDS_PN = "2";
BODY = "RES","I38": #LOCATION = "R7G14" !CDS_LOCATION = "R7G14" #SEC = "1" !CDS_SEC = "1";
"A":   PN = "1"  !CDS_PN = "1";
"B":   PN = "2"  !CDS_PN = "2";
BODY = "RES","I44": #LOCATION = "R3R15" !CDS_LOCATION = "R3R15" #SEC = "1" !CDS_SEC = "1";
"A":   PN = "1"  !CDS_PN = "1";
"B":   PN = "2"  !CDS_PN = "2";
BODY = "RES","I45": #LOCATION = "R3R11" !CDS_LOCATION = "R3R11" #SEC = "1" !CDS_SEC = "1";
"A":   PN = "1"  !CDS_PN = "1";
"B":   PN = "2"  !CDS_PN = "2";
BODY = "CONN8_C77962004","I47": #LOCATION = "J7G2" !CDS_LOCATION = "J7G2" #SEC = "1" !CDS_SEC = "1";
"IO1":   PN = "1"  !CDS_PN = "1";
"IO2":   PN = "2"  !CDS_PN = "2";
"IO3":   PN = "3"  !CDS_PN = "3";
"IO4":   PN = "4"  !CDS_PN = "4";
"IO5":   PN = "5"  !CDS_PN = "5";
"IO6":   PN = "6"  !CDS_PN = "6";
"IO7":   PN = "7"  !CDS_PN = "7";
"IO8":   PN = "8"  !CDS_PN = "8";
BODY = "DIODE","I49": #LOCATION = "CR3U1" !CDS_LOCATION = "CR3U1" #SEC = "1" !CDS_SEC = "1";
"A":   PN = "2"  !CDS_PN = "2";
"C":   PN = "1"  !CDS_PN = "1";
BODY = "RES","I50": #LOCATION = "R8G20" !CDS_LOCATION = "R8G20" &SEC = "1" #&CDS_SEC = "1";
"A":   PN = "1"  !CDS_PN = "1";
"B":   PN = "2"  !CDS_PN = "2";
BODY = "RES","I51": #LOCATION = "R7G23" !CDS_LOCATION = "R7G23" &SEC = "1" #&CDS_SEC = "1";
"A":   PN = "1"  !CDS_PN = "1";
"B":   PN = "2"  !CDS_PN = "2";
BODY = "RES","I53": #LOCATION = "R7G22" !CDS_LOCATION = "R7G22" &SEC = "1" #&CDS_SEC = "1";
"A":   PN = "1"  !CDS_PN = "1";
"B":   PN = "2"  !CDS_PN = "2";
BODY = "RES","I56": #LOCATION = "R8G23" !CDS_LOCATION = "R8G23" #SEC = "1" !CDS_SEC = "1";
"A":   PN = "1"  !CDS_PN = "1";
"B":   PN = "2"  !CDS_PN = "2";
BODY = "RES","I63": #LOCATION = "R7G21" !CDS_LOCATION = "R7G21" #SEC = "1" !CDS_SEC = "1";
"A":   PN = "1"  !CDS_PN = "1";
"B":   PN = "2"  !CDS_PN = "2";
BODY = "RES","I64": #LOCATION = "R8G19" !CDS_LOCATION = "R8G19" #SEC = "1" !CDS_SEC = "1";
"A":   PN = "1"  !CDS_PN = "1";
"B":   PN = "2"  !CDS_PN = "2";
BODY = "RES","I65": #LOCATION = "R8G21" !CDS_LOCATION = "R8G21" #SEC = "1" !CDS_SEC = "1";
"A":   PN = "1"  !CDS_PN = "1";
"B":   PN = "2"  !CDS_PN = "2";
BODY = "RES","I66": #LOCATION = "R8G22" !CDS_LOCATION = "R8G22" #SEC = "1" !CDS_SEC = "1";
"A":   PN = "1"  !CDS_PN = "1";
"B":   PN = "2"  !CDS_PN = "2";
DRAWING = "@baseboard_fab2_lib.baseboard_fab2(sch_1):page190";
BODY = "RES","I116": #LOCATION = "R3P34" !CDS_LOCATION = "R3P34" #SEC = "1" !CDS_SEC = "1";
"A":   PN = "1"  !CDS_PN = "1";
"B":   PN = "2"  !CDS_PN = "2";
BODY = "RES","I117": #LOCATION = "R3P35" !CDS_LOCATION = "R3P35" #SEC = "1" !CDS_SEC = "1";
"A":   PN = "1"  !CDS_PN = "1";
"B":   PN = "2"  !CDS_PN = "2";
BODY = "LCMXO2_A","I179": #LOCATION = "U8D7" !CDS_LOCATION = "U8D7" #SEC = "1" !CDS_SEC = "1";
"PB3A":   PN = "P4"  !CDS_PN = "P4";
"PB3B":   PN = "T4"  !CDS_PN = "T4";
"PB3C":   PN = "T2"  !CDS_PN = "T2";
"PB3D":   PN = "R3"  !CDS_PN = "R3";
"PB5A_CSSPIN":   PN = "R5"  !CDS_PN = "R5";
"PB5B":   PN = "P5"  !CDS_PN = "P5";
"PB6A":   PN = "T5"  !CDS_PN = "T5";
"PB6B":   PN = "R6"  !CDS_PN = "R6";
"PB6C":   PN = "T3"  !CDS_PN = "T3";
"PB6D":   PN = "R4"  !CDS_PN = "R4";
"PB8A_MCLK_CCLK":   PN = "P6"  !CDS_PN = "P6";
"PB8B_SO_SPISO":   PN = "T6"  !CDS_PN = "T6";
"PB8C":   PN = "N6"  !CDS_PN = "N6";
"PB8D":   PN = "L7"  !CDS_PN = "L7";
"PB9A":   PN = "R7"  !CDS_PN = "R7";
"PB9B":   PN = "P7"  !CDS_PN = "P7";
"PB9C":   PN = "M7"  !CDS_PN = "M7";
"PB9D":   PN = "N7"  !CDS_PN = "N7";
"PB11A_PCLKT2_0":   PN = "T7"  !CDS_PN = "T7";
"PB11B_PCLKC2_0":   PN = "R8"  !CDS_PN = "R8";
"PB11C":   PN = "M6"  !CDS_PN = "M6";
"PB11D":   PN = "L8"  !CDS_PN = "L8";
"PB12A":   PN = "P8"  !CDS_PN = "P8";
"PB12B":   PN = "T8"  !CDS_PN = "T8";
"PB12C":   PN = "N8"  !CDS_PN = "N8";
"PB12D":   PN = "L9"  !CDS_PN = "L9";
"PB16A_PCLKT2_1":   PN = "T9"  !CDS_PN = "T9";
"PB16B_PCLKC2_1":   PN = "P9"  !CDS_PN = "P9";
"PB16C":   PN = "M8"  !CDS_PN = "M8";
"PB16D":   PN = "N9"  !CDS_PN = "N9";
"PB18A":   PN = "R9"  !CDS_PN = "R9";
"PB18B":   PN = "T10"  !CDS_PN = "T10";
"PB18C":   PN = "M9"  !CDS_PN = "M9";
"PB18D":   PN = "L10"  !CDS_PN = "L10";
"PB19A":   PN = "P10"  !CDS_PN = "P10";
"PB19B":   PN = "R10"  !CDS_PN = "R10";
"PB19C":   PN = "N10"  !CDS_PN = "N10";
"PB19D":   PN = "M11"  !CDS_PN = "M11";
"PB21A":   PN = "T11"  !CDS_PN = "T11";
"PB21B":   PN = "P11"  !CDS_PN = "P11";
"PB21C":   PN = "M10"  !CDS_PN = "M10";
"PB21D":   PN = "N11"  !CDS_PN = "N11";
"PB22A":   PN = "R11"  !CDS_PN = "R11";
"PB22B":   PN = "T12"  !CDS_PN = "T12";
"PB22C":   PN = "R13"  !CDS_PN = "R13";
"PB22D":   PN = "T14"  !CDS_PN = "T14";
"PB24A":   PN = "P12"  !CDS_PN = "P12";
"PB24B":   PN = "T13"  !CDS_PN = "T13";
"PB25A_SN":   PN = "R12"  !CDS_PN = "R12";
"PB25B_SI_SISPI":   PN = "P13"  !CDS_PN = "P13";
"PB25C":   PN = "T15"  !CDS_PN = "T15";
"PB25D":   PN = "R14"  !CDS_PN = "R14";
"PL1A_L_GPLLT_FB":   PN = "D3"  !CDS_PN = "D3";
"PL1B_L_GPLLC_FB":   PN = "D1"  !CDS_PN = "D1";
"PL1C":   PN = "B1"  !CDS_PN = "B1";
"PL1D":   PN = "C2"  !CDS_PN = "C2";
"PL2A_L_GPLLT_IN":   PN = "E2"  !CDS_PN = "E2";
"PL2B_L_GPLLC_IN":   PN = "E3"  !CDS_PN = "E3";
"PL2C":   PN = "C1"  !CDS_PN = "C1";
"PL2D":   PN = "D2"  !CDS_PN = "D2";
"PL3A_PCLKT5_0":   PN = "E1"  !CDS_PN = "E1";
"PL3B_PCLKC5_0":   PN = "F2"  !CDS_PN = "F2";
"PL3C":   PN = "F4"  !CDS_PN = "F4";
"PL3D":   PN = "G6"  !CDS_PN = "G6";
"PL4A":   PN = "F3"  !CDS_PN = "F3";
"PL4B":   PN = "F1"  !CDS_PN = "F1";
"PL4C":   PN = "G5"  !CDS_PN = "G5";
"PL4D":   PN = "G4"  !CDS_PN = "G4";
"PL5A":   PN = "G2"  !CDS_PN = "G2";
"PL5B":   PN = "G3"  !CDS_PN = "G3";
"PL5C":   PN = "F5"  !CDS_PN = "F5";
"PL5D":   PN = "H6"  !CDS_PN = "H6";
"PL6A":   PN = "G1"  !CDS_PN = "G1";
"PL6B":   PN = "H2"  !CDS_PN = "H2";
"PL6C":   PN = "H4"  !CDS_PN = "H4";
"PL6D":   PN = "J6"  !CDS_PN = "J6";
"PL7A":   PN = "H3"  !CDS_PN = "H3";
"PL7B":   PN = "H1"  !CDS_PN = "H1";
"PL7C_PCLKT4_0":   PN = "J1"  !CDS_PN = "J1";
"PL7D_PCLKC4_0":   PN = "J3"  !CDS_PN = "J3";
"PL9A":   PN = "J2"  !CDS_PN = "J2";
"PL9B":   PN = "K1"  !CDS_PN = "K1";
"PL9C":   PN = "H5"  !CDS_PN = "H5";
"PL9D":   PN = "J4"  !CDS_PN = "J4";
"PL10A":   PN = "K3"  !CDS_PN = "K3";
"PL10B":   PN = "K2"  !CDS_PN = "K2";
"PL10C":   PN = "J5"  !CDS_PN = "J5";
"PL10D":   PN = "K6"  !CDS_PN = "K6";
"PL11A":   PN = "L1"  !CDS_PN = "L1";
"PL11B":   PN = "L3"  !CDS_PN = "L3";
"PL11C":   PN = "K4"  !CDS_PN = "K4";
"PL11D":   PN = "L5"  !CDS_PN = "L5";
"PL12A_PCLKT3_0":   PN = "L2"  !CDS_PN = "L2";
"PL12B_PCLKC3_0":   PN = "M1"  !CDS_PN = "M1";
"PL12C":   PN = "K5"  !CDS_PN = "K5";
"PL12D":   PN = "L4"  !CDS_PN = "L4";
"PL13A":   PN = "M3"  !CDS_PN = "M3";
"PL13B":   PN = "N1"  !CDS_PN = "N1";
"PL13C":   PN = "N2"  !CDS_PN = "N2";
"PL13D":   PN = "P1"  !CDS_PN = "P1";
"PL14A":   PN = "M2"  !CDS_PN = "M2";
"PL14B":   PN = "N3"  !CDS_PN = "N3";
"PL14C":   PN = "R1"  !CDS_PN = "R1";
"PL14D":   PN = "P2"  !CDS_PN = "P2";
BODY = "RES","I338": #LOCATION = "R2R2" !CDS_LOCATION = "R2R2" &SEC = "1" #&CDS_SEC = "1";
"A":   PN = "1"  !CDS_PN = "1";
"B":   PN = "2"  !CDS_PN = "2";
DRAWING = "@baseboard_fab2_lib.baseboard_fab2(sch_1):page191";
BODY = "LCMXO2_A","I59": #LOCATION = "U8D7" !CDS_LOCATION = "U8D7" #SEC = "2" !CDS_SEC = "2";
"PR1A":   PN = "D14"  !CDS_PN = "D14";
"PR1B":   PN = "E15"  !CDS_PN = "E15";
"PR1C":   PN = "C15"  !CDS_PN = "C15";
"PR1D":   PN = "B16"  !CDS_PN = "B16";
"PR2A":   PN = "D16"  !CDS_PN = "D16";
"PR2B":   PN = "E14"  !CDS_PN = "E14";
"PR2C":   PN = "C16"  !CDS_PN = "C16";
"PR2D":   PN = "D15"  !CDS_PN = "D15";
"PR3A":   PN = "E16"  !CDS_PN = "E16";
"PR3B":   PN = "F15"  !CDS_PN = "F15";
"PR3C":   PN = "F13"  !CDS_PN = "F13";
"PR3D":   PN = "G12"  !CDS_PN = "G12";
"PR4A":   PN = "F14"  !CDS_PN = "F14";
"PR4B":   PN = "F16"  !CDS_PN = "F16";
"PR4C":   PN = "F12"  !CDS_PN = "F12";
"PR4D":   PN = "G13"  !CDS_PN = "G13";
"PR5A":   PN = "G15"  !CDS_PN = "G15";
"PR5B":   PN = "G14"  !CDS_PN = "G14";
"PR5C":   PN = "G11"  !CDS_PN = "G11";
"PR5D":   PN = "H12"  !CDS_PN = "H12";
"PR6A":   PN = "G16"  !CDS_PN = "G16";
"PR6B":   PN = "H15"  !CDS_PN = "H15";
"PR6C":   PN = "H13"  !CDS_PN = "H13";
"PR6D":   PN = "J12"  !CDS_PN = "J12";
"PR7A_PCLKT1_0":   PN = "H14"  !CDS_PN = "H14";
"PR7B_PCLKC1_0":   PN = "H16"  !CDS_PN = "H16";
"PR7C":   PN = "J16"  !CDS_PN = "J16";
"PR7D":   PN = "J14"  !CDS_PN = "J14";
"PR9A":   PN = "J15"  !CDS_PN = "J15";
"PR9B":   PN = "K16"  !CDS_PN = "K16";
"PR9C":   PN = "H11"  !CDS_PN = "H11";
"PR9D":   PN = "J13"  !CDS_PN = "J13";
"PR10A":   PN = "K14"  !CDS_PN = "K14";
"PR10B":   PN = "K15"  !CDS_PN = "K15";
"PR10C":   PN = "J11"  !CDS_PN = "J11";
"PR10D":   PN = "L12"  !CDS_PN = "L12";
"PR11A":   PN = "L16"  !CDS_PN = "L16";
"PR11B":   PN = "L14"  !CDS_PN = "L14";
"PR11C":   PN = "K13"  !CDS_PN = "K13";
"PR11D":   PN = "K12"  !CDS_PN = "K12";
"PR12A":   PN = "L15"  !CDS_PN = "L15";
"PR12B":   PN = "M16"  !CDS_PN = "M16";
"PR12C":   PN = "K11"  !CDS_PN = "K11";
"PR12D":   PN = "L13"  !CDS_PN = "L13";
"PR13A":   PN = "M14"  !CDS_PN = "M14";
"PR13B":   PN = "M15"  !CDS_PN = "M15";
"PR13C":   PN = "N15"  !CDS_PN = "N15";
"PR13D":   PN = "P16"  !CDS_PN = "P16";
"PR14A":   PN = "N16"  !CDS_PN = "N16";
"PR14B":   PN = "N14"  !CDS_PN = "N14";
"PR14C":   PN = "P15"  !CDS_PN = "P15";
"PR14D":   PN = "R16"  !CDS_PN = "R16";
"PT9A":   PN = "C4"  !CDS_PN = "C4";
"PT9B":   PN = "B5"  !CDS_PN = "B5";
"PT9C":   PN = "B3"  !CDS_PN = "B3";
"PT10A":   PN = "A4"  !CDS_PN = "A4";
"PT10B":   PN = "C5"  !CDS_PN = "C5";
"PT11A":   PN = "A5"  !CDS_PN = "A5";
"PT11B":   PN = "B6"  !CDS_PN = "B6";
"PT11C":   PN = "A3"  !CDS_PN = "A3";
"PT11D":   PN = "B4"  !CDS_PN = "B4";
"PT12A":   PN = "D6"  !CDS_PN = "D6";
"PT12B":   PN = "E7"  !CDS_PN = "E7";
"PT12C_TDO":   PN = "C6"  !CDS_PN = "C6";
"PT12D_TDI":   PN = "A6"  !CDS_PN = "A6";
"PT13A":   PN = "B7"  !CDS_PN = "B7";
"PT13B":   PN = "C7"  !CDS_PN = "C7";
"PT13C":   PN = "E6"  !CDS_PN = "E6";
"PT13D":   PN = "D7"  !CDS_PN = "D7";
"PT16A":   PN = "F7"  !CDS_PN = "F7";
"PT16B":   PN = "E8"  !CDS_PN = "E8";
"PT16C_TCK":   PN = "A7"  !CDS_PN = "A7";
"PT16D_TMS":   PN = "B8"  !CDS_PN = "B8";
"PT17A_PCLKT0_1":   PN = "C8"  !CDS_PN = "C8";
"PT17B_PCLKC0_1":   PN = "A8"  !CDS_PN = "A8";
"PT17C":   PN = "D8"  !CDS_PN = "D8";
"PT17D":   PN = "E9"  !CDS_PN = "E9";
"PT18A":   PN = "F8"  !CDS_PN = "F8";
"PT18B":   PN = "D9"  !CDS_PN = "D9";
"PT18C_SCL_PCLKT0_0":   PN = "A9"  !CDS_PN = "A9";
"PT18D_SDA_PCLKC0_0":   PN = "C9"  !CDS_PN = "C9";
"PT19A":   PN = "B9"  !CDS_PN = "B9";
"PT19B":   PN = "A10"  !CDS_PN = "A10";
"PT19C":   PN = "F9"  !CDS_PN = "F9";
"PT19D":   PN = "E11"  !CDS_PN = "E11";
"PT20A":   PN = "D10"  !CDS_PN = "D10";
"PT20B":   PN = "E10"  !CDS_PN = "E10";
"PT20C_JTAGENB":   PN = "C10"  !CDS_PN = "C10";
"PT20D_PROGRAMN":   PN = "B10"  !CDS_PN = "B10";
"PT21A":   PN = "A11"  !CDS_PN = "A11";
"PT21B":   PN = "C11"  !CDS_PN = "C11";
"PT21C":   PN = "F10"  !CDS_PN = "F10";
"PT21D":   PN = "D11"  !CDS_PN = "D11";
"PT22A":   PN = "B11"  !CDS_PN = "B11";
"PT22B":   PN = "A12"  !CDS_PN = "A12";
"PT22C":   PN = "B13"  !CDS_PN = "B13";
"PT22D":   PN = "A14"  !CDS_PN = "A14";
"PT23A":   PN = "C12"  !CDS_PN = "C12";
"PT23B":   PN = "B12"  !CDS_PN = "B12";
"PT24A":   PN = "B14"  !CDS_PN = "B14";
"PT24B":   PN = "A15"  !CDS_PN = "A15";
"PT24C_INITN":   PN = "A13"  !CDS_PN = "A13";
"PT24D_DONE":   PN = "C13"  !CDS_PN = "C13";
BODY = "RES","I166": #LOCATION = "R2R6" !CDS_LOCATION = "R2R6" #SEC = "1" !CDS_SEC = "1";
"A":   PN = "1"  !CDS_PN = "1";
"B":   PN = "2"  !CDS_PN = "2";
BODY = "RES","I172": #LOCATION = "R2R7" !CDS_LOCATION = "R2R7" #SEC = "1" !CDS_SEC = "1";
"A":   PN = "1"  !CDS_PN = "1";
"B":   PN = "2"  !CDS_PN = "2";
BODY = "RES","I184": #LOCATION = "R2R4" !CDS_LOCATION = "R2R4" &SEC = "1" #&CDS_SEC = "1";
"A":   PN = "1"  !CDS_PN = "1";
"B":   PN = "2"  !CDS_PN = "2";
BODY = "RES","I193": #LOCATION = "R7D42" !CDS_LOCATION = "R7D42" #SEC = "1" !CDS_SEC = "1";
"A":   PN = "1"  !CDS_PN = "1";
"B":   PN = "2"  !CDS_PN = "2";
DRAWING = "@baseboard_fab2_lib.baseboard_fab2(sch_1):page192";
BODY = "CAP_A","I1": #LOCATION = "C2P8" !CDS_LOCATION = "C2P8" &SEC = "1" #&CDS_SEC = "1";
"A":   PN = "1"  !CDS_PN = "1";
"B":   PN = "2"  !CDS_PN = "2";
BODY = "CAP_A","I3": #LOCATION = "C2P5" !CDS_LOCATION = "C2P5" &SEC = "1" #&CDS_SEC = "1";
"A":   PN = "1"  !CDS_PN = "1";
"B":   PN = "2"  !CDS_PN = "2";
BODY = "CAP_A","I4": #LOCATION = "C3R1" !CDS_LOCATION = "C3R1" &SEC = "1" #&CDS_SEC = "1";
"A":   PN = "1"  !CDS_PN = "1";
"B":   PN = "2"  !CDS_PN = "2";
BODY = "CAP_A","I6": #LOCATION = "C3P43" !CDS_LOCATION = "C3P43" &SEC = "1" #&CDS_SEC = "1";
"A":   PN = "1"  !CDS_PN = "1";
"B":   PN = "2"  !CDS_PN = "2";
BODY = "CAP_A","I7": #LOCATION = "C3R3" !CDS_LOCATION = "C3R3" &SEC = "1" #&CDS_SEC = "1";
"A":   PN = "1"  !CDS_PN = "1";
"B":   PN = "2"  !CDS_PN = "2";
BODY = "CAP_A","I8": #LOCATION = "C2R1" !CDS_LOCATION = "C2R1" &SEC = "1" #&CDS_SEC = "1";
"A":   PN = "1"  !CDS_PN = "1";
"B":   PN = "2"  !CDS_PN = "2";
BODY = "CAP_A","I9": #LOCATION = "C2P2" !CDS_LOCATION = "C2P2" &SEC = "1" #&CDS_SEC = "1";
"A":   PN = "1"  !CDS_PN = "1";
"B":   PN = "2"  !CDS_PN = "2";
BODY = "CAP_A","I10": #LOCATION = "C3R2" !CDS_LOCATION = "C3R2" &SEC = "1" #&CDS_SEC = "1";
"A":   PN = "1"  !CDS_PN = "1";
"B":   PN = "2"  !CDS_PN = "2";
BODY = "CAP_A","I11": #LOCATION = "C3P51" !CDS_LOCATION = "C3P51" &SEC = "1" #&CDS_SEC = "1";
"A":   PN = "1"  !CDS_PN = "1";
"B":   PN = "2"  !CDS_PN = "2";
BODY = "CAP_A","I12": #LOCATION = "C3P47" !CDS_LOCATION = "C3P47" &SEC = "1" #&CDS_SEC = "1";
"A":   PN = "1"  !CDS_PN = "1";
"B":   PN = "2"  !CDS_PN = "2";
BODY = "LCMXO2_A","I14": #LOCATION = "U8D7" !CDS_LOCATION = "U8D7" #SEC = "3" !CDS_SEC = "3";
"GND<0>":   PN = "B2"  !CDS_PN = "B2";
"GND<1>":   PN = "B15"  !CDS_PN = "B15";
"GND<2>":   PN = "C3"  !CDS_PN = "C3";
"GND<3>":   PN = "C14"  !CDS_PN = "C14";
"GND<4>":   PN = "D4"  !CDS_PN = "D4";
"GND<5>":   PN = "D13"  !CDS_PN = "D13";
"GND<6>":   PN = "E5"  !CDS_PN = "E5";
"GND<7>":   PN = "E12"  !CDS_PN = "E12";
"GND<8>":   PN = "F6"  !CDS_PN = "F6";
"GND<9>":   PN = "F11"  !CDS_PN = "F11";
"GND<10>":   PN = "H8"  !CDS_PN = "H8";
"GND<11>":   PN = "H9"  !CDS_PN = "H9";
"GND<12>":   PN = "J8"  !CDS_PN = "J8";
"GND<13>":   PN = "J9"  !CDS_PN = "J9";
"GND<14>":   PN = "L6"  !CDS_PN = "L6";
"GND<15>":   PN = "L11"  !CDS_PN = "L11";
"GND<16>":   PN = "M5"  !CDS_PN = "M5";
"GND<17>":   PN = "M12"  !CDS_PN = "M12";
"GND<18>":   PN = "N4"  !CDS_PN = "N4";
"GND<19>":   PN = "N13"  !CDS_PN = "N13";
"GND<20>":   PN = "P3"  !CDS_PN = "P3";
"GND<21>":   PN = "P14"  !CDS_PN = "P14";
"GND<22>":   PN = "R2"  !CDS_PN = "R2";
"GND<23>":   PN = "R15"  !CDS_PN = "R15";
"NC<0>":   PN = "A2"  !CDS_PN = "A2";
"VCC<0>":   PN = "A1"  !CDS_PN = "A1";
"VCC<1>":   PN = "A16"  !CDS_PN = "A16";
"VCC<2>":   PN = "T1"  !CDS_PN = "T1";
"VCC<3>":   PN = "T16"  !CDS_PN = "T16";
"VCC<4>":   PN = "G7"  !CDS_PN = "G7";
"VCC<5>":   PN = "G10"  !CDS_PN = "G10";
"VCC<6>":   PN = "K7"  !CDS_PN = "K7";
"VCC<7>":   PN = "K10"  !CDS_PN = "K10";
"VCCIO0<0>":   PN = "G8"  !CDS_PN = "G8";
"VCCIO0<1>":   PN = "D12"  !CDS_PN = "D12";
"VCCIO0<2>":   PN = "G9"  !CDS_PN = "G9";
"VCCIO0<3>":   PN = "D5"  !CDS_PN = "D5";
"VCCIO1<0>":   PN = "E13"  !CDS_PN = "E13";
"VCCIO1<1>":   PN = "H10"  !CDS_PN = "H10";
"VCCIO1<2>":   PN = "J10"  !CDS_PN = "J10";
"VCCIO1<3>":   PN = "M13"  !CDS_PN = "M13";
"VCCIO2<0>":   PN = "K9"  !CDS_PN = "K9";
"VCCIO2<1>":   PN = "N12"  !CDS_PN = "N12";
"VCCIO2<2>":   PN = "K8"  !CDS_PN = "K8";
"VCCIO2<3>":   PN = "N5"  !CDS_PN = "N5";
"VCCIO3<0>":   PN = "M4"  !CDS_PN = "M4";
"VCCIO4<0>":   PN = "J7"  !CDS_PN = "J7";
"VCCIO4<1>":   PN = "H7"  !CDS_PN = "H7";
"VCCIO5<0>":   PN = "E4"  !CDS_PN = "E4";
BODY = "CAP_A","I15": #LOCATION = "C2R5" !CDS_LOCATION = "C2R5" &SEC = "1" #&CDS_SEC = "1";
"A":   PN = "1"  !CDS_PN = "1";
"B":   PN = "2"  !CDS_PN = "2";
BODY = "CAP_A","I16": #LOCATION = "C2P4" !CDS_LOCATION = "C2P4" &SEC = "1" #&CDS_SEC = "1";
"A":   PN = "1"  !CDS_PN = "1";
"B":   PN = "2"  !CDS_PN = "2";
BODY = "CAP_A","I17": #LOCATION = "C3P52" !CDS_LOCATION = "C3P52" &SEC = "1" #&CDS_SEC = "1";
"A":   PN = "1"  !CDS_PN = "1";
"B":   PN = "2"  !CDS_PN = "2";
BODY = "CAP_A","I18": #LOCATION = "C2P6" !CDS_LOCATION = "C2P6" &SEC = "1" #&CDS_SEC = "1";
"A":   PN = "1"  !CDS_PN = "1";
"B":   PN = "2"  !CDS_PN = "2";
BODY = "CAP_A","I19": #LOCATION = "C2R3" !CDS_LOCATION = "C2R3" &SEC = "1" #&CDS_SEC = "1";
"A":   PN = "1"  !CDS_PN = "1";
"B":   PN = "2"  !CDS_PN = "2";
BODY = "CAP_A","I20": #LOCATION = "C2P7" !CDS_LOCATION = "C2P7" &SEC = "1" #&CDS_SEC = "1";
"A":   PN = "1"  !CDS_PN = "1";
"B":   PN = "2"  !CDS_PN = "2";
BODY = "CAP_A","I21": #LOCATION = "C2R4" !CDS_LOCATION = "C2R4" &SEC = "1" #&CDS_SEC = "1";
"A":   PN = "1"  !CDS_PN = "1";
"B":   PN = "2"  !CDS_PN = "2";
BODY = "CAP_A","I22": #LOCATION = "C2P3" !CDS_LOCATION = "C2P3" &SEC = "1" #&CDS_SEC = "1";
"A":   PN = "1"  !CDS_PN = "1";
"B":   PN = "2"  !CDS_PN = "2";
BODY = "CAP_A","I23": #LOCATION = "C3P44" !CDS_LOCATION = "C3P44" &SEC = "1" #&CDS_SEC = "1";
"A":   PN = "1"  !CDS_PN = "1";
"B":   PN = "2"  !CDS_PN = "2";
BODY = "CAP_A","I25": #LOCATION = "C3P48" !CDS_LOCATION = "C3P48" #SEC = "1" !CDS_SEC = "1";
"A":   PN = "1"  !CDS_PN = "1";
"B":   PN = "2"  !CDS_PN = "2";
BODY = "CAP_A","I28": #LOCATION = "C2R2" !CDS_LOCATION = "C2R2" &SEC = "1" #&CDS_SEC = "1";
"A":   PN = "1"  !CDS_PN = "1";
"B":   PN = "2"  !CDS_PN = "2";
BODY = "RES","I33": #LOCATION = "R7E6" !CDS_LOCATION = "R7E6" &SEC = "1" #&CDS_SEC = "1";
"A":   PN = "1"  !CDS_PN = "1";
"B":   PN = "2"  !CDS_PN = "2";
BODY = "RES","I34": #LOCATION = "R2R1" !CDS_LOCATION = "R2R1" &SEC = "1" #&CDS_SEC = "1";
"A":   PN = "1"  !CDS_PN = "1";
"B":   PN = "2"  !CDS_PN = "2";
BODY = "RES","I38": #LOCATION = "R7E5" !CDS_LOCATION = "R7E5" &SEC = "1" #&CDS_SEC = "1";
"A":   PN = "1"  !CDS_PN = "1";
"B":   PN = "2"  !CDS_PN = "2";
BODY = "RES","I41": #LOCATION = "R2R3" !CDS_LOCATION = "R2R3" &SEC = "1" #&CDS_SEC = "1";
"A":   PN = "1"  !CDS_PN = "1";
"B":   PN = "2"  !CDS_PN = "2";
BODY = "RES","I48": #LOCATION = "R3R16" !CDS_LOCATION = "R3R16" #SEC = "1" !CDS_SEC = "1";
"A":   PN = "1"  !CDS_PN = "1";
"B":   PN = "2"  !CDS_PN = "2";
BODY = "RES","I49": #LOCATION = "R6M9" !CDS_LOCATION = "R6M9" #SEC = "1" !CDS_SEC = "1";
"A":   PN = "1"  !CDS_PN = "1";
"B":   PN = "2"  !CDS_PN = "2";
BODY = "RES","I55": #LOCATION = "R7E18" !CDS_LOCATION = "R7E18" &SEC = "1" #&CDS_SEC = "1";
"A":   PN = "1"  !CDS_PN = "1";
"B":   PN = "2"  !CDS_PN = "2";
BODY = "RES","I57": #LOCATION = "R7E19" !CDS_LOCATION = "R7E19" &SEC = "1" #&CDS_SEC = "1";
"A":   PN = "1"  !CDS_PN = "1";
"B":   PN = "2"  !CDS_PN = "2";
BODY = "RES","I59": #LOCATION = "R7E20" !CDS_LOCATION = "R7E20" &SEC = "1" #&CDS_SEC = "1";
"A":   PN = "1"  !CDS_PN = "1";
"B":   PN = "2"  !CDS_PN = "2";
DRAWING = "@baseboard_fab2_lib.baseboard_fab2(sch_1):page193";
BODY = "CAPP","I29": #LOCATION = "C4C1" !CDS_LOCATION = "C4C1" #SEC = "1" !CDS_SEC = "1";
"A":   PN = "1"  !CDS_PN = "1";
"B":   PN = "2"  !CDS_PN = "2";
BODY = "CAP_A","I31": #LOCATION = "C3C2" !CDS_LOCATION = "C3C2" #SEC = "1" !CDS_SEC = "1";
"A":   PN = "1"  !CDS_PN = "1";
"B":   PN = "2"  !CDS_PN = "2";
BODY = "CAP_A","I38": #LOCATION = "C3C1" !CDS_LOCATION = "C3C1" #SEC = "1" !CDS_SEC = "1";
"A":   PN = "1"  !CDS_PN = "1";
"B":   PN = "2"  !CDS_PN = "2";
BODY = "SCONN120_H61426002","I45": #LOCATION = "J4E1" !CDS_LOCATION = "J4E1" #SEC = "1" !CDS_SEC = "1";
"IOA1":   PN = "A1"  !CDS_PN = "A1";
"IOA2":   PN = "A2"  !CDS_PN = "A2";
"IOA3":   PN = "A3"  !CDS_PN = "A3";
"IOA4":   PN = "A4"  !CDS_PN = "A4";
"IOA5":   PN = "A5"  !CDS_PN = "A5";
"IOA6":   PN = "A6"  !CDS_PN = "A6";
"IOA7":   PN = "A7"  !CDS_PN = "A7";
"IOA8":   PN = "A8"  !CDS_PN = "A8";
"IOA9":   PN = "A9"  !CDS_PN = "A9";
"IOA10":   PN = "A10"  !CDS_PN = "A10";
"IOA11":   PN = "A11"  !CDS_PN = "A11";
"IOA12":   PN = "A12"  !CDS_PN = "A12";
"IOA13":   PN = "A13"  !CDS_PN = "A13";
"IOA14":   PN = "A14"  !CDS_PN = "A14";
"IOA15":   PN = "A15"  !CDS_PN = "A15";
"IOA16":   PN = "A16"  !CDS_PN = "A16";
"IOA17":   PN = "A17"  !CDS_PN = "A17";
"IOA18":   PN = "A18"  !CDS_PN = "A18";
"IOA19":   PN = "A19"  !CDS_PN = "A19";
"IOA20":   PN = "A20"  !CDS_PN = "A20";
"IOB1":   PN = "B1"  !CDS_PN = "B1";
"IOB2":   PN = "B2"  !CDS_PN = "B2";
"IOB3":   PN = "B3"  !CDS_PN = "B3";
"IOB4":   PN = "B4"  !CDS_PN = "B4";
"IOB5":   PN = "B5"  !CDS_PN = "B5";
"IOB6":   PN = "B6"  !CDS_PN = "B6";
"IOB7":   PN = "B7"  !CDS_PN = "B7";
"IOB8":   PN = "B8"  !CDS_PN = "B8";
"IOB9":   PN = "B9"  !CDS_PN = "B9";
"IOB10":   PN = "B10"  !CDS_PN = "B10";
"IOB11":   PN = "B11"  !CDS_PN = "B11";
"IOB12":   PN = "B12"  !CDS_PN = "B12";
"IOB13":   PN = "B13"  !CDS_PN = "B13";
"IOB14":   PN = "B14"  !CDS_PN = "B14";
"IOB15":   PN = "B15"  !CDS_PN = "B15";
"IOB16":   PN = "B16"  !CDS_PN = "B16";
"IOB17":   PN = "B17"  !CDS_PN = "B17";
"IOB18":   PN = "B18"  !CDS_PN = "B18";
"IOB19":   PN = "B19"  !CDS_PN = "B19";
"IOB20":   PN = "B20"  !CDS_PN = "B20";
"IOC1":   PN = "C1"  !CDS_PN = "C1";
"IOC2":   PN = "C2"  !CDS_PN = "C2";
"IOC3":   PN = "C3"  !CDS_PN = "C3";
"IOC4":   PN = "C4"  !CDS_PN = "C4";
"IOC5":   PN = "C5"  !CDS_PN = "C5";
"IOC6":   PN = "C6"  !CDS_PN = "C6";
"IOC7":   PN = "C7"  !CDS_PN = "C7";
"IOC8":   PN = "C8"  !CDS_PN = "C8";
"IOC9":   PN = "C9"  !CDS_PN = "C9";
"IOC10":   PN = "C10"  !CDS_PN = "C10";
"IOC11":   PN = "C11"  !CDS_PN = "C11";
"IOC12":   PN = "C12"  !CDS_PN = "C12";
"IOC13":   PN = "C13"  !CDS_PN = "C13";
"IOC14":   PN = "C14"  !CDS_PN = "C14";
"IOC15":   PN = "C15"  !CDS_PN = "C15";
"IOC16":   PN = "C16"  !CDS_PN = "C16";
"IOC17":   PN = "C17"  !CDS_PN = "C17";
"IOC18":   PN = "C18"  !CDS_PN = "C18";
"IOC19":   PN = "C19"  !CDS_PN = "C19";
"IOC20":   PN = "C20"  !CDS_PN = "C20";
"IOD1":   PN = "D1"  !CDS_PN = "D1";
"IOD2":   PN = "D2"  !CDS_PN = "D2";
"IOD3":   PN = "D3"  !CDS_PN = "D3";
"IOD4":   PN = "D4"  !CDS_PN = "D4";
"IOD5":   PN = "D5"  !CDS_PN = "D5";
"IOD6":   PN = "D6"  !CDS_PN = "D6";
"IOD7":   PN = "D7"  !CDS_PN = "D7";
"IOD8":   PN = "D8"  !CDS_PN = "D8";
"IOD9":   PN = "D9"  !CDS_PN = "D9";
"IOD10":   PN = "D10"  !CDS_PN = "D10";
"IOD11":   PN = "D11"  !CDS_PN = "D11";
"IOD12":   PN = "D12"  !CDS_PN = "D12";
"IOD13":   PN = "D13"  !CDS_PN = "D13";
"IOD14":   PN = "D14"  !CDS_PN = "D14";
"IOD15":   PN = "D15"  !CDS_PN = "D15";
"IOD16":   PN = "D16"  !CDS_PN = "D16";
"IOD17":   PN = "D17"  !CDS_PN = "D17";
"IOD18":   PN = "D18"  !CDS_PN = "D18";
"IOD19":   PN = "D19"  !CDS_PN = "D19";
"IOD20":   PN = "D20"  !CDS_PN = "D20";
"IOE1":   PN = "E1"  !CDS_PN = "E1";
"IOE2":   PN = "E2"  !CDS_PN = "E2";
"IOE3":   PN = "E3"  !CDS_PN = "E3";
"IOE4":   PN = "E4"  !CDS_PN = "E4";
"IOE5":   PN = "E5"  !CDS_PN = "E5";
"IOE6":   PN = "E6"  !CDS_PN = "E6";
"IOE7":   PN = "E7"  !CDS_PN = "E7";
"IOE8":   PN = "E8"  !CDS_PN = "E8";
"IOE9":   PN = "E9"  !CDS_PN = "E9";
"IOE10":   PN = "E10"  !CDS_PN = "E10";
"IOE11":   PN = "E11"  !CDS_PN = "E11";
"IOE12":   PN = "E12"  !CDS_PN = "E12";
"IOE13":   PN = "E13"  !CDS_PN = "E13";
"IOE14":   PN = "E14"  !CDS_PN = "E14";
"IOE15":   PN = "E15"  !CDS_PN = "E15";
"IOE16":   PN = "E16"  !CDS_PN = "E16";
"IOE17":   PN = "E17"  !CDS_PN = "E17";
"IOE18":   PN = "E18"  !CDS_PN = "E18";
"IOE19":   PN = "E19"  !CDS_PN = "E19";
"IOE20":   PN = "E20"  !CDS_PN = "E20";
"IOF1":   PN = "F1"  !CDS_PN = "F1";
"IOF2":   PN = "F2"  !CDS_PN = "F2";
"IOF3":   PN = "F3"  !CDS_PN = "F3";
"IOF4":   PN = "F4"  !CDS_PN = "F4";
"IOF5":   PN = "F5"  !CDS_PN = "F5";
"IOF6":   PN = "F6"  !CDS_PN = "F6";
"IOF7":   PN = "F7"  !CDS_PN = "F7";
"IOF8":   PN = "F8"  !CDS_PN = "F8";
"IOF9":   PN = "F9"  !CDS_PN = "F9";
"IOF10":   PN = "F10"  !CDS_PN = "F10";
"IOF11":   PN = "F11"  !CDS_PN = "F11";
"IOF12":   PN = "F12"  !CDS_PN = "F12";
"IOF13":   PN = "F13"  !CDS_PN = "F13";
"IOF14":   PN = "F14"  !CDS_PN = "F14";
"IOF15":   PN = "F15"  !CDS_PN = "F15";
"IOF16":   PN = "F16"  !CDS_PN = "F16";
"IOF17":   PN = "F17"  !CDS_PN = "F17";
"IOF18":   PN = "F18"  !CDS_PN = "F18";
"IOF19":   PN = "F19"  !CDS_PN = "F19";
"IOF20":   PN = "F20"  !CDS_PN = "F20";
BODY = "SCONN120_H61426002","I46": #LOCATION = "J4B2" !CDS_LOCATION = "J4B2" #SEC = "1" !CDS_SEC = "1";
"IOA1":   PN = "A1"  !CDS_PN = "A1";
"IOA2":   PN = "A2"  !CDS_PN = "A2";
"IOA3":   PN = "A3"  !CDS_PN = "A3";
"IOA4":   PN = "A4"  !CDS_PN = "A4";
"IOA5":   PN = "A5"  !CDS_PN = "A5";
"IOA6":   PN = "A6"  !CDS_PN = "A6";
"IOA7":   PN = "A7"  !CDS_PN = "A7";
"IOA8":   PN = "A8"  !CDS_PN = "A8";
"IOA9":   PN = "A9"  !CDS_PN = "A9";
"IOA10":   PN = "A10"  !CDS_PN = "A10";
"IOA11":   PN = "A11"  !CDS_PN = "A11";
"IOA12":   PN = "A12"  !CDS_PN = "A12";
"IOA13":   PN = "A13"  !CDS_PN = "A13";
"IOA14":   PN = "A14"  !CDS_PN = "A14";
"IOA15":   PN = "A15"  !CDS_PN = "A15";
"IOA16":   PN = "A16"  !CDS_PN = "A16";
"IOA17":   PN = "A17"  !CDS_PN = "A17";
"IOA18":   PN = "A18"  !CDS_PN = "A18";
"IOA19":   PN = "A19"  !CDS_PN = "A19";
"IOA20":   PN = "A20"  !CDS_PN = "A20";
"IOB1":   PN = "B1"  !CDS_PN = "B1";
"IOB2":   PN = "B2"  !CDS_PN = "B2";
"IOB3":   PN = "B3"  !CDS_PN = "B3";
"IOB4":   PN = "B4"  !CDS_PN = "B4";
"IOB5":   PN = "B5"  !CDS_PN = "B5";
"IOB6":   PN = "B6"  !CDS_PN = "B6";
"IOB7":   PN = "B7"  !CDS_PN = "B7";
"IOB8":   PN = "B8"  !CDS_PN = "B8";
"IOB9":   PN = "B9"  !CDS_PN = "B9";
"IOB10":   PN = "B10"  !CDS_PN = "B10";
"IOB11":   PN = "B11"  !CDS_PN = "B11";
"IOB12":   PN = "B12"  !CDS_PN = "B12";
"IOB13":   PN = "B13"  !CDS_PN = "B13";
"IOB14":   PN = "B14"  !CDS_PN = "B14";
"IOB15":   PN = "B15"  !CDS_PN = "B15";
"IOB16":   PN = "B16"  !CDS_PN = "B16";
"IOB17":   PN = "B17"  !CDS_PN = "B17";
"IOB18":   PN = "B18"  !CDS_PN = "B18";
"IOB19":   PN = "B19"  !CDS_PN = "B19";
"IOB20":   PN = "B20"  !CDS_PN = "B20";
"IOC1":   PN = "C1"  !CDS_PN = "C1";
"IOC2":   PN = "C2"  !CDS_PN = "C2";
"IOC3":   PN = "C3"  !CDS_PN = "C3";
"IOC4":   PN = "C4"  !CDS_PN = "C4";
"IOC5":   PN = "C5"  !CDS_PN = "C5";
"IOC6":   PN = "C6"  !CDS_PN = "C6";
"IOC7":   PN = "C7"  !CDS_PN = "C7";
"IOC8":   PN = "C8"  !CDS_PN = "C8";
"IOC9":   PN = "C9"  !CDS_PN = "C9";
"IOC10":   PN = "C10"  !CDS_PN = "C10";
"IOC11":   PN = "C11"  !CDS_PN = "C11";
"IOC12":   PN = "C12"  !CDS_PN = "C12";
"IOC13":   PN = "C13"  !CDS_PN = "C13";
"IOC14":   PN = "C14"  !CDS_PN = "C14";
"IOC15":   PN = "C15"  !CDS_PN = "C15";
"IOC16":   PN = "C16"  !CDS_PN = "C16";
"IOC17":   PN = "C17"  !CDS_PN = "C17";
"IOC18":   PN = "C18"  !CDS_PN = "C18";
"IOC19":   PN = "C19"  !CDS_PN = "C19";
"IOC20":   PN = "C20"  !CDS_PN = "C20";
"IOD1":   PN = "D1"  !CDS_PN = "D1";
"IOD2":   PN = "D2"  !CDS_PN = "D2";
"IOD3":   PN = "D3"  !CDS_PN = "D3";
"IOD4":   PN = "D4"  !CDS_PN = "D4";
"IOD5":   PN = "D5"  !CDS_PN = "D5";
"IOD6":   PN = "D6"  !CDS_PN = "D6";
"IOD7":   PN = "D7"  !CDS_PN = "D7";
"IOD8":   PN = "D8"  !CDS_PN = "D8";
"IOD9":   PN = "D9"  !CDS_PN = "D9";
"IOD10":   PN = "D10"  !CDS_PN = "D10";
"IOD11":   PN = "D11"  !CDS_PN = "D11";
"IOD12":   PN = "D12"  !CDS_PN = "D12";
"IOD13":   PN = "D13"  !CDS_PN = "D13";
"IOD14":   PN = "D14"  !CDS_PN = "D14";
"IOD15":   PN = "D15"  !CDS_PN = "D15";
"IOD16":   PN = "D16"  !CDS_PN = "D16";
"IOD17":   PN = "D17"  !CDS_PN = "D17";
"IOD18":   PN = "D18"  !CDS_PN = "D18";
"IOD19":   PN = "D19"  !CDS_PN = "D19";
"IOD20":   PN = "D20"  !CDS_PN = "D20";
"IOE1":   PN = "E1"  !CDS_PN = "E1";
"IOE2":   PN = "E2"  !CDS_PN = "E2";
"IOE3":   PN = "E3"  !CDS_PN = "E3";
"IOE4":   PN = "E4"  !CDS_PN = "E4";
"IOE5":   PN = "E5"  !CDS_PN = "E5";
"IOE6":   PN = "E6"  !CDS_PN = "E6";
"IOE7":   PN = "E7"  !CDS_PN = "E7";
"IOE8":   PN = "E8"  !CDS_PN = "E8";
"IOE9":   PN = "E9"  !CDS_PN = "E9";
"IOE10":   PN = "E10"  !CDS_PN = "E10";
"IOE11":   PN = "E11"  !CDS_PN = "E11";
"IOE12":   PN = "E12"  !CDS_PN = "E12";
"IOE13":   PN = "E13"  !CDS_PN = "E13";
"IOE14":   PN = "E14"  !CDS_PN = "E14";
"IOE15":   PN = "E15"  !CDS_PN = "E15";
"IOE16":   PN = "E16"  !CDS_PN = "E16";
"IOE17":   PN = "E17"  !CDS_PN = "E17";
"IOE18":   PN = "E18"  !CDS_PN = "E18";
"IOE19":   PN = "E19"  !CDS_PN = "E19";
"IOE20":   PN = "E20"  !CDS_PN = "E20";
"IOF1":   PN = "F1"  !CDS_PN = "F1";
"IOF2":   PN = "F2"  !CDS_PN = "F2";
"IOF3":   PN = "F3"  !CDS_PN = "F3";
"IOF4":   PN = "F4"  !CDS_PN = "F4";
"IOF5":   PN = "F5"  !CDS_PN = "F5";
"IOF6":   PN = "F6"  !CDS_PN = "F6";
"IOF7":   PN = "F7"  !CDS_PN = "F7";
"IOF8":   PN = "F8"  !CDS_PN = "F8";
"IOF9":   PN = "F9"  !CDS_PN = "F9";
"IOF10":   PN = "F10"  !CDS_PN = "F10";
"IOF11":   PN = "F11"  !CDS_PN = "F11";
"IOF12":   PN = "F12"  !CDS_PN = "F12";
"IOF13":   PN = "F13"  !CDS_PN = "F13";
"IOF14":   PN = "F14"  !CDS_PN = "F14";
"IOF15":   PN = "F15"  !CDS_PN = "F15";
"IOF16":   PN = "F16"  !CDS_PN = "F16";
"IOF17":   PN = "F17"  !CDS_PN = "F17";
"IOF18":   PN = "F18"  !CDS_PN = "F18";
"IOF19":   PN = "F19"  !CDS_PN = "F19";
"IOF20":   PN = "F20"  !CDS_PN = "F20";
BODY = "CAPP","I61": #LOCATION = "C4E24" !CDS_LOCATION = "C4E24" &SEC = "1" #&CDS_SEC = "1";
"A":   PN = "1"  !CDS_PN = "1";
"B":   PN = "2"  !CDS_PN = "2";
BODY = "CAPP","I62": #LOCATION = "C6R16" !CDS_LOCATION = "C6R16" #SEC = "1" !CDS_SEC = "1";
"A":   PN = "1"  !CDS_PN = "1";
"B":   PN = "2"  !CDS_PN = "2";
BODY = "CAP_A","I68": #LOCATION = "C4F1" !CDS_LOCATION = "C4F1" #SEC = "1" !CDS_SEC = "1";
"A":   PN = "1"  !CDS_PN = "1";
"B":   PN = "2"  !CDS_PN = "2";
BODY = "CAP_A","I70": #LOCATION = "C4F3" !CDS_LOCATION = "C4F3" #SEC = "1" !CDS_SEC = "1";
"A":   PN = "1"  !CDS_PN = "1";
"B":   PN = "2"  !CDS_PN = "2";
BODY = "CAP_A","I140": #LOCATION = "C3F1" !CDS_LOCATION = "C3F1" #SEC = "1" !CDS_SEC = "1";
"A":   PN = "1"  !CDS_PN = "1";
"B":   PN = "2"  !CDS_PN = "2";
BODY = "CAP_A","I141": #LOCATION = "C4F2" !CDS_LOCATION = "C4F2" #SEC = "1" !CDS_SEC = "1";
"A":   PN = "1"  !CDS_PN = "1";
"B":   PN = "2"  !CDS_PN = "2";
BODY = "RES","I169": #LOCATION = "R4C12" !CDS_LOCATION = "R4C12" #SEC = "1" !CDS_SEC = "1";
"A":   PN = "1"  !CDS_PN = "1";
"B":   PN = "2"  !CDS_PN = "2";
BODY = "RES","I170": #LOCATION = "R4C11" !CDS_LOCATION = "R4C11" #SEC = "1" !CDS_SEC = "1";
"A":   PN = "1"  !CDS_PN = "1";
"B":   PN = "2"  !CDS_PN = "2";
DRAWING = "@baseboard_fab2_lib.baseboard_fab2(sch_1):page194";
BODY = "CAP_A","I9": #LOCATION = "C4T2" !CDS_LOCATION = "C4T2" #SEC = "1" !CDS_SEC = "1";
"A":   PN = "1"  !CDS_PN = "1";
"B":   PN = "2"  !CDS_PN = "2";
BODY = "CAP_A","I16": #LOCATION = "C4T1" !CDS_LOCATION = "C4T1" #SEC = "1" !CDS_SEC = "1";
"A":   PN = "1"  !CDS_PN = "1";
"B":   PN = "2"  !CDS_PN = "2";
BODY = "CAPP","I29": #LOCATION = "C4R1" !CDS_LOCATION = "C4R1" #SEC = "1" !CDS_SEC = "1";
"A":   PN = "1"  !CDS_PN = "1";
"B":   PN = "2"  !CDS_PN = "2";
BODY = "CAPP","I31": #LOCATION = "C3R4" !CDS_LOCATION = "C3R4" &SEC = "1" #&CDS_SEC = "1";
"A":   PN = "1"  !CDS_PN = "1";
"B":   PN = "2"  !CDS_PN = "2";
BODY = "SCONN120_H61426002","I55": #LOCATION = "J6E1" !CDS_LOCATION = "J6E1" #SEC = "1" !CDS_SEC = "1";
"IOA1":   PN = "A1"  !CDS_PN = "A1";
"IOA2":   PN = "A2"  !CDS_PN = "A2";
"IOA3":   PN = "A3"  !CDS_PN = "A3";
"IOA4":   PN = "A4"  !CDS_PN = "A4";
"IOA5":   PN = "A5"  !CDS_PN = "A5";
"IOA6":   PN = "A6"  !CDS_PN = "A6";
"IOA7":   PN = "A7"  !CDS_PN = "A7";
"IOA8":   PN = "A8"  !CDS_PN = "A8";
"IOA9":   PN = "A9"  !CDS_PN = "A9";
"IOA10":   PN = "A10"  !CDS_PN = "A10";
"IOA11":   PN = "A11"  !CDS_PN = "A11";
"IOA12":   PN = "A12"  !CDS_PN = "A12";
"IOA13":   PN = "A13"  !CDS_PN = "A13";
"IOA14":   PN = "A14"  !CDS_PN = "A14";
"IOA15":   PN = "A15"  !CDS_PN = "A15";
"IOA16":   PN = "A16"  !CDS_PN = "A16";
"IOA17":   PN = "A17"  !CDS_PN = "A17";
"IOA18":   PN = "A18"  !CDS_PN = "A18";
"IOA19":   PN = "A19"  !CDS_PN = "A19";
"IOA20":   PN = "A20"  !CDS_PN = "A20";
"IOB1":   PN = "B1"  !CDS_PN = "B1";
"IOB2":   PN = "B2"  !CDS_PN = "B2";
"IOB3":   PN = "B3"  !CDS_PN = "B3";
"IOB4":   PN = "B4"  !CDS_PN = "B4";
"IOB5":   PN = "B5"  !CDS_PN = "B5";
"IOB6":   PN = "B6"  !CDS_PN = "B6";
"IOB7":   PN = "B7"  !CDS_PN = "B7";
"IOB8":   PN = "B8"  !CDS_PN = "B8";
"IOB9":   PN = "B9"  !CDS_PN = "B9";
"IOB10":   PN = "B10"  !CDS_PN = "B10";
"IOB11":   PN = "B11"  !CDS_PN = "B11";
"IOB12":   PN = "B12"  !CDS_PN = "B12";
"IOB13":   PN = "B13"  !CDS_PN = "B13";
"IOB14":   PN = "B14"  !CDS_PN = "B14";
"IOB15":   PN = "B15"  !CDS_PN = "B15";
"IOB16":   PN = "B16"  !CDS_PN = "B16";
"IOB17":   PN = "B17"  !CDS_PN = "B17";
"IOB18":   PN = "B18"  !CDS_PN = "B18";
"IOB19":   PN = "B19"  !CDS_PN = "B19";
"IOB20":   PN = "B20"  !CDS_PN = "B20";
"IOC1":   PN = "C1"  !CDS_PN = "C1";
"IOC2":   PN = "C2"  !CDS_PN = "C2";
"IOC3":   PN = "C3"  !CDS_PN = "C3";
"IOC4":   PN = "C4"  !CDS_PN = "C4";
"IOC5":   PN = "C5"  !CDS_PN = "C5";
"IOC6":   PN = "C6"  !CDS_PN = "C6";
"IOC7":   PN = "C7"  !CDS_PN = "C7";
"IOC8":   PN = "C8"  !CDS_PN = "C8";
"IOC9":   PN = "C9"  !CDS_PN = "C9";
"IOC10":   PN = "C10"  !CDS_PN = "C10";
"IOC11":   PN = "C11"  !CDS_PN = "C11";
"IOC12":   PN = "C12"  !CDS_PN = "C12";
"IOC13":   PN = "C13"  !CDS_PN = "C13";
"IOC14":   PN = "C14"  !CDS_PN = "C14";
"IOC15":   PN = "C15"  !CDS_PN = "C15";
"IOC16":   PN = "C16"  !CDS_PN = "C16";
"IOC17":   PN = "C17"  !CDS_PN = "C17";
"IOC18":   PN = "C18"  !CDS_PN = "C18";
"IOC19":   PN = "C19"  !CDS_PN = "C19";
"IOC20":   PN = "C20"  !CDS_PN = "C20";
"IOD1":   PN = "D1"  !CDS_PN = "D1";
"IOD2":   PN = "D2"  !CDS_PN = "D2";
"IOD3":   PN = "D3"  !CDS_PN = "D3";
"IOD4":   PN = "D4"  !CDS_PN = "D4";
"IOD5":   PN = "D5"  !CDS_PN = "D5";
"IOD6":   PN = "D6"  !CDS_PN = "D6";
"IOD7":   PN = "D7"  !CDS_PN = "D7";
"IOD8":   PN = "D8"  !CDS_PN = "D8";
"IOD9":   PN = "D9"  !CDS_PN = "D9";
"IOD10":   PN = "D10"  !CDS_PN = "D10";
"IOD11":   PN = "D11"  !CDS_PN = "D11";
"IOD12":   PN = "D12"  !CDS_PN = "D12";
"IOD13":   PN = "D13"  !CDS_PN = "D13";
"IOD14":   PN = "D14"  !CDS_PN = "D14";
"IOD15":   PN = "D15"  !CDS_PN = "D15";
"IOD16":   PN = "D16"  !CDS_PN = "D16";
"IOD17":   PN = "D17"  !CDS_PN = "D17";
"IOD18":   PN = "D18"  !CDS_PN = "D18";
"IOD19":   PN = "D19"  !CDS_PN = "D19";
"IOD20":   PN = "D20"  !CDS_PN = "D20";
"IOE1":   PN = "E1"  !CDS_PN = "E1";
"IOE2":   PN = "E2"  !CDS_PN = "E2";
"IOE3":   PN = "E3"  !CDS_PN = "E3";
"IOE4":   PN = "E4"  !CDS_PN = "E4";
"IOE5":   PN = "E5"  !CDS_PN = "E5";
"IOE6":   PN = "E6"  !CDS_PN = "E6";
"IOE7":   PN = "E7"  !CDS_PN = "E7";
"IOE8":   PN = "E8"  !CDS_PN = "E8";
"IOE9":   PN = "E9"  !CDS_PN = "E9";
"IOE10":   PN = "E10"  !CDS_PN = "E10";
"IOE11":   PN = "E11"  !CDS_PN = "E11";
"IOE12":   PN = "E12"  !CDS_PN = "E12";
"IOE13":   PN = "E13"  !CDS_PN = "E13";
"IOE14":   PN = "E14"  !CDS_PN = "E14";
"IOE15":   PN = "E15"  !CDS_PN = "E15";
"IOE16":   PN = "E16"  !CDS_PN = "E16";
"IOE17":   PN = "E17"  !CDS_PN = "E17";
"IOE18":   PN = "E18"  !CDS_PN = "E18";
"IOE19":   PN = "E19"  !CDS_PN = "E19";
"IOE20":   PN = "E20"  !CDS_PN = "E20";
"IOF1":   PN = "F1"  !CDS_PN = "F1";
"IOF2":   PN = "F2"  !CDS_PN = "F2";
"IOF3":   PN = "F3"  !CDS_PN = "F3";
"IOF4":   PN = "F4"  !CDS_PN = "F4";
"IOF5":   PN = "F5"  !CDS_PN = "F5";
"IOF6":   PN = "F6"  !CDS_PN = "F6";
"IOF7":   PN = "F7"  !CDS_PN = "F7";
"IOF8":   PN = "F8"  !CDS_PN = "F8";
"IOF9":   PN = "F9"  !CDS_PN = "F9";
"IOF10":   PN = "F10"  !CDS_PN = "F10";
"IOF11":   PN = "F11"  !CDS_PN = "F11";
"IOF12":   PN = "F12"  !CDS_PN = "F12";
"IOF13":   PN = "F13"  !CDS_PN = "F13";
"IOF14":   PN = "F14"  !CDS_PN = "F14";
"IOF15":   PN = "F15"  !CDS_PN = "F15";
"IOF16":   PN = "F16"  !CDS_PN = "F16";
"IOF17":   PN = "F17"  !CDS_PN = "F17";
"IOF18":   PN = "F18"  !CDS_PN = "F18";
"IOF19":   PN = "F19"  !CDS_PN = "F19";
"IOF20":   PN = "F20"  !CDS_PN = "F20";
BODY = "SCONN120_H61426002","I56": #LOCATION = "J6B1" !CDS_LOCATION = "J6B1" #SEC = "1" !CDS_SEC = "1";
"IOA1":   PN = "A1"  !CDS_PN = "A1";
"IOA2":   PN = "A2"  !CDS_PN = "A2";
"IOA3":   PN = "A3"  !CDS_PN = "A3";
"IOA4":   PN = "A4"  !CDS_PN = "A4";
"IOA5":   PN = "A5"  !CDS_PN = "A5";
"IOA6":   PN = "A6"  !CDS_PN = "A6";
"IOA7":   PN = "A7"  !CDS_PN = "A7";
"IOA8":   PN = "A8"  !CDS_PN = "A8";
"IOA9":   PN = "A9"  !CDS_PN = "A9";
"IOA10":   PN = "A10"  !CDS_PN = "A10";
"IOA11":   PN = "A11"  !CDS_PN = "A11";
"IOA12":   PN = "A12"  !CDS_PN = "A12";
"IOA13":   PN = "A13"  !CDS_PN = "A13";
"IOA14":   PN = "A14"  !CDS_PN = "A14";
"IOA15":   PN = "A15"  !CDS_PN = "A15";
"IOA16":   PN = "A16"  !CDS_PN = "A16";
"IOA17":   PN = "A17"  !CDS_PN = "A17";
"IOA18":   PN = "A18"  !CDS_PN = "A18";
"IOA19":   PN = "A19"  !CDS_PN = "A19";
"IOA20":   PN = "A20"  !CDS_PN = "A20";
"IOB1":   PN = "B1"  !CDS_PN = "B1";
"IOB2":   PN = "B2"  !CDS_PN = "B2";
"IOB3":   PN = "B3"  !CDS_PN = "B3";
"IOB4":   PN = "B4"  !CDS_PN = "B4";
"IOB5":   PN = "B5"  !CDS_PN = "B5";
"IOB6":   PN = "B6"  !CDS_PN = "B6";
"IOB7":   PN = "B7"  !CDS_PN = "B7";
"IOB8":   PN = "B8"  !CDS_PN = "B8";
"IOB9":   PN = "B9"  !CDS_PN = "B9";
"IOB10":   PN = "B10"  !CDS_PN = "B10";
"IOB11":   PN = "B11"  !CDS_PN = "B11";
"IOB12":   PN = "B12"  !CDS_PN = "B12";
"IOB13":   PN = "B13"  !CDS_PN = "B13";
"IOB14":   PN = "B14"  !CDS_PN = "B14";
"IOB15":   PN = "B15"  !CDS_PN = "B15";
"IOB16":   PN = "B16"  !CDS_PN = "B16";
"IOB17":   PN = "B17"  !CDS_PN = "B17";
"IOB18":   PN = "B18"  !CDS_PN = "B18";
"IOB19":   PN = "B19"  !CDS_PN = "B19";
"IOB20":   PN = "B20"  !CDS_PN = "B20";
"IOC1":   PN = "C1"  !CDS_PN = "C1";
"IOC2":   PN = "C2"  !CDS_PN = "C2";
"IOC3":   PN = "C3"  !CDS_PN = "C3";
"IOC4":   PN = "C4"  !CDS_PN = "C4";
"IOC5":   PN = "C5"  !CDS_PN = "C5";
"IOC6":   PN = "C6"  !CDS_PN = "C6";
"IOC7":   PN = "C7"  !CDS_PN = "C7";
"IOC8":   PN = "C8"  !CDS_PN = "C8";
"IOC9":   PN = "C9"  !CDS_PN = "C9";
"IOC10":   PN = "C10"  !CDS_PN = "C10";
"IOC11":   PN = "C11"  !CDS_PN = "C11";
"IOC12":   PN = "C12"  !CDS_PN = "C12";
"IOC13":   PN = "C13"  !CDS_PN = "C13";
"IOC14":   PN = "C14"  !CDS_PN = "C14";
"IOC15":   PN = "C15"  !CDS_PN = "C15";
"IOC16":   PN = "C16"  !CDS_PN = "C16";
"IOC17":   PN = "C17"  !CDS_PN = "C17";
"IOC18":   PN = "C18"  !CDS_PN = "C18";
"IOC19":   PN = "C19"  !CDS_PN = "C19";
"IOC20":   PN = "C20"  !CDS_PN = "C20";
"IOD1":   PN = "D1"  !CDS_PN = "D1";
"IOD2":   PN = "D2"  !CDS_PN = "D2";
"IOD3":   PN = "D3"  !CDS_PN = "D3";
"IOD4":   PN = "D4"  !CDS_PN = "D4";
"IOD5":   PN = "D5"  !CDS_PN = "D5";
"IOD6":   PN = "D6"  !CDS_PN = "D6";
"IOD7":   PN = "D7"  !CDS_PN = "D7";
"IOD8":   PN = "D8"  !CDS_PN = "D8";
"IOD9":   PN = "D9"  !CDS_PN = "D9";
"IOD10":   PN = "D10"  !CDS_PN = "D10";
"IOD11":   PN = "D11"  !CDS_PN = "D11";
"IOD12":   PN = "D12"  !CDS_PN = "D12";
"IOD13":   PN = "D13"  !CDS_PN = "D13";
"IOD14":   PN = "D14"  !CDS_PN = "D14";
"IOD15":   PN = "D15"  !CDS_PN = "D15";
"IOD16":   PN = "D16"  !CDS_PN = "D16";
"IOD17":   PN = "D17"  !CDS_PN = "D17";
"IOD18":   PN = "D18"  !CDS_PN = "D18";
"IOD19":   PN = "D19"  !CDS_PN = "D19";
"IOD20":   PN = "D20"  !CDS_PN = "D20";
"IOE1":   PN = "E1"  !CDS_PN = "E1";
"IOE2":   PN = "E2"  !CDS_PN = "E2";
"IOE3":   PN = "E3"  !CDS_PN = "E3";
"IOE4":   PN = "E4"  !CDS_PN = "E4";
"IOE5":   PN = "E5"  !CDS_PN = "E5";
"IOE6":   PN = "E6"  !CDS_PN = "E6";
"IOE7":   PN = "E7"  !CDS_PN = "E7";
"IOE8":   PN = "E8"  !CDS_PN = "E8";
"IOE9":   PN = "E9"  !CDS_PN = "E9";
"IOE10":   PN = "E10"  !CDS_PN = "E10";
"IOE11":   PN = "E11"  !CDS_PN = "E11";
"IOE12":   PN = "E12"  !CDS_PN = "E12";
"IOE13":   PN = "E13"  !CDS_PN = "E13";
"IOE14":   PN = "E14"  !CDS_PN = "E14";
"IOE15":   PN = "E15"  !CDS_PN = "E15";
"IOE16":   PN = "E16"  !CDS_PN = "E16";
"IOE17":   PN = "E17"  !CDS_PN = "E17";
"IOE18":   PN = "E18"  !CDS_PN = "E18";
"IOE19":   PN = "E19"  !CDS_PN = "E19";
"IOE20":   PN = "E20"  !CDS_PN = "E20";
"IOF1":   PN = "F1"  !CDS_PN = "F1";
"IOF2":   PN = "F2"  !CDS_PN = "F2";
"IOF3":   PN = "F3"  !CDS_PN = "F3";
"IOF4":   PN = "F4"  !CDS_PN = "F4";
"IOF5":   PN = "F5"  !CDS_PN = "F5";
"IOF6":   PN = "F6"  !CDS_PN = "F6";
"IOF7":   PN = "F7"  !CDS_PN = "F7";
"IOF8":   PN = "F8"  !CDS_PN = "F8";
"IOF9":   PN = "F9"  !CDS_PN = "F9";
"IOF10":   PN = "F10"  !CDS_PN = "F10";
"IOF11":   PN = "F11"  !CDS_PN = "F11";
"IOF12":   PN = "F12"  !CDS_PN = "F12";
"IOF13":   PN = "F13"  !CDS_PN = "F13";
"IOF14":   PN = "F14"  !CDS_PN = "F14";
"IOF15":   PN = "F15"  !CDS_PN = "F15";
"IOF16":   PN = "F16"  !CDS_PN = "F16";
"IOF17":   PN = "F17"  !CDS_PN = "F17";
"IOF18":   PN = "F18"  !CDS_PN = "F18";
"IOF19":   PN = "F19"  !CDS_PN = "F19";
"IOF20":   PN = "F20"  !CDS_PN = "F20";
BODY = "CAP_A","I86": #LOCATION = "C3N40" !CDS_LOCATION = "C3N40" #SEC = "1" !CDS_SEC = "1";
"A":   PN = "1"  !CDS_PN = "1";
"B":   PN = "2"  !CDS_PN = "2";
BODY = "CAP_A","I99": #LOCATION = "C3M46" !CDS_LOCATION = "C3M46" #SEC = "1" !CDS_SEC = "1";
"A":   PN = "1"  !CDS_PN = "1";
"B":   PN = "2"  !CDS_PN = "2";
BODY = "CAPP","I101": #LOCATION = "C3N14" !CDS_LOCATION = "C3N14" #SEC = "1" !CDS_SEC = "1";
"A":   PN = "1"  !CDS_PN = "1";
"B":   PN = "2"  !CDS_PN = "2";
BODY = "CAP_A","I149": #LOCATION = "C3T1" !CDS_LOCATION = "C3T1" #SEC = "1" !CDS_SEC = "1";
"A":   PN = "1"  !CDS_PN = "1";
"B":   PN = "2"  !CDS_PN = "2";
BODY = "CAP_A","I150": #LOCATION = "C3T2" !CDS_LOCATION = "C3T2" #SEC = "1" !CDS_SEC = "1";
"A":   PN = "1"  !CDS_PN = "1";
"B":   PN = "2"  !CDS_PN = "2";
BODY = "RES","I155": #LOCATION = "R7C24" !CDS_LOCATION = "R7C24" #SEC = "1" !CDS_SEC = "1";
"A":   PN = "1"  !CDS_PN = "1";
"B":   PN = "2"  !CDS_PN = "2";
BODY = "RES","I156": #LOCATION = "R3N29" !CDS_LOCATION = "R3N29" #SEC = "1" !CDS_SEC = "1";
"A":   PN = "1"  !CDS_PN = "1";
"B":   PN = "2"  !CDS_PN = "2";
DRAWING = "@baseboard_fab2_lib.baseboard_fab2(sch_1):page195";
BODY = "CONN3_G98259001","I26": #LOCATION = "RM1E1" !CDS_LOCATION = "RM1E1" &SEC = "1" #&CDS_SEC = "1";
"IO1":   PN = "1"  !CDS_PN = "1";
"IO2":   PN = "2"  !CDS_PN = "2";
"IO3":   PN = "3"  !CDS_PN = "3";
BODY = "CONN12_G98257001","I29": #LOCATION = "J1E1" !CDS_LOCATION = "J1E1" #SEC = "1" !CDS_SEC = "1";
"A1":   PN = "A1"  !CDS_PN = "A1";
"A2":   PN = "A2"  !CDS_PN = "A2";
"A3":   PN = "A3"  !CDS_PN = "A3";
"B1":   PN = "B1"  !CDS_PN = "B1";
"B2":   PN = "B2"  !CDS_PN = "B2";
"B3":   PN = "B3"  !CDS_PN = "B3";
"C1":   PN = "C1"  !CDS_PN = "C1";
"C2":   PN = "C2"  !CDS_PN = "C2";
"C3":   PN = "C3"  !CDS_PN = "C3";
"D1":   PN = "D1"  !CDS_PN = "D1";
"D2":   PN = "D2"  !CDS_PN = "D2";
"D3":   PN = "D3"  !CDS_PN = "D3";
BODY = "CAP","I31": #LOCATION = "C9R5" !CDS_LOCATION = "C9R5" #SEC = "1" !CDS_SEC = "1";
"A":   PN = "1"  !CDS_PN = "1";
"B":   PN = "2"  !CDS_PN = "2";
BODY = "CAP","I32": #LOCATION = "C1E12" !CDS_LOCATION = "C1E12" #SEC = "1" !CDS_SEC = "1";
"A":   PN = "1"  !CDS_PN = "1";
"B":   PN = "2"  !CDS_PN = "2";
BODY = "CAP","I35": #LOCATION = "C1E15" !CDS_LOCATION = "C1E15" #SEC = "1" !CDS_SEC = "1";
"A":   PN = "1"  !CDS_PN = "1";
"B":   PN = "2"  !CDS_PN = "2";
BODY = "CAP_A","I36": #LOCATION = "C9R12" !CDS_LOCATION = "C9R12" #SEC = "1" !CDS_SEC = "1";
"A":   PN = "1"  !CDS_PN = "1";
"B":   PN = "2"  !CDS_PN = "2";
BODY = "CAP_A","I37": #LOCATION = "C9R6" !CDS_LOCATION = "C9R6" #SEC = "1" !CDS_SEC = "1";
"A":   PN = "1"  !CDS_PN = "1";
"B":   PN = "2"  !CDS_PN = "2";
BODY = "CAP_A","I38": #LOCATION = "C1E17" !CDS_LOCATION = "C1E17" #SEC = "1" !CDS_SEC = "1";
"A":   PN = "1"  !CDS_PN = "1";
"B":   PN = "2"  !CDS_PN = "2";
BODY = "CAP_A","I39": #LOCATION = "C1E16" !CDS_LOCATION = "C1E16" #SEC = "1" !CDS_SEC = "1";
"A":   PN = "1"  !CDS_PN = "1";
"B":   PN = "2"  !CDS_PN = "2";
BODY = "MTG_KEYHOLE","I49": #LOCATION = "TH4G1" !CDS_LOCATION = "TH4G1" &SEC = "1" #&CDS_SEC = "1";
"1":   PN = "1"  !CDS_PN = "1";
BODY = "MTG_KEYHOLE","I52": #LOCATION = "TH9G1" !CDS_LOCATION = "TH9G1" &SEC = "1" #&CDS_SEC = "1";
"1":   PN = "1"  !CDS_PN = "1";
BODY = "MTG_KEYHOLE","I54": #LOCATION = "TH9A1" !CDS_LOCATION = "TH9A1" &SEC = "1" #&CDS_SEC = "1";
"1":   PN = "1"  !CDS_PN = "1";
BODY = "MTG_KEYHOLE","I56": #LOCATION = "TH1A1" !CDS_LOCATION = "TH1A1" &SEC = "1" #&CDS_SEC = "1";
"1":   PN = "1"  !CDS_PN = "1";
BODY = "MTG_KEYHOLE","I62": #LOCATION = "TH4A1" !CDS_LOCATION = "TH4A1" &SEC = "1" #&CDS_SEC = "1";
"1":   PN = "1"  !CDS_PN = "1";
BODY = "MTG_KEYHOLE","I65": #LOCATION = "TH7A1" !CDS_LOCATION = "TH7A1" &SEC = "1" #&CDS_SEC = "1";
"1":   PN = "1"  !CDS_PN = "1";
BODY = "MTG_KEYHOLE","I67": #LOCATION = "TH7G1" !CDS_LOCATION = "TH7G1" &SEC = "1" #&CDS_SEC = "1";
"1":   PN = "1"  !CDS_PN = "1";
BODY = "CAPTIVE_SCREW","I76": #LOCATION = "RM1G1" !CDS_LOCATION = "RM1G1";
BODY = "CONN12_G98257001","I78": #LOCATION = "J1D1" !CDS_LOCATION = "J1D1" #SEC = "1" !CDS_SEC = "1";
"A1":   PN = "A1"  !CDS_PN = "A1";
"A2":   PN = "A2"  !CDS_PN = "A2";
"A3":   PN = "A3"  !CDS_PN = "A3";
"B1":   PN = "B1"  !CDS_PN = "B1";
"B2":   PN = "B2"  !CDS_PN = "B2";
"B3":   PN = "B3"  !CDS_PN = "B3";
"C1":   PN = "C1"  !CDS_PN = "C1";
"C2":   PN = "C2"  !CDS_PN = "C2";
"C3":   PN = "C3"  !CDS_PN = "C3";
"D1":   PN = "D1"  !CDS_PN = "D1";
"D2":   PN = "D2"  !CDS_PN = "D2";
"D3":   PN = "D3"  !CDS_PN = "D3";
BODY = "CAPP","I82": #LOCATION = "C4F6" !CDS_LOCATION = "C4F6" &SEC = "1" #&CDS_SEC = "1";
"A":   PN = "1"  !CDS_PN = "1";
"B":   PN = "2"  !CDS_PN = "2";
BODY = "CAPP","I83": #LOCATION = "C4B13" !CDS_LOCATION = "C4B13" &SEC = "1" #&CDS_SEC = "1";
"A":   PN = "1"  !CDS_PN = "1";
"B":   PN = "2"  !CDS_PN = "2";
BODY = "CAPP","I84": #LOCATION = "C1B14" !CDS_LOCATION = "C1B14" &SEC = "1" #&CDS_SEC = "1";
"A":   PN = "1"  !CDS_PN = "1";
"B":   PN = "2"  !CDS_PN = "2";
BODY = "CAPP","I85": #LOCATION = "C1F7" !CDS_LOCATION = "C1F7" &SEC = "1" #&CDS_SEC = "1";
"A":   PN = "1"  !CDS_PN = "1";
"B":   PN = "2"  !CDS_PN = "2";
BODY = "CAPP","I96": #LOCATION = "C4F5" !CDS_LOCATION = "C4F5" &SEC = "1" #&CDS_SEC = "1";
"A":   PN = "1"  !CDS_PN = "1";
"B":   PN = "2"  !CDS_PN = "2";
BODY = "CAPP","I97": #LOCATION = "C4B14" !CDS_LOCATION = "C4B14" &SEC = "1" #&CDS_SEC = "1";
"A":   PN = "1"  !CDS_PN = "1";
"B":   PN = "2"  !CDS_PN = "2";
BODY = "CAPP","I98": #LOCATION = "C3T6" !CDS_LOCATION = "C3T6" &SEC = "1" #&CDS_SEC = "1";
"A":   PN = "1"  !CDS_PN = "1";
"B":   PN = "2"  !CDS_PN = "2";
BODY = "CAPP","I99": #LOCATION = "C9M3" !CDS_LOCATION = "C9M3" &SEC = "1" #&CDS_SEC = "1";
"A":   PN = "1"  !CDS_PN = "1";
"B":   PN = "2"  !CDS_PN = "2";
BODY = "CAPP","I100": #LOCATION = "C3B6" !CDS_LOCATION = "C3B6" &SEC = "1" #&CDS_SEC = "1";
"A":   PN = "1"  !CDS_PN = "1";
"B":   PN = "2"  !CDS_PN = "2";
BODY = "CAPP","I101": #LOCATION = "C1R23" !CDS_LOCATION = "C1R23" &SEC = "1" #&CDS_SEC = "1";
"A":   PN = "1"  !CDS_PN = "1";
"B":   PN = "2"  !CDS_PN = "2";
BODY = "CAPP","I102": #LOCATION = "C4M6" !CDS_LOCATION = "C4M6" &SEC = "1" #&CDS_SEC = "1";
"A":   PN = "1"  !CDS_PN = "1";
"B":   PN = "2"  !CDS_PN = "2";
BODY = "CAPP","I103": #LOCATION = "C1M5" !CDS_LOCATION = "C1M5" &SEC = "1" #&CDS_SEC = "1";
"A":   PN = "1"  !CDS_PN = "1";
"B":   PN = "2"  !CDS_PN = "2";
BODY = "CAPP","I104": #LOCATION = "C3T13" !CDS_LOCATION = "C3T13" &SEC = "1" #&CDS_SEC = "1";
"A":   PN = "1"  !CDS_PN = "1";
"B":   PN = "2"  !CDS_PN = "2";
BODY = "CAPP","I105": #LOCATION = "C4M7" !CDS_LOCATION = "C4M7" &SEC = "1" #&CDS_SEC = "1";
"A":   PN = "1"  !CDS_PN = "1";
"B":   PN = "2"  !CDS_PN = "2";
BODY = "CAPP","I106": #LOCATION = "C3T15" !CDS_LOCATION = "C3T15" &SEC = "1" #&CDS_SEC = "1";
"A":   PN = "1"  !CDS_PN = "1";
"B":   PN = "2"  !CDS_PN = "2";
BODY = "CAPP","I108": #LOCATION = "C7M6" !CDS_LOCATION = "C7M6" &SEC = "1" #&CDS_SEC = "1";
"A":   PN = "1"  !CDS_PN = "1";
"B":   PN = "2"  !CDS_PN = "2";
BODY = "CAPP","I109": #LOCATION = "C6N5" !CDS_LOCATION = "C6N5" &SEC = "1" #&CDS_SEC = "1";
"A":   PN = "1"  !CDS_PN = "1";
"B":   PN = "2"  !CDS_PN = "2";
BODY = "CAPP","I111": #LOCATION = "C9T3" !CDS_LOCATION = "C9T3" &SEC = "1" #&CDS_SEC = "1";
"A":   PN = "1"  !CDS_PN = "1";
"B":   PN = "2"  !CDS_PN = "2";
BODY = "CAPP","I112": #LOCATION = "C4F4" !CDS_LOCATION = "C4F4" &SEC = "1" #&CDS_SEC = "1";
"A":   PN = "1"  !CDS_PN = "1";
"B":   PN = "2"  !CDS_PN = "2";
BODY = "CAPP","I113": #LOCATION = "C3T3" !CDS_LOCATION = "C3T3" &SEC = "1" #&CDS_SEC = "1";
"A":   PN = "1"  !CDS_PN = "1";
"B":   PN = "2"  !CDS_PN = "2";
DRAWING = "@baseboard_fab2_lib.baseboard_fab2(sch_1):page196";
BODY = "RES","I46": #LOCATION = "R2U43" !CDS_LOCATION = "R2U43" #SEC = "1" !CDS_SEC = "1";
"A":   PN = "1"  !CDS_PN = "1";
"B":   PN = "2"  !CDS_PN = "2";
BODY = "BATTERY","I47": #LOCATION = "BT8G1" !CDS_LOCATION = "BT8G1";
BODY = "VERT_BATT_3PIN","I51": #LOCATION = "XBT8G1" !CDS_LOCATION = "XBT8G1" #SEC = "1" !CDS_SEC = "1";
"N":   PN = "3"  !CDS_PN = "3";
"P1":   PN = "1"  !CDS_PN = "1";
"P2":   PN = "2"  !CDS_PN = "2";
BODY = "DIODE2A_DUAL","I53": #LOCATION = "CR2U1" !CDS_LOCATION = "CR2U1" #SEC = "1" !CDS_SEC = "1";
"A1":   PN = "1"  !CDS_PN = "1";
"A2":   PN = "2"  !CDS_PN = "2";
"C":   PN = "3"  !CDS_PN = "3";
BODY = "RES","I59": #LOCATION = "R3P44" !CDS_LOCATION = "R3P44" #SEC = "1" !CDS_SEC = "1";
"A":   PN = "1"  !CDS_PN = "1";
"B":   PN = "2"  !CDS_PN = "2";
BODY = "CAP","I60": #LOCATION = "C3P45" !CDS_LOCATION = "C3P45" #SEC = "1" !CDS_SEC = "1";
"A":   PN = "1"  !CDS_PN = "1";
"B":   PN = "2"  !CDS_PN = "2";
BODY = "RES","I65": #LOCATION = "R2P20" !CDS_LOCATION = "R2P20" #SEC = "1" !CDS_SEC = "1";
"A":   PN = "1"  !CDS_PN = "1";
"B":   PN = "2"  !CDS_PN = "2";
BODY = "RES","I68": #LOCATION = "R1L16" !CDS_LOCATION = "R1L16" #SEC = "1" !CDS_SEC = "1";
"A":   PN = "1"  !CDS_PN = "1";
"B":   PN = "2"  !CDS_PN = "2";
BODY = "ADM1085","I70": #LOCATION = "U7D3" !CDS_LOCATION = "U7D3" #SEC = "1" !CDS_SEC = "1";
"CEXT":   PN = "5"  !CDS_PN = "5";
"ENIN":   PN = "1"  !CDS_PN = "1";
"ENOUT":   PN = "4"  !CDS_PN = "4";
"GND":   PN = "2"  !CDS_PN = "2";
"VCC":   PN = "6"  !CDS_PN = "6";
"VIN":   PN = "3"  !CDS_PN = "3";
BODY = "RES","I71": #LOCATION = "R3P50" !CDS_LOCATION = "R3P50" #SEC = "1" !CDS_SEC = "1";
"A":   PN = "1"  !CDS_PN = "1";
"B":   PN = "2"  !CDS_PN = "2";
BODY = "CAP_A","I72": #LOCATION = "C3P46" !CDS_LOCATION = "C3P46" #SEC = "1" !CDS_SEC = "1";
"A":   PN = "1"  !CDS_PN = "1";
"B":   PN = "2"  !CDS_PN = "2";
BODY = "RES","I74": #LOCATION = "R3P48" !CDS_LOCATION = "R3P48" #SEC = "1" !CDS_SEC = "1";
"A":   PN = "1"  !CDS_PN = "1";
"B":   PN = "2"  !CDS_PN = "2";
BODY = "RES","I75": #LOCATION = "R3P51" !CDS_LOCATION = "R3P51" #SEC = "1" !CDS_SEC = "1";
"A":   PN = "1"  !CDS_PN = "1";
"B":   PN = "2"  !CDS_PN = "2";
BODY = "ADM809","I80": #LOCATION = "U1L3" !CDS_LOCATION = "U1L3" &SEC = "1" #&CDS_SEC = "1";
"RESET_N":   PN = "2"  !CDS_PN = "2";
"VCC":   PN = "3"  !CDS_PN = "3";
BODY = "CAP_A","I81": #LOCATION = "C1L16" !CDS_LOCATION = "C1L16" &SEC = "1" #&CDS_SEC = "1";
"A":   PN = "1"  !CDS_PN = "1";
"B":   PN = "2"  !CDS_PN = "2";
BODY = "ADM809","I89": #LOCATION = "U8E2" !CDS_LOCATION = "U8E2" &SEC = "1" #&CDS_SEC = "1";
"RESET_N":   PN = "2"  !CDS_PN = "2";
"VCC":   PN = "3"  !CDS_PN = "3";
BODY = "RES","I90": #LOCATION = "R8E7" !CDS_LOCATION = "R8E7" #SEC = "1" !CDS_SEC = "1";
"A":   PN = "1"  !CDS_PN = "1";
"B":   PN = "2"  !CDS_PN = "2";
BODY = "CAP_A","I94": #LOCATION = "C8E3" !CDS_LOCATION = "C8E3" #SEC = "1" !CDS_SEC = "1";
"A":   PN = "1"  !CDS_PN = "1";
"B":   PN = "2"  !CDS_PN = "2";
BODY = "CAP_A","I102": #LOCATION = "C2U26" !CDS_LOCATION = "C2U26" #SEC = "1" !CDS_SEC = "1";
"A":   PN = "1"  !CDS_PN = "1";
"B":   PN = "2"  !CDS_PN = "2";
BODY = "DIODE","I103": #LOCATION = "CR7E1" !CDS_LOCATION = "CR7E1" #SEC = "1" !CDS_SEC = "1";
"A":   PN = "2"  !CDS_PN = "2";
"C":   PN = "1"  !CDS_PN = "1";
BODY = "TPS3700","I104": #LOCATION = "U8D8" !CDS_LOCATION = "U8D8" &SEC = "1" #&CDS_SEC = "1";
"GND":   PN = "5"  !CDS_PN = "5";
"INAP":   PN = "4"  !CDS_PN = "4";
"INBN":   PN = "3"  !CDS_PN = "3";
"OUTA":   PN = "6"  !CDS_PN = "6";
"OUTB":   PN = "1"  !CDS_PN = "1";
"VDD":   PN = "2"  !CDS_PN = "2";
BODY = "CAP_A","I105": #LOCATION = "C8D4" !CDS_LOCATION = "C8D4" &SEC = "1" #&CDS_SEC = "1";
"A":   PN = "1"  !CDS_PN = "1";
"B":   PN = "2"  !CDS_PN = "2";
BODY = "RES","I106": #LOCATION = "R8D42" !CDS_LOCATION = "R8D42" #SEC = "1" !CDS_SEC = "1";
"A":   PN = "1"  !CDS_PN = "1";
"B":   PN = "2"  !CDS_PN = "2";
BODY = "RES","I112": #LOCATION = "R8D38" !CDS_LOCATION = "R8D38" #SEC = "1" !CDS_SEC = "1";
"A":   PN = "1"  !CDS_PN = "1";
"B":   PN = "2"  !CDS_PN = "2";
BODY = "RES","I113": #LOCATION = "R8D40" !CDS_LOCATION = "R8D40" #SEC = "1" !CDS_SEC = "1";
"A":   PN = "1"  !CDS_PN = "1";
"B":   PN = "2"  !CDS_PN = "2";
BODY = "RES","I114": #LOCATION = "R8D39" !CDS_LOCATION = "R8D39" #SEC = "1" !CDS_SEC = "1";
"A":   PN = "1"  !CDS_PN = "1";
"B":   PN = "2"  !CDS_PN = "2";
BODY = "RES","I115": #LOCATION = "R8D37" !CDS_LOCATION = "R8D37" #SEC = "1" !CDS_SEC = "1";
"A":   PN = "1"  !CDS_PN = "1";
"B":   PN = "2"  !CDS_PN = "2";
BODY = "RES","I120": #LOCATION = "R8D41" !CDS_LOCATION = "R8D41" #SEC = "1" !CDS_SEC = "1";
"A":   PN = "1"  !CDS_PN = "1";
"B":   PN = "2"  !CDS_PN = "2";
BODY = "RES","I121": #LOCATION = "R2P18" !CDS_LOCATION = "R2P18" #SEC = "1" !CDS_SEC = "1";
"A":   PN = "1"  !CDS_PN = "1";
"B":   PN = "2"  !CDS_PN = "2";
BODY = "RES","I122": #LOCATION = "R2P21" !CDS_LOCATION = "R2P21" #SEC = "1" !CDS_SEC = "1";
"A":   PN = "1"  !CDS_PN = "1";
"B":   PN = "2"  !CDS_PN = "2";
BODY = "FET_N","I124": #LOCATION = "Q2P2" !CDS_LOCATION = "Q2P2" &SEC = "1" #&CDS_SEC = "1";
"DRN":   PN = "3"  !CDS_PN = "3";
"GATE":   PN = "1"  !CDS_PN = "1";
"SRC":   PN = "2"  !CDS_PN = "2";
BODY = "DIODE","I128": #LOCATION = "CR8E1" !CDS_LOCATION = "CR8E1" #SEC = "1" !CDS_SEC = "1";
"A":   PN = "2"  !CDS_PN = "2";
"C":   PN = "1"  !CDS_PN = "1";
DRAWING = "@baseboard_fab2_lib.baseboard_fab2(sch_1):page197";
BODY = "CAP","I52": #LOCATION = "C6U18" !CDS_LOCATION = "C6U18" &SEC = "1" #&CDS_SEC = "1";
"A":   PN = "1"  !CDS_PN = "1";
"B":   PN = "2"  !CDS_PN = "2";
BODY = "CAP","I54": #LOCATION = "C6T2" !CDS_LOCATION = "C6T2" &SEC = "1" #&CDS_SEC = "1";
"A":   PN = "1"  !CDS_PN = "1";
"B":   PN = "2"  !CDS_PN = "2";
BODY = "CAP","I59": #LOCATION = "C4B11" !CDS_LOCATION = "C4B11" &SEC = "1" #&CDS_SEC = "1";
"A":   PN = "1"  !CDS_PN = "1";
"B":   PN = "2"  !CDS_PN = "2";
BODY = "CAP","I62": #LOCATION = "C4A4" !CDS_LOCATION = "C4A4" &SEC = "1" #&CDS_SEC = "1";
"A":   PN = "1"  !CDS_PN = "1";
"B":   PN = "2"  !CDS_PN = "2";
BODY = "CAP","I65": #LOCATION = "C6U10" !CDS_LOCATION = "C6U10" &SEC = "1" #&CDS_SEC = "1";
"A":   PN = "1"  !CDS_PN = "1";
"B":   PN = "2"  !CDS_PN = "2";
BODY = "CAP","I67": #LOCATION = "C4A17" !CDS_LOCATION = "C4A17" &SEC = "1" #&CDS_SEC = "1";
"A":   PN = "1"  !CDS_PN = "1";
"B":   PN = "2"  !CDS_PN = "2";
BODY = "CAP","I70": #LOCATION = "C9T8" !CDS_LOCATION = "C9T8" &SEC = "1" #&CDS_SEC = "1";
"A":   PN = "1"  !CDS_PN = "1";
"B":   PN = "2"  !CDS_PN = "2";
BODY = "CAP","I73": #LOCATION = "C9U11" !CDS_LOCATION = "C9U11" &SEC = "1" #&CDS_SEC = "1";
"A":   PN = "1"  !CDS_PN = "1";
"B":   PN = "2"  !CDS_PN = "2";
BODY = "CAP","I76": #LOCATION = "C9U8" !CDS_LOCATION = "C9U8" &SEC = "1" #&CDS_SEC = "1";
"A":   PN = "1"  !CDS_PN = "1";
"B":   PN = "2"  !CDS_PN = "2";
BODY = "CAP","I79": #LOCATION = "C1A4" !CDS_LOCATION = "C1A4" &SEC = "1" #&CDS_SEC = "1";
"A":   PN = "1"  !CDS_PN = "1";
"B":   PN = "2"  !CDS_PN = "2";
BODY = "CAP","I82": #LOCATION = "C1B7" !CDS_LOCATION = "C1B7" &SEC = "1" #&CDS_SEC = "1";
"A":   PN = "1"  !CDS_PN = "1";
"B":   PN = "2"  !CDS_PN = "2";
BODY = "CAP","I85": #LOCATION = "C1A16" !CDS_LOCATION = "C1A16" &SEC = "1" #&CDS_SEC = "1";
"A":   PN = "1"  !CDS_PN = "1";
"B":   PN = "2"  !CDS_PN = "2";
BODY = "MAX9634","I97": #LOCATION = "U4F1" !CDS_LOCATION = "U4F1" #SEC = "1" !CDS_SEC = "1";
"GND<0>":   PN = "2"  !CDS_PN = "2";
"GND<1>":   PN = "1"  !CDS_PN = "1";
"OUT":   PN = "3"  !CDS_PN = "3";
"RSN":   PN = "4"  !CDS_PN = "4";
"RSP":   PN = "5"  !CDS_PN = "5";
BODY = "RES","I99": #LOCATION = "R4F2" !CDS_LOCATION = "R4F2" #SEC = "1" !CDS_SEC = "1";
"A":   PN = "1"  !CDS_PN = "1";
"B":   PN = "2"  !CDS_PN = "2";
BODY = "RES","I110": #LOCATION = "R4F1" !CDS_LOCATION = "R4F1" #SEC = "1" !CDS_SEC = "1";
"A":   PN = "1"  !CDS_PN = "1";
"B":   PN = "2"  !CDS_PN = "2";
BODY = "RES","I113": #LOCATION = "R4B11" !CDS_LOCATION = "R4B11" #SEC = "1" !CDS_SEC = "1";
"A":   PN = "1"  !CDS_PN = "1";
"B":   PN = "2"  !CDS_PN = "2";
BODY = "MAX9634","I120": #LOCATION = "U4B1" !CDS_LOCATION = "U4B1" #SEC = "1" !CDS_SEC = "1";
"GND<0>":   PN = "2"  !CDS_PN = "2";
"GND<1>":   PN = "1"  !CDS_PN = "1";
"OUT":   PN = "3"  !CDS_PN = "3";
"RSN":   PN = "4"  !CDS_PN = "4";
"RSP":   PN = "5"  !CDS_PN = "5";
BODY = "RES","I121": #LOCATION = "R4B12" !CDS_LOCATION = "R4B12" #SEC = "1" !CDS_SEC = "1";
"A":   PN = "1"  !CDS_PN = "1";
"B":   PN = "2"  !CDS_PN = "2";
BODY = "RES","I126": #LOCATION = "R9T4" !CDS_LOCATION = "R9T4" #SEC = "1" !CDS_SEC = "1";
"A":   PN = "1"  !CDS_PN = "1";
"B":   PN = "2"  !CDS_PN = "2";
BODY = "RES","I131": #LOCATION = "R1F3" !CDS_LOCATION = "R1F3" #SEC = "1" !CDS_SEC = "1";
"A":   PN = "1"  !CDS_PN = "1";
"B":   PN = "2"  !CDS_PN = "2";
BODY = "MAX9634","I133": #LOCATION = "U1F1" !CDS_LOCATION = "U1F1" #SEC = "1" !CDS_SEC = "1";
"GND<0>":   PN = "2"  !CDS_PN = "2";
"GND<1>":   PN = "1"  !CDS_PN = "1";
"OUT":   PN = "3"  !CDS_PN = "3";
"RSN":   PN = "4"  !CDS_PN = "4";
"RSP":   PN = "5"  !CDS_PN = "5";
BODY = "RES","I137": #LOCATION = "R1B14" !CDS_LOCATION = "R1B14" #SEC = "1" !CDS_SEC = "1";
"A":   PN = "1"  !CDS_PN = "1";
"B":   PN = "2"  !CDS_PN = "2";
BODY = "RES","I142": #LOCATION = "R9M4" !CDS_LOCATION = "R9M4" #SEC = "1" !CDS_SEC = "1";
"A":   PN = "1"  !CDS_PN = "1";
"B":   PN = "2"  !CDS_PN = "2";
BODY = "MAX9634","I144": #LOCATION = "U1B1" !CDS_LOCATION = "U1B1" #SEC = "1" !CDS_SEC = "1";
"GND<0>":   PN = "2"  !CDS_PN = "2";
"GND<1>":   PN = "1"  !CDS_PN = "1";
"OUT":   PN = "3"  !CDS_PN = "3";
"RSN":   PN = "4"  !CDS_PN = "4";
"RSP":   PN = "5"  !CDS_PN = "5";
DRAWING = "@baseboard_fab2_lib.baseboard_fab2(sch_1):page198";
BODY = "SLG55021","I1": #LOCATION = "EU2T1" !CDS_LOCATION = "EU2T1" &SEC = "1" #&CDS_SEC = "1";
"D":   PN = "5"  !CDS_PN = "5";
"G":   PN = "7"  !CDS_PN = "7";
"GND":   PN = "4"  !CDS_PN = "4";
"ON":   PN = "2"  !CDS_PN = "2";
"PG":   PN = "8"  !CDS_PN = "8";
"S":   PN = "6"  !CDS_PN = "6";
"SHDN_N":   PN = "3"  !CDS_PN = "3";
"THPAD":   PN = "9"  !CDS_PN = "9";
"VCC":   PN = "1"  !CDS_PN = "1";
BODY = "SLG55021","I13": #LOCATION = "EU8B1" !CDS_LOCATION = "EU8B1" #SEC = "1" !CDS_SEC = "1";
"D":   PN = "5"  !CDS_PN = "5";
"G":   PN = "7"  !CDS_PN = "7";
"GND":   PN = "4"  !CDS_PN = "4";
"ON":   PN = "2"  !CDS_PN = "2";
"PG":   PN = "8"  !CDS_PN = "8";
"S":   PN = "6"  !CDS_PN = "6";
"SHDN_N":   PN = "3"  !CDS_PN = "3";
"THPAD":   PN = "9"  !CDS_PN = "9";
"VCC":   PN = "1"  !CDS_PN = "1";
BODY = "SLG55021","I19": #LOCATION = "EU7E1" !CDS_LOCATION = "EU7E1" #SEC = "1" !CDS_SEC = "1";
"D":   PN = "5"  !CDS_PN = "5";
"G":   PN = "7"  !CDS_PN = "7";
"GND":   PN = "4"  !CDS_PN = "4";
"ON":   PN = "2"  !CDS_PN = "2";
"PG":   PN = "8"  !CDS_PN = "8";
"S":   PN = "6"  !CDS_PN = "6";
"SHDN_N":   PN = "3"  !CDS_PN = "3";
"THPAD":   PN = "9"  !CDS_PN = "9";
"VCC":   PN = "1"  !CDS_PN = "1";
BODY = "CAP_A","I24": #LOCATION = "C8F17" !CDS_LOCATION = "C8F17" #SEC = "1" !CDS_SEC = "1";
"A":   PN = "1"  !CDS_PN = "1";
"B":   PN = "2"  !CDS_PN = "2";
BODY = "CAP_A","I26": #LOCATION = "C8B8" !CDS_LOCATION = "C8B8" #SEC = "1" !CDS_SEC = "1";
"A":   PN = "1"  !CDS_PN = "1";
"B":   PN = "2"  !CDS_PN = "2";
BODY = "CAP_A","I28": #LOCATION = "C8E19" !CDS_LOCATION = "C8E19" #SEC = "1" !CDS_SEC = "1";
"A":   PN = "1"  !CDS_PN = "1";
"B":   PN = "2"  !CDS_PN = "2";
BODY = "CAP_A","I37": #LOCATION = "C8B5" !CDS_LOCATION = "C8B5" #SEC = "1" !CDS_SEC = "1";
"A":   PN = "1"  !CDS_PN = "1";
"B":   PN = "2"  !CDS_PN = "2";
BODY = "CAP","I38": #LOCATION = "C8B12" !CDS_LOCATION = "C8B12" #SEC = "1" !CDS_SEC = "1";
"A":   PN = "1"  !CDS_PN = "1";
"B":   PN = "2"  !CDS_PN = "2";
BODY = "CAP","I40": #LOCATION = "C8B6" !CDS_LOCATION = "C8B6" #SEC = "1" !CDS_SEC = "1";
"A":   PN = "1"  !CDS_PN = "1";
"B":   PN = "2"  !CDS_PN = "2";
BODY = "CAP_A","I41": #LOCATION = "C8B7" !CDS_LOCATION = "C8B7" #SEC = "1" !CDS_SEC = "1";
"A":   PN = "1"  !CDS_PN = "1";
"B":   PN = "2"  !CDS_PN = "2";
BODY = "CAP_A","I43": #LOCATION = "C2T36" !CDS_LOCATION = "C2T36" #SEC = "1" !CDS_SEC = "1";
"A":   PN = "1"  !CDS_PN = "1";
"B":   PN = "2"  !CDS_PN = "2";
BODY = "CAP","I44": #LOCATION = "C2U1" !CDS_LOCATION = "C2U1" #SEC = "1" !CDS_SEC = "1";
"A":   PN = "1"  !CDS_PN = "1";
"B":   PN = "2"  !CDS_PN = "2";
BODY = "CAP_A","I46": #LOCATION = "C2U19" !CDS_LOCATION = "C2U19" #SEC = "1" !CDS_SEC = "1";
"A":   PN = "1"  !CDS_PN = "1";
"B":   PN = "2"  !CDS_PN = "2";
BODY = "CAP","I47": #LOCATION = "C2U2" !CDS_LOCATION = "C2U2" #SEC = "1" !CDS_SEC = "1";
"A":   PN = "1"  !CDS_PN = "1";
"B":   PN = "2"  !CDS_PN = "2";
BODY = "CAP_A","I49": #LOCATION = "C7E9" !CDS_LOCATION = "C7E9" #SEC = "1" !CDS_SEC = "1";
"A":   PN = "1"  !CDS_PN = "1";
"B":   PN = "2"  !CDS_PN = "2";
BODY = "CAP","I50": #LOCATION = "C7E8" !CDS_LOCATION = "C7E8" #SEC = "1" !CDS_SEC = "1";
"A":   PN = "1"  !CDS_PN = "1";
"B":   PN = "2"  !CDS_PN = "2";
BODY = "CAP_A","I52": #LOCATION = "C7E5" !CDS_LOCATION = "C7E5" #SEC = "1" !CDS_SEC = "1";
"A":   PN = "1"  !CDS_PN = "1";
"B":   PN = "2"  !CDS_PN = "2";
BODY = "CAP","I53": #LOCATION = "C7E6" !CDS_LOCATION = "C7E6" #SEC = "1" !CDS_SEC = "1";
"A":   PN = "1"  !CDS_PN = "1";
"B":   PN = "2"  !CDS_PN = "2";
BODY = "CAP","I61": #LOCATION = "C1B18" !CDS_LOCATION = "C1B18" #SEC = "1" !CDS_SEC = "1";
"A":   PN = "1"  !CDS_PN = "1";
"B":   PN = "2"  !CDS_PN = "2";
BODY = "CAP_A","I64": #LOCATION = "C1B19" !CDS_LOCATION = "C1B19" #SEC = "1" !CDS_SEC = "1";
"A":   PN = "1"  !CDS_PN = "1";
"B":   PN = "2"  !CDS_PN = "2";
BODY = "CAP_A","I67": #LOCATION = "C9M6" !CDS_LOCATION = "C9M6" #SEC = "1" !CDS_SEC = "1";
"A":   PN = "1"  !CDS_PN = "1";
"B":   PN = "2"  !CDS_PN = "2";
BODY = "SLG55021","I69": #LOCATION = "EU9M1" !CDS_LOCATION = "EU9M1" #SEC = "1" !CDS_SEC = "1";
"D":   PN = "5"  !CDS_PN = "5";
"G":   PN = "7"  !CDS_PN = "7";
"GND":   PN = "4"  !CDS_PN = "4";
"ON":   PN = "2"  !CDS_PN = "2";
"PG":   PN = "8"  !CDS_PN = "8";
"S":   PN = "6"  !CDS_PN = "6";
"SHDN_N":   PN = "3"  !CDS_PN = "3";
"THPAD":   PN = "9"  !CDS_PN = "9";
"VCC":   PN = "1"  !CDS_PN = "1";
BODY = "CAP","I74": #LOCATION = "C9M10" !CDS_LOCATION = "C9M10" #SEC = "1" !CDS_SEC = "1";
"A":   PN = "1"  !CDS_PN = "1";
"B":   PN = "2"  !CDS_PN = "2";
BODY = "CAP_A","I76": #LOCATION = "C9M9" !CDS_LOCATION = "C9M9" #SEC = "1" !CDS_SEC = "1";
"A":   PN = "1"  !CDS_PN = "1";
"B":   PN = "2"  !CDS_PN = "2";
BODY = "RES","I78": #LOCATION = "R8E12" !CDS_LOCATION = "R8E12" &SEC = "1" #&CDS_SEC = "1";
"A":   PN = "1"  !CDS_PN = "1";
"B":   PN = "2"  !CDS_PN = "2";
BODY = "RES","I83": #LOCATION = "R8B4" !CDS_LOCATION = "R8B4" #SEC = "1" !CDS_SEC = "1";
"A":   PN = "1"  !CDS_PN = "1";
"B":   PN = "2"  !CDS_PN = "2";
BODY = "MOSFET_N","I85": #LOCATION = "Q8G1" !CDS_LOCATION = "Q8G1" #SEC = "1" !CDS_SEC = "1";
"DRN":   PN = "5"  !CDS_PN = "5";
"GATE":   PN = "4"  !CDS_PN = "4";
"SRC":   PN = "1"  !CDS_PN = "1";
BODY = "MOSFET_N","I86": #LOCATION = "Q1B1" !CDS_LOCATION = "Q1B1" #SEC = "1" !CDS_SEC = "1";
"DRN":   PN = "5"  !CDS_PN = "5";
"GATE":   PN = "4"  !CDS_PN = "4";
"SRC":   PN = "1"  !CDS_PN = "1";
BODY = "MOSFET_N","I87": #LOCATION = "Q8B1" !CDS_LOCATION = "Q8B1" #SEC = "1" !CDS_SEC = "1";
"DRN":   PN = "5"  !CDS_PN = "5";
"GATE":   PN = "4"  !CDS_PN = "4";
"SRC":   PN = "1"  !CDS_PN = "1";
BODY = "MOSFET_N","I88": #LOCATION = "Q7E7" !CDS_LOCATION = "Q7E7" #SEC = "1" !CDS_SEC = "1";
"DRN":   PN = "5"  !CDS_PN = "5";
"GATE":   PN = "4"  !CDS_PN = "4";
"SRC":   PN = "1"  !CDS_PN = "1";
DRAWING = "@baseboard_fab2_lib.baseboard_fab2(sch_1):page199";
BODY = "RES","I2": #LOCATION = "R9P30" !CDS_LOCATION = "R9P30" #SEC = "1" !CDS_SEC = "1";
"A":   PN = "1"  !CDS_PN = "1";
"B":   PN = "2"  !CDS_PN = "2";
BODY = "CAP","I3": #LOCATION = "C1D25" !CDS_LOCATION = "C1D25" #SEC = "1" !CDS_SEC = "1";
"A":   PN = "1"  !CDS_PN = "1";
"B":   PN = "2"  !CDS_PN = "2";
BODY = "RES","I6": #LOCATION = "R9P28" !CDS_LOCATION = "R9P28" #SEC = "1" !CDS_SEC = "1";
"A":   PN = "1"  !CDS_PN = "1";
"B":   PN = "2"  !CDS_PN = "2";
BODY = "CAP_A","I7": #LOCATION = "C1D27" !CDS_LOCATION = "C1D27" #SEC = "1" !CDS_SEC = "1";
"A":   PN = "1"  !CDS_PN = "1";
"B":   PN = "2"  !CDS_PN = "2";
BODY = "RES","I9": #LOCATION = "R1D43" !CDS_LOCATION = "R1D43" #SEC = "1" !CDS_SEC = "1";
"A":   PN = "1"  !CDS_PN = "1";
"B":   PN = "2"  !CDS_PN = "2";
BODY = "ADM1278","I10": #LOCATION = "EU1D2" !CDS_LOCATION = "EU1D2" #SEC = "1" !CDS_SEC = "1";
"ADR1":   PN = "7"  !CDS_PN = "7";
"ADR2":   PN = "8"  !CDS_PN = "8";
"CSOUT":   PN = "19"  !CDS_PN = "19";
"ENABLE":   PN = "12"  !CDS_PN = "12";
"EP":   PN = "33"  !CDS_PN = "33";
"FAULT_N":   PN = "6"  !CDS_PN = "6";
"GATE":   PN = "24"  !CDS_PN = "24";
"GND":   PN = "22"  !CDS_PN = "22";
"GPO1_ALERT1_N_CONV":   PN = "13"  !CDS_PN = "13";
"GPO2_ALERT2_N":   PN = "14"  !CDS_PN = "14";
"HSN":   PN = "27"  !CDS_PN = "27";
"HSP":   PN = "28"  !CDS_PN = "28";
"ISET":   PN = "3"  !CDS_PN = "3";
"ISTART":   PN = "4"  !CDS_PN = "4";
"MCLK":   PN = "10"  !CDS_PN = "10";
"MDAT":   PN = "11"  !CDS_PN = "11";
"MON":   PN = "26"  !CDS_PN = "26";
"MOP":   PN = "29"  !CDS_PN = "29";
"OV":   PN = "32"  !CDS_PN = "32";
"PGND":   PN = "23"  !CDS_PN = "23";
"PSET":   PN = "1"  !CDS_PN = "1";
"PWGIN":   PN = "21"  !CDS_PN = "21";
"PWRGD":   PN = "18"  !CDS_PN = "18";
"RETRY_N":   PN = "17"  !CDS_PN = "17";
"SCL":   PN = "16"  !CDS_PN = "16";
"SDA":   PN = "15"  !CDS_PN = "15";
"SPISS_N":   PN = "9"  !CDS_PN = "9";
"TEMP":   PN = "25"  !CDS_PN = "25";
"TIMER":   PN = "5"  !CDS_PN = "5";
"UV":   PN = "31"  !CDS_PN = "31";
"VCAP":   PN = "2"  !CDS_PN = "2";
"VCC":   PN = "30"  !CDS_PN = "30";
"VOUT":   PN = "20"  !CDS_PN = "20";
BODY = "RES","I12": #LOCATION = "R9P29" !CDS_LOCATION = "R9P29" #SEC = "1" !CDS_SEC = "1";
"A":   PN = "1"  !CDS_PN = "1";
"B":   PN = "2"  !CDS_PN = "2";
BODY = "RES","I13": #LOCATION = "R1D42" !CDS_LOCATION = "R1D42" #SEC = "1" !CDS_SEC = "1";
"A":   PN = "1"  !CDS_PN = "1";
"B":   PN = "2"  !CDS_PN = "2";
BODY = "RES","I15": #LOCATION = "R1D37" !CDS_LOCATION = "R1D37" #SEC = "1" !CDS_SEC = "1";
"A":   PN = "1"  !CDS_PN = "1";
"B":   PN = "2"  !CDS_PN = "2";
BODY = "RES","I16": #LOCATION = "R1D39" !CDS_LOCATION = "R1D39" #SEC = "1" !CDS_SEC = "1";
"A":   PN = "1"  !CDS_PN = "1";
"B":   PN = "2"  !CDS_PN = "2";
BODY = "RES","I17": #LOCATION = "R1D32" !CDS_LOCATION = "R1D32" #SEC = "1" !CDS_SEC = "1";
"A":   PN = "1"  !CDS_PN = "1";
"B":   PN = "2"  !CDS_PN = "2";
BODY = "RES","I19": #LOCATION = "R1D41" !CDS_LOCATION = "R1D41" #SEC = "1" !CDS_SEC = "1";
"A":   PN = "1"  !CDS_PN = "1";
"B":   PN = "2"  !CDS_PN = "2";
BODY = "CAP","I24": #LOCATION = "C9P14" !CDS_LOCATION = "C9P14" #SEC = "1" !CDS_SEC = "1";
"A":   PN = "1"  !CDS_PN = "1";
"B":   PN = "2"  !CDS_PN = "2";
BODY = "RES","I26": #LOCATION = "R1D28" !CDS_LOCATION = "R1D28" #SEC = "1" !CDS_SEC = "1";
"A":   PN = "1"  !CDS_PN = "1";
"B":   PN = "2"  !CDS_PN = "2";
BODY = "RES","I27": #LOCATION = "R1D24" !CDS_LOCATION = "R1D24" #SEC = "1" !CDS_SEC = "1";
"A":   PN = "1"  !CDS_PN = "1";
"B":   PN = "2"  !CDS_PN = "2";
BODY = "RES","I28": #LOCATION = "R1D25" !CDS_LOCATION = "R1D25" #SEC = "1" !CDS_SEC = "1";
"A":   PN = "1"  !CDS_PN = "1";
"B":   PN = "2"  !CDS_PN = "2";
BODY = "RES","I33": #LOCATION = "R9P17" !CDS_LOCATION = "R9P17" #SEC = "1" !CDS_SEC = "1";
"A":   PN = "1"  !CDS_PN = "1";
"B":   PN = "2"  !CDS_PN = "2";
BODY = "RES","I36": #LOCATION = "R9P16" !CDS_LOCATION = "R9P16" #SEC = "1" !CDS_SEC = "1";
"A":   PN = "1"  !CDS_PN = "1";
"B":   PN = "2"  !CDS_PN = "2";
BODY = "RES","I37": #LOCATION = "R1D29" !CDS_LOCATION = "R1D29" #SEC = "1" !CDS_SEC = "1";
"A":   PN = "1"  !CDS_PN = "1";
"B":   PN = "2"  !CDS_PN = "2";
BODY = "RES","I38": #LOCATION = "R1D27" !CDS_LOCATION = "R1D27" #SEC = "1" !CDS_SEC = "1";
"A":   PN = "1"  !CDS_PN = "1";
"B":   PN = "2"  !CDS_PN = "2";
BODY = "RES","I41": #LOCATION = "R9P18" !CDS_LOCATION = "R9P18" #SEC = "1" !CDS_SEC = "1";
"A":   PN = "1"  !CDS_PN = "1";
"B":   PN = "2"  !CDS_PN = "2";
BODY = "RES","I43": #LOCATION = "R1D31" !CDS_LOCATION = "R1D31" #SEC = "1" !CDS_SEC = "1";
"A":   PN = "1"  !CDS_PN = "1";
"B":   PN = "2"  !CDS_PN = "2";
BODY = "CAP_A","I53": #LOCATION = "C1D11" !CDS_LOCATION = "C1D11" #SEC = "1" !CDS_SEC = "1";
"A":   PN = "1"  !CDS_PN = "1";
"B":   PN = "2"  !CDS_PN = "2";
BODY = "RES","I54": #LOCATION = "R9P23" !CDS_LOCATION = "R9P23" #SEC = "1" !CDS_SEC = "1";
"A":   PN = "1"  !CDS_PN = "1";
"B":   PN = "2"  !CDS_PN = "2";
BODY = "RES","I55": #LOCATION = "R9P24" !CDS_LOCATION = "R9P24" #SEC = "1" !CDS_SEC = "1";
"A":   PN = "1"  !CDS_PN = "1";
"B":   PN = "2"  !CDS_PN = "2";
BODY = "NPN","I58": #LOCATION = "Q1D3" !CDS_LOCATION = "Q1D3" #SEC = "1" !CDS_SEC = "1";
"B":   PN = "1"  !CDS_PN = "1";
"C":   PN = "3"  !CDS_PN = "3";
"E":   PN = "2"  !CDS_PN = "2";
BODY = "RES","I65": #LOCATION = "R1D36" !CDS_LOCATION = "R1D36" #SEC = "1" !CDS_SEC = "1";
"A":   PN = "1"  !CDS_PN = "1";
"B":   PN = "2"  !CDS_PN = "2";
BODY = "CAP_A","I67": #LOCATION = "C9P12" !CDS_LOCATION = "C9P12" #SEC = "1" !CDS_SEC = "1";
"A":   PN = "1"  !CDS_PN = "1";
"B":   PN = "2"  !CDS_PN = "2";
BODY = "FET_N_DUAL","I82": #LOCATION = "Q1D1" !CDS_LOCATION = "Q1D1" #SEC = "2" !CDS_SEC = "2";
"DRAIN<0>":   PN = "3"  !CDS_PN = "3";
"GATE<0>":   PN = "5"  !CDS_PN = "5";
"SOURCE<0>":   PN = "4"  !CDS_PN = "4";
BODY = "RES","I84": #LOCATION = "R1D13" !CDS_LOCATION = "R1D13" #SEC = "1" !CDS_SEC = "1";
"A":   PN = "1"  !CDS_PN = "1";
"B":   PN = "2"  !CDS_PN = "2";
BODY = "RES","I85": #LOCATION = "R1D16" !CDS_LOCATION = "R1D16" #SEC = "1" !CDS_SEC = "1";
"A":   PN = "1"  !CDS_PN = "1";
"B":   PN = "2"  !CDS_PN = "2";
BODY = "FET_N_DUAL","I86": #LOCATION = "Q1D1" !CDS_LOCATION = "Q1D1" #SEC = "1" !CDS_SEC = "1";
"DRAIN<0>":   PN = "6"  !CDS_PN = "6";
"GATE<0>":   PN = "2"  !CDS_PN = "2";
"SOURCE<0>":   PN = "1"  !CDS_PN = "1";
BODY = "RES","I87": #LOCATION = "R1D18" !CDS_LOCATION = "R1D18" #SEC = "1" !CDS_SEC = "1";
"A":   PN = "1"  !CDS_PN = "1";
"B":   PN = "2"  !CDS_PN = "2";
BODY = "RES","I88": #LOCATION = "R1D11" !CDS_LOCATION = "R1D11" #SEC = "1" !CDS_SEC = "1";
"A":   PN = "1"  !CDS_PN = "1";
"B":   PN = "2"  !CDS_PN = "2";
BODY = "RES","I92": #LOCATION = "R1D15" !CDS_LOCATION = "R1D15" #SEC = "1" !CDS_SEC = "1";
"A":   PN = "1"  !CDS_PN = "1";
"B":   PN = "2"  !CDS_PN = "2";
BODY = "ZENER","I99": #LOCATION = "VR1D1" !CDS_LOCATION = "VR1D1" #SEC = "1" !CDS_SEC = "1";
"A":   PN = "2"  !CDS_PN = "2";
"C":   PN = "1"  !CDS_PN = "1";
BODY = "RES","I100": #LOCATION = "R1D40" !CDS_LOCATION = "R1D40" #SEC = "1" !CDS_SEC = "1";
"A":   PN = "1"  !CDS_PN = "1";
"B":   PN = "2"  !CDS_PN = "2";
BODY = "RES","I102": #LOCATION = "R1D34" !CDS_LOCATION = "R1D34" #SEC = "1" !CDS_SEC = "1";
"A":   PN = "1"  !CDS_PN = "1";
"B":   PN = "2"  !CDS_PN = "2";
BODY = "CAP_A","I105": #LOCATION = "C9P15" !CDS_LOCATION = "C9P15" &SEC = "1" #&CDS_SEC = "1";
"A":   PN = "1"  !CDS_PN = "1";
"B":   PN = "2"  !CDS_PN = "2";
BODY = "CAP_A","I107": #LOCATION = "C1D26" !CDS_LOCATION = "C1D26" #SEC = "1" !CDS_SEC = "1";
"A":   PN = "1"  !CDS_PN = "1";
"B":   PN = "2"  !CDS_PN = "2";
BODY = "RES","I108": #LOCATION = "R1D33" !CDS_LOCATION = "R1D33" #SEC = "1" !CDS_SEC = "1";
"A":   PN = "1"  !CDS_PN = "1";
"B":   PN = "2"  !CDS_PN = "2";
BODY = "RES","I109": #LOCATION = "R1D26" !CDS_LOCATION = "R1D26" #SEC = "1" !CDS_SEC = "1";
"A":   PN = "1"  !CDS_PN = "1";
"B":   PN = "2"  !CDS_PN = "2";
BODY = "RES","I110": #LOCATION = "R1D30" !CDS_LOCATION = "R1D30" #SEC = "1" !CDS_SEC = "1";
"A":   PN = "1"  !CDS_PN = "1";
"B":   PN = "2"  !CDS_PN = "2";
BODY = "CAP","I119": #LOCATION = "C1D19" !CDS_LOCATION = "C1D19" #SEC = "1" !CDS_SEC = "1";
"A":   PN = "1"  !CDS_PN = "1";
"B":   PN = "2"  !CDS_PN = "2";
BODY = "CAP_A","I121": #LOCATION = "C1D21" !CDS_LOCATION = "C1D21" #SEC = "1" !CDS_SEC = "1";
"A":   PN = "1"  !CDS_PN = "1";
"B":   PN = "2"  !CDS_PN = "2";
BODY = "CONN3_C95678002","I123": #LOCATION = "J1B3" !CDS_LOCATION = "J1B3" #SEC = "1" !CDS_SEC = "1";
"IO1":   PN = "1"  !CDS_PN = "1";
"IO2":   PN = "2"  !CDS_PN = "2";
"IO3":   PN = "3"  !CDS_PN = "3";
BODY = "SCONN3_D53458001","I124": #LOCATION = "J1B4" !CDS_LOCATION = "J1B4" #SEC = "1" !CDS_SEC = "1";
"IO1":   PN = "1"  !CDS_PN = "1";
"IO2":   PN = "2"  !CDS_PN = "2";
"IO3":   PN = "3"  !CDS_PN = "3";
DRAWING = "@baseboard_fab2_lib.baseboard_fab2(sch_1):page200";
BODY = "CAP_A","I36": #LOCATION = "C9P17" !CDS_LOCATION = "C9P17" #SEC = "1" !CDS_SEC = "1";
"A":   PN = "1"  !CDS_PN = "1";
"B":   PN = "2"  !CDS_PN = "2";
BODY = "CAP_A","I40": #LOCATION = "C9P16" !CDS_LOCATION = "C9P16" &SEC = "1" #&CDS_SEC = "1";
"A":   PN = "1"  !CDS_PN = "1";
"B":   PN = "2"  !CDS_PN = "2";
BODY = "CAP_A","I42": #LOCATION = "C1D22" !CDS_LOCATION = "C1D22" &SEC = "1" #&CDS_SEC = "1";
"A":   PN = "1"  !CDS_PN = "1";
"B":   PN = "2"  !CDS_PN = "2";
BODY = "RES","I43": #LOCATION = "R1D45" !CDS_LOCATION = "R1D45" &SEC = "1" #&CDS_SEC = "1";
"A":   PN = "1"  !CDS_PN = "1";
"B":   PN = "2"  !CDS_PN = "2";
BODY = "RES","I44": #LOCATION = "R1D44" !CDS_LOCATION = "R1D44" &SEC = "1" #&CDS_SEC = "1";
"A":   PN = "1"  !CDS_PN = "1";
"B":   PN = "2"  !CDS_PN = "2";
BODY = "RES","I47": #LOCATION = "R9P27" !CDS_LOCATION = "R9P27" &SEC = "1" #&CDS_SEC = "1";
"A":   PN = "1"  !CDS_PN = "1";
"B":   PN = "2"  !CDS_PN = "2";
BODY = "RES","I48": #LOCATION = "R1D46" !CDS_LOCATION = "R1D46" &SEC = "1" #&CDS_SEC = "1";
"A":   PN = "1"  !CDS_PN = "1";
"B":   PN = "2"  !CDS_PN = "2";
BODY = "RES_PWR","I49": #LOCATION = "R9R1" !CDS_LOCATION = "R9R1" #SEC = "1" !CDS_SEC = "1";
"1":   PN = "1"  !CDS_PN = "1";
"2":   PN = "2"  !CDS_PN = "2";
"3":   PN = "3"  !CDS_PN = "3";
"4":   PN = "4"  !CDS_PN = "4";
"5":   PN = "5"  !CDS_PN = "5";
"6":   PN = "6"  !CDS_PN = "6";
BODY = "RES_PWR","I50": #LOCATION = "R1D49" !CDS_LOCATION = "R1D49" #SEC = "1" !CDS_SEC = "1";
"1":   PN = "1"  !CDS_PN = "1";
"2":   PN = "2"  !CDS_PN = "2";
"3":   PN = "3"  !CDS_PN = "3";
"4":   PN = "4"  !CDS_PN = "4";
"5":   PN = "5"  !CDS_PN = "5";
"6":   PN = "6"  !CDS_PN = "6";
BODY = "RES","I51": #LOCATION = "R9P26" !CDS_LOCATION = "R9P26" &SEC = "1" #&CDS_SEC = "1";
"A":   PN = "1"  !CDS_PN = "1";
"B":   PN = "2"  !CDS_PN = "2";
BODY = "RES","I52": #LOCATION = "R1D47" !CDS_LOCATION = "R1D47" &SEC = "1" #&CDS_SEC = "1";
"A":   PN = "1"  !CDS_PN = "1";
"B":   PN = "2"  !CDS_PN = "2";
BODY = "MOSFETN_1D3S","I54": #LOCATION = "EU1E3" !CDS_LOCATION = "EU1E3" #SEC = "1" !CDS_SEC = "1";
"D":   PN = "5"  !CDS_PN = "5";
"G":   PN = "4"  !CDS_PN = "4";
"S1":   PN = "1"  !CDS_PN = "1";
"S2":   PN = "2"  !CDS_PN = "2";
"S3":   PN = "3"  !CDS_PN = "3";
BODY = "RES","I56": #LOCATION = "R1E1" !CDS_LOCATION = "R1E1" #SEC = "1" !CDS_SEC = "1";
"A":   PN = "1"  !CDS_PN = "1";
"B":   PN = "2"  !CDS_PN = "2";
BODY = "MOSFETN_1D3S","I57": #LOCATION = "EU9R1" !CDS_LOCATION = "EU9R1" #SEC = "1" !CDS_SEC = "1";
"D":   PN = "5"  !CDS_PN = "5";
"G":   PN = "4"  !CDS_PN = "4";
"S1":   PN = "1"  !CDS_PN = "1";
"S2":   PN = "2"  !CDS_PN = "2";
"S3":   PN = "3"  !CDS_PN = "3";
BODY = "RES","I58": #LOCATION = "R9R4" !CDS_LOCATION = "R9R4" &SEC = "1" #&CDS_SEC = "1";
"A":   PN = "1"  !CDS_PN = "1";
"B":   PN = "2"  !CDS_PN = "2";
BODY = "MOSFETN_1D3S","I59": #LOCATION = "EU1E1" !CDS_LOCATION = "EU1E1" #SEC = "1" !CDS_SEC = "1";
"D":   PN = "5"  !CDS_PN = "5";
"G":   PN = "4"  !CDS_PN = "4";
"S1":   PN = "1"  !CDS_PN = "1";
"S2":   PN = "2"  !CDS_PN = "2";
"S3":   PN = "3"  !CDS_PN = "3";
BODY = "RES","I60": #LOCATION = "R1D48" !CDS_LOCATION = "R1D48" #SEC = "1" !CDS_SEC = "1";
"A":   PN = "1"  !CDS_PN = "1";
"B":   PN = "2"  !CDS_PN = "2";
BODY = "RES","I70": #LOCATION = "R9P19" !CDS_LOCATION = "R9P19" #SEC = "1" !CDS_SEC = "1";
"A":   PN = "1"  !CDS_PN = "1";
"B":   PN = "2"  !CDS_PN = "2";
BODY = "RES","I71": #LOCATION = "R9P21" !CDS_LOCATION = "R9P21" #SEC = "1" !CDS_SEC = "1";
"A":   PN = "1"  !CDS_PN = "1";
"B":   PN = "2"  !CDS_PN = "2";
BODY = "RES","I86": #LOCATION = "R9P20" !CDS_LOCATION = "R9P20" #SEC = "1" !CDS_SEC = "1";
"A":   PN = "1"  !CDS_PN = "1";
"B":   PN = "2"  !CDS_PN = "2";
BODY = "TTL1G126_A","I103": #LOCATION = "U1D1" !CDS_LOCATION = "U1D1" #SEC = "1" !CDS_SEC = "1";
"A":   PN = "2"  !CDS_PN = "2";
"OE":   PN = "1"  !CDS_PN = "1";
"Y":   PN = "4"  !CDS_PN = "4";
BODY = "RES","I107": #LOCATION = "R9P13" !CDS_LOCATION = "R9P13" #SEC = "1" !CDS_SEC = "1";
"A":   PN = "1"  !CDS_PN = "1";
"B":   PN = "2"  !CDS_PN = "2";
BODY = "RES","I108": #LOCATION = "R9P11" !CDS_LOCATION = "R9P11" #SEC = "1" !CDS_SEC = "1";
"A":   PN = "1"  !CDS_PN = "1";
"B":   PN = "2"  !CDS_PN = "2";
BODY = "RES","I145": #LOCATION = "R9P7" !CDS_LOCATION = "R9P7" #SEC = "1" !CDS_SEC = "1";
"A":   PN = "1"  !CDS_PN = "1";
"B":   PN = "2"  !CDS_PN = "2";
BODY = "RES","I146": #LOCATION = "R9P9" !CDS_LOCATION = "R9P9" #SEC = "1" !CDS_SEC = "1";
"A":   PN = "1"  !CDS_PN = "1";
"B":   PN = "2"  !CDS_PN = "2";
BODY = "RES","I149": #LOCATION = "R9P6" !CDS_LOCATION = "R9P6" #SEC = "1" !CDS_SEC = "1";
"A":   PN = "1"  !CDS_PN = "1";
"B":   PN = "2"  !CDS_PN = "2";
BODY = "RES","I154": #LOCATION = "R1D51" !CDS_LOCATION = "R1D51" #SEC = "1" !CDS_SEC = "1";
"A":   PN = "1"  !CDS_PN = "1";
"B":   PN = "2"  !CDS_PN = "2";
BODY = "CAP","I155": #LOCATION = "C1E2" !CDS_LOCATION = "C1E2" #SEC = "1" !CDS_SEC = "1";
"A":   PN = "1"  !CDS_PN = "1";
"B":   PN = "2"  !CDS_PN = "2";
BODY = "RES","I158": #LOCATION = "R1D22" !CDS_LOCATION = "R1D22" #SEC = "1" !CDS_SEC = "1";
"A":   PN = "1"  !CDS_PN = "1";
"B":   PN = "2"  !CDS_PN = "2";
BODY = "TPS3700","I163": #LOCATION = "U9P1" !CDS_LOCATION = "U9P1" #SEC = "1" !CDS_SEC = "1";
"GND":   PN = "5"  !CDS_PN = "5";
"INAP":   PN = "4"  !CDS_PN = "4";
"INBN":   PN = "3"  !CDS_PN = "3";
"OUTA":   PN = "6"  !CDS_PN = "6";
"OUTB":   PN = "1"  !CDS_PN = "1";
"VDD":   PN = "2"  !CDS_PN = "2";
BODY = "TPS3700","I170": #LOCATION = "U1D2" !CDS_LOCATION = "U1D2" #SEC = "1" !CDS_SEC = "1";
"GND":   PN = "5"  !CDS_PN = "5";
"INAP":   PN = "4"  !CDS_PN = "4";
"INBN":   PN = "3"  !CDS_PN = "3";
"OUTA":   PN = "6"  !CDS_PN = "6";
"OUTB":   PN = "1"  !CDS_PN = "1";
"VDD":   PN = "2"  !CDS_PN = "2";
BODY = "RES","I172": #LOCATION = "R1D20" !CDS_LOCATION = "R1D20" #SEC = "1" !CDS_SEC = "1";
"A":   PN = "1"  !CDS_PN = "1";
"B":   PN = "2"  !CDS_PN = "2";
BODY = "RES","I173": #LOCATION = "R1D14" !CDS_LOCATION = "R1D14" #SEC = "1" !CDS_SEC = "1";
"A":   PN = "1"  !CDS_PN = "1";
"B":   PN = "2"  !CDS_PN = "2";
BODY = "RES","I174": #LOCATION = "R1D12" !CDS_LOCATION = "R1D12" #SEC = "1" !CDS_SEC = "1";
"A":   PN = "1"  !CDS_PN = "1";
"B":   PN = "2"  !CDS_PN = "2";
BODY = "RES","I175": #LOCATION = "R1D19" !CDS_LOCATION = "R1D19" #SEC = "1" !CDS_SEC = "1";
"A":   PN = "1"  !CDS_PN = "1";
"B":   PN = "2"  !CDS_PN = "2";
BODY = "CAP_A","I185": #LOCATION = "C9P6" !CDS_LOCATION = "C9P6" #SEC = "1" !CDS_SEC = "1";
"A":   PN = "1"  !CDS_PN = "1";
"B":   PN = "2"  !CDS_PN = "2";
BODY = "CAP_A","I187": #LOCATION = "C1D9" !CDS_LOCATION = "C1D9" #SEC = "1" !CDS_SEC = "1";
"A":   PN = "1"  !CDS_PN = "1";
"B":   PN = "2"  !CDS_PN = "2";
BODY = "RES","I189": #LOCATION = "R1D10" !CDS_LOCATION = "R1D10" #SEC = "1" !CDS_SEC = "1";
"A":   PN = "1"  !CDS_PN = "1";
"B":   PN = "2"  !CDS_PN = "2";
BODY = "RES","I191": #LOCATION = "R1D23" !CDS_LOCATION = "R1D23" #SEC = "1" !CDS_SEC = "1";
"A":   PN = "1"  !CDS_PN = "1";
"B":   PN = "2"  !CDS_PN = "2";
BODY = "RES","I192": #LOCATION = "R9P10" !CDS_LOCATION = "R9P10" #SEC = "1" !CDS_SEC = "1";
"A":   PN = "1"  !CDS_PN = "1";
"B":   PN = "2"  !CDS_PN = "2";
BODY = "FET_N_DUAL","I196": #LOCATION = "Q9P1" !CDS_LOCATION = "Q9P1" #SEC = "1" !CDS_SEC = "1";
"DRAIN<0>":   PN = "6"  !CDS_PN = "6";
"GATE<0>":   PN = "2"  !CDS_PN = "2";
"SOURCE<0>":   PN = "1"  !CDS_PN = "1";
BODY = "RES","I198": #LOCATION = "R9P15" !CDS_LOCATION = "R9P15" #SEC = "1" !CDS_SEC = "1";
"A":   PN = "1"  !CDS_PN = "1";
"B":   PN = "2"  !CDS_PN = "2";
BODY = "FET_N_DUAL","I199": #LOCATION = "Q9P1" !CDS_LOCATION = "Q9P1" #SEC = "2" !CDS_SEC = "2";
"DRAIN<0>":   PN = "3"  !CDS_PN = "3";
"GATE<0>":   PN = "5"  !CDS_PN = "5";
"SOURCE<0>":   PN = "4"  !CDS_PN = "4";
BODY = "TPS3700","I200": #LOCATION = "U9P2" !CDS_LOCATION = "U9P2" &SEC = "1" #&CDS_SEC = "1";
"GND":   PN = "5"  !CDS_PN = "5";
"INAP":   PN = "4"  !CDS_PN = "4";
"INBN":   PN = "3"  !CDS_PN = "3";
"OUTA":   PN = "6"  !CDS_PN = "6";
"OUTB":   PN = "1"  !CDS_PN = "1";
"VDD":   PN = "2"  !CDS_PN = "2";
BODY = "CAP_A","I201": #LOCATION = "C9P11" !CDS_LOCATION = "C9P11" #SEC = "1" !CDS_SEC = "1";
"A":   PN = "1"  !CDS_PN = "1";
"B":   PN = "2"  !CDS_PN = "2";
BODY = "FET_N","I203": #LOCATION = "Q1D2" !CDS_LOCATION = "Q1D2" #SEC = "1" !CDS_SEC = "1";
"DRN":   PN = "3"  !CDS_PN = "3";
"GATE":   PN = "1"  !CDS_PN = "1";
"SRC":   PN = "2"  !CDS_PN = "2";
BODY = "RES","I204": #LOCATION = "R1D21" !CDS_LOCATION = "R1D21" #SEC = "1" !CDS_SEC = "1";
"A":   PN = "1"  !CDS_PN = "1";
"B":   PN = "2"  !CDS_PN = "2";
BODY = "RES","I210": #LOCATION = "R9P4" !CDS_LOCATION = "R9P4" #SEC = "1" !CDS_SEC = "1";
"A":   PN = "1"  !CDS_PN = "1";
"B":   PN = "2"  !CDS_PN = "2";
BODY = "DIODE","I213": #LOCATION = "CR9P2" !CDS_LOCATION = "CR9P2" #SEC = "1" !CDS_SEC = "1";
"A":   PN = "2"  !CDS_PN = "2";
"C":   PN = "1"  !CDS_PN = "1";
BODY = "DIODE","I214": #LOCATION = "CR9P1" !CDS_LOCATION = "CR9P1" #SEC = "1" !CDS_SEC = "1";
"A":   PN = "2"  !CDS_PN = "2";
"C":   PN = "1"  !CDS_PN = "1";
BODY = "RES","I215": #LOCATION = "R9P5" !CDS_LOCATION = "R9P5" #SEC = "1" !CDS_SEC = "1";
"A":   PN = "1"  !CDS_PN = "1";
"B":   PN = "2"  !CDS_PN = "2";
BODY = "RES","I218": #LOCATION = "R9P12" !CDS_LOCATION = "R9P12" #SEC = "1" !CDS_SEC = "1";
"A":   PN = "1"  !CDS_PN = "1";
"B":   PN = "2"  !CDS_PN = "2";
BODY = "DIODE","I220": #LOCATION = "CR1F5" !CDS_LOCATION = "CR1F5" #SEC = "1" !CDS_SEC = "1";
"A":   PN = "2"  !CDS_PN = "2";
"C":   PN = "1"  !CDS_PN = "1";
BODY = "RES","I222": #LOCATION = "R9P33" !CDS_LOCATION = "R9P33" &SEC = "1" #&CDS_SEC = "1";
"A":   PN = "1"  !CDS_PN = "1";
"B":   PN = "2"  !CDS_PN = "2";
BODY = "FET_N","I225": #LOCATION = "Q6W1" !CDS_LOCATION = "Q6W1" &SEC = "1" #&CDS_SEC = "1";
"DRN":   PN = "3"  !CDS_PN = "3";
"GATE":   PN = "1"  !CDS_PN = "1";
"SRC":   PN = "2"  !CDS_PN = "2";
BODY = "RES","I229": #LOCATION = "R6W1" !CDS_LOCATION = "R6W1" &SEC = "1" #&CDS_SEC = "1";
"A":   PN = "1"  !CDS_PN = "1";
"B":   PN = "2"  !CDS_PN = "2";
BODY = "RES","I230": #LOCATION = "R6W2" !CDS_LOCATION = "R6W2" &SEC = "1" #&CDS_SEC = "1";
"A":   PN = "1"  !CDS_PN = "1";
"B":   PN = "2"  !CDS_PN = "2";
BODY = "SC22P50V2JN-4GP","I235": #LOCATION = "C9W1" !CDS_LOCATION = "C9W1" &SEC = "1" #&CDS_SEC = "1";
"1":   PN = "1"  !CDS_PN = "1";
"2":   PN = "2"  !CDS_PN = "2";
BODY = "SC22P50V2JN-4GP","I236": #LOCATION = "C9W2" !CDS_LOCATION = "C9W2" &SEC = "1" #&CDS_SEC = "1";
"1":   PN = "1"  !CDS_PN = "1";
"2":   PN = "2"  !CDS_PN = "2";
BODY = "232KR2F-2-GP","I239": #LOCATION = "R6W3" !CDS_LOCATION = "R6W3" &SEC = "1" #&CDS_SEC = "1";
"1":   PN = "1"  !CDS_PN = "1";
"2":   PN = "2"  !CDS_PN = "2";
DRAWING = "@baseboard_fab2_lib.baseboard_fab2(sch_1):page201";
BODY = "RES","I19": #LOCATION = "R4E4" !CDS_LOCATION = "R4E4" #SEC = "1" !CDS_SEC = "1";
"A":   PN = "1"  !CDS_PN = "1";
"B":   PN = "2"  !CDS_PN = "2";
BODY = "RES","I20": #LOCATION = "R4E10" !CDS_LOCATION = "R4E10" #SEC = "1" !CDS_SEC = "1";
"A":   PN = "1"  !CDS_PN = "1";
"B":   PN = "2"  !CDS_PN = "2";
BODY = "RES","I22": #LOCATION = "R4D31" !CDS_LOCATION = "R4D31" #SEC = "1" !CDS_SEC = "1";
"A":   PN = "1"  !CDS_PN = "1";
"B":   PN = "2"  !CDS_PN = "2";
BODY = "RES","I25": #LOCATION = "R4D58" !CDS_LOCATION = "R4D58" #SEC = "1" !CDS_SEC = "1";
"A":   PN = "1"  !CDS_PN = "1";
"B":   PN = "2"  !CDS_PN = "2";
BODY = "RES","I26": #LOCATION = "R4D67" !CDS_LOCATION = "R4D67" #SEC = "1" !CDS_SEC = "1";
"A":   PN = "1"  !CDS_PN = "1";
"B":   PN = "2"  !CDS_PN = "2";
BODY = "RES","I27": #LOCATION = "R4E5" !CDS_LOCATION = "R4E5" #SEC = "1" !CDS_SEC = "1";
"A":   PN = "1"  !CDS_PN = "1";
"B":   PN = "2"  !CDS_PN = "2";
BODY = "RES","I28": #LOCATION = "R4D50" !CDS_LOCATION = "R4D50" #SEC = "1" !CDS_SEC = "1";
"A":   PN = "1"  !CDS_PN = "1";
"B":   PN = "2"  !CDS_PN = "2";
BODY = "CAP_A","I30": #LOCATION = "C4D25" !CDS_LOCATION = "C4D25" #SEC = "1" !CDS_SEC = "1";
"A":   PN = "1"  !CDS_PN = "1";
"B":   PN = "2"  !CDS_PN = "2";
BODY = "RES","I31": #LOCATION = "R4D53" !CDS_LOCATION = "R4D53" #SEC = "1" !CDS_SEC = "1";
"A":   PN = "1"  !CDS_PN = "1";
"B":   PN = "2"  !CDS_PN = "2";
BODY = "CAP_A","I32": #LOCATION = "C4D26" !CDS_LOCATION = "C4D26" #SEC = "1" !CDS_SEC = "1";
"A":   PN = "1"  !CDS_PN = "1";
"B":   PN = "2"  !CDS_PN = "2";
BODY = "CAP_A","I37": #LOCATION = "C4D15" !CDS_LOCATION = "C4D15" #SEC = "1" !CDS_SEC = "1";
"A":   PN = "1"  !CDS_PN = "1";
"B":   PN = "2"  !CDS_PN = "2";
BODY = "CAP_A","I39": #LOCATION = "C4D19" !CDS_LOCATION = "C4D19" #SEC = "1" !CDS_SEC = "1";
"A":   PN = "1"  !CDS_PN = "1";
"B":   PN = "2"  !CDS_PN = "2";
BODY = "RES","I40": #LOCATION = "R4D26" !CDS_LOCATION = "R4D26" #SEC = "1" !CDS_SEC = "1";
"A":   PN = "1"  !CDS_PN = "1";
"B":   PN = "2"  !CDS_PN = "2";
BODY = "RES","I52": #LOCATION = "R4E9" !CDS_LOCATION = "R4E9" #SEC = "1" !CDS_SEC = "1";
"A":   PN = "1"  !CDS_PN = "1";
"B":   PN = "2"  !CDS_PN = "2";
BODY = "RES","I54": #LOCATION = "R4D27" !CDS_LOCATION = "R4D27" #SEC = "1" !CDS_SEC = "1";
"A":   PN = "1"  !CDS_PN = "1";
"B":   PN = "2"  !CDS_PN = "2";
BODY = "RES","I55": #LOCATION = "R4D32" !CDS_LOCATION = "R4D32" #SEC = "1" !CDS_SEC = "1";
"A":   PN = "1"  !CDS_PN = "1";
"B":   PN = "2"  !CDS_PN = "2";
BODY = "RES","I56": #LOCATION = "R4E6" !CDS_LOCATION = "R4E6" #SEC = "1" !CDS_SEC = "1";
"A":   PN = "1"  !CDS_PN = "1";
"B":   PN = "2"  !CDS_PN = "2";
BODY = "CAP","I60": #LOCATION = "C4D20" !CDS_LOCATION = "C4D20" #SEC = "1" !CDS_SEC = "1";
"A":   PN = "1"  !CDS_PN = "1";
"B":   PN = "2"  !CDS_PN = "2";
BODY = "CAP","I64": #LOCATION = "C4D29" !CDS_LOCATION = "C4D29" #SEC = "1" !CDS_SEC = "1";
"A":   PN = "1"  !CDS_PN = "1";
"B":   PN = "2"  !CDS_PN = "2";
BODY = "CAP","I66": #LOCATION = "C4D17" !CDS_LOCATION = "C4D17" #SEC = "1" !CDS_SEC = "1";
"A":   PN = "1"  !CDS_PN = "1";
"B":   PN = "2"  !CDS_PN = "2";
BODY = "CAP","I68": #LOCATION = "C4D18" !CDS_LOCATION = "C4D18" #SEC = "1" !CDS_SEC = "1";
"A":   PN = "1"  !CDS_PN = "1";
"B":   PN = "2"  !CDS_PN = "2";
BODY = "CAP","I70": #LOCATION = "C4D45" !CDS_LOCATION = "C4D45" #SEC = "1" !CDS_SEC = "1";
"A":   PN = "1"  !CDS_PN = "1";
"B":   PN = "2"  !CDS_PN = "2";
BODY = "RES","I98": #LOCATION = "R4D66" !CDS_LOCATION = "R4D66" #SEC = "1" !CDS_SEC = "1";
"A":   PN = "1"  !CDS_PN = "1";
"B":   PN = "2"  !CDS_PN = "2";
BODY = "RES","I102": #LOCATION = "R6P32" !CDS_LOCATION = "R6P32" &SEC = "1" #&CDS_SEC = "1";
"A":   PN = "1"  !CDS_PN = "1";
"B":   PN = "2"  !CDS_PN = "2";
BODY = "RES","I103": #LOCATION = "R6P37" !CDS_LOCATION = "R6P37" &SEC = "1" #&CDS_SEC = "1";
"A":   PN = "1"  !CDS_PN = "1";
"B":   PN = "2"  !CDS_PN = "2";
BODY = "RES","I109": #LOCATION = "R4E8" !CDS_LOCATION = "R4E8" #SEC = "1" !CDS_SEC = "1";
"A":   PN = "1"  !CDS_PN = "1";
"B":   PN = "2"  !CDS_PN = "2";
BODY = "RES","I110": #LOCATION = "R4D39" !CDS_LOCATION = "R4D39" #SEC = "1" !CDS_SEC = "1";
"A":   PN = "1"  !CDS_PN = "1";
"B":   PN = "2"  !CDS_PN = "2";
BODY = "RES","I111": #LOCATION = "R4E3" !CDS_LOCATION = "R4E3" #SEC = "1" !CDS_SEC = "1";
"A":   PN = "1"  !CDS_PN = "1";
"B":   PN = "2"  !CDS_PN = "2";
BODY = "RES","I116": #LOCATION = "R4E20" !CDS_LOCATION = "R4E20" #SEC = "1" !CDS_SEC = "1";
"A":   PN = "1"  !CDS_PN = "1";
"B":   PN = "2"  !CDS_PN = "2";
BODY = "RES","I120": #LOCATION = "R6P27" !CDS_LOCATION = "R6P27" #SEC = "1" !CDS_SEC = "1";
"A":   PN = "1"  !CDS_PN = "1";
"B":   PN = "2"  !CDS_PN = "2";
BODY = "RES","I121": #LOCATION = "R6P28" !CDS_LOCATION = "R6P28" #SEC = "1" !CDS_SEC = "1";
"A":   PN = "1"  !CDS_PN = "1";
"B":   PN = "2"  !CDS_PN = "2";
BODY = "CONN3_C95678002","I122": #LOCATION = "J8D4" !CDS_LOCATION = "J8D4" #SEC = "1" !CDS_SEC = "1";
"IO1":   PN = "1"  !CDS_PN = "1";
"IO2":   PN = "2"  !CDS_PN = "2";
"IO3":   PN = "3"  !CDS_PN = "3";
BODY = "RES","I124": #LOCATION = "R4D63" !CDS_LOCATION = "R4D63" &SEC = "1" #&CDS_SEC = "1";
"A":   PN = "1"  !CDS_PN = "1";
"B":   PN = "2"  !CDS_PN = "2";
BODY = "CAP","I125": #LOCATION = "C4D42" !CDS_LOCATION = "C4D42" #SEC = "1" !CDS_SEC = "1";
"A":   PN = "1"  !CDS_PN = "1";
"B":   PN = "2"  !CDS_PN = "2";
BODY = "RES","I127": #LOCATION = "R4D65" !CDS_LOCATION = "R4D65" #SEC = "1" !CDS_SEC = "1";
"A":   PN = "1"  !CDS_PN = "1";
"B":   PN = "2"  !CDS_PN = "2";
BODY = "RES","I128": #LOCATION = "R6P45" !CDS_LOCATION = "R6P45" #SEC = "1" !CDS_SEC = "1";
"A":   PN = "1"  !CDS_PN = "1";
"B":   PN = "2"  !CDS_PN = "2";
BODY = "RES","I131": #LOCATION = "R6P18" !CDS_LOCATION = "R6P18" #SEC = "1" !CDS_SEC = "1";
"A":   PN = "1"  !CDS_PN = "1";
"B":   PN = "2"  !CDS_PN = "2";
BODY = "RES","I132": #LOCATION = "R6P16" !CDS_LOCATION = "R6P16" &SEC = "1" #&CDS_SEC = "1";
"A":   PN = "1"  !CDS_PN = "1";
"B":   PN = "2"  !CDS_PN = "2";
BODY = "RES","I139": #LOCATION = "R6P42" !CDS_LOCATION = "R6P42" #SEC = "1" !CDS_SEC = "1";
"A":   PN = "1"  !CDS_PN = "1";
"B":   PN = "2"  !CDS_PN = "2";
BODY = "RES","I147": #LOCATION = "R6P38" !CDS_LOCATION = "R6P38" #SEC = "1" !CDS_SEC = "1";
"A":   PN = "1"  !CDS_PN = "1";
"B":   PN = "2"  !CDS_PN = "2";
BODY = "RES","I148": #LOCATION = "R6P34" !CDS_LOCATION = "R6P34" #SEC = "1" !CDS_SEC = "1";
"A":   PN = "1"  !CDS_PN = "1";
"B":   PN = "2"  !CDS_PN = "2";
BODY = "RES","I149": #LOCATION = "R6P30" !CDS_LOCATION = "R6P30" #SEC = "1" !CDS_SEC = "1";
"A":   PN = "1"  !CDS_PN = "1";
"B":   PN = "2"  !CDS_PN = "2";
BODY = "RES","I150": #LOCATION = "R6P43" !CDS_LOCATION = "R6P43" #SEC = "1" !CDS_SEC = "1";
"A":   PN = "1"  !CDS_PN = "1";
"B":   PN = "2"  !CDS_PN = "2";
BODY = "RES","I154": #LOCATION = "R6P29" !CDS_LOCATION = "R6P29" #SEC = "1" !CDS_SEC = "1";
"A":   PN = "1"  !CDS_PN = "1";
"B":   PN = "2"  !CDS_PN = "2";
BODY = "PXE1610B","I155": #LOCATION = "EU4D4" !CDS_LOCATION = "EU4D4" &SEC = "1" #&CDS_SEC = "1";
"AIREF1":   PN = "23"  !CDS_PN = "23";
"AIREF2":   PN = "25"  !CDS_PN = "25";
"AIREF3":   PN = "27"  !CDS_PN = "27";
"AIREF4":   PN = "29"  !CDS_PN = "29";
"AIREF5":   PN = "31"  !CDS_PN = "31";
"AIREF6":   PN = "33"  !CDS_PN = "33";
"AISEN1":   PN = "24"  !CDS_PN = "24";
"AISEN2":   PN = "26"  !CDS_PN = "26";
"AISEN3":   PN = "28"  !CDS_PN = "28";
"AISEN4":   PN = "30"  !CDS_PN = "30";
"AISEN5":   PN = "32"  !CDS_PN = "32";
"AISEN6":   PN = "34"  !CDS_PN = "34";
"APWM1":   PN = "7"  !CDS_PN = "7";
"APWM2":   PN = "6"  !CDS_PN = "6";
"APWM3":   PN = "5"  !CDS_PN = "5";
"APWM4":   PN = "4"  !CDS_PN = "4";
"APWM5":   PN = "3"  !CDS_PN = "3";
"APWM6":   PN = "2"  !CDS_PN = "2";
"ATSEN":   PN = "43"  !CDS_PN = "43";
"AVREF":   PN = "22"  !CDS_PN = "22";
"AVREN":   PN = "12"  !CDS_PN = "12";
"AVRRDY":   PN = "11"  !CDS_PN = "11";
"AVSEN":   PN = "21"  !CDS_PN = "21";
"BIREF1":   PN = "37"  !CDS_PN = "37";
"BISEN1":   PN = "38"  !CDS_PN = "38";
"BPWM1":   PN = "1"  !CDS_PN = "1";
"BTSEN":   PN = "42"  !CDS_PN = "42";
"BVREF":   PN = "36"  !CDS_PN = "36";
"BVSEN":   PN = "35"  !CDS_PN = "35";
"IINSEN":   PN = "46"  !CDS_PN = "46";
"MP0":   PN = "15"  !CDS_PN = "15";
"MP1":   PN = "16"  !CDS_PN = "16";
"MP2":   PN = "20"  !CDS_PN = "20";
"MP3":   PN = "39"  !CDS_PN = "39";
"MP4":   PN = "40"  !CDS_PN = "40";
"PINALRT_N":   PN = "14"  !CDS_PN = "14";
"RESET_N":   PN = "10"  !CDS_PN = "10";
"SCL":   PN = "9"  !CDS_PN = "9";
"SDA":   PN = "8"  !CDS_PN = "8";
"THPAD":   PN = "49"  !CDS_PN = "49";
"VALRT_N":   PN = "19"  !CDS_PN = "19";
"VCLK":   PN = "17"  !CDS_PN = "17";
"VD12":   PN = "48"  !CDS_PN = "48";
"VDD":   PN = "47"  !CDS_PN = "47";
"VDIO":   PN = "18"  !CDS_PN = "18";
"VINSEN":   PN = "45"  !CDS_PN = "45";
"VRHOT_N":   PN = "13"  !CDS_PN = "13";
"XADDR1":   PN = "44"  !CDS_PN = "44";
"XADDR2":   PN = "41"  !CDS_PN = "41";
DRAWING = "@baseboard_fab2_lib.baseboard_fab2(sch_1):page206";
BODY = "RES","I4": #LOCATION = "R9P1" !CDS_LOCATION = "R9P1" #SEC = "1" !CDS_SEC = "1";
"A":   PN = "1"  !CDS_PN = "1";
"B":   PN = "2"  !CDS_PN = "2";
BODY = "RES","I6": #LOCATION = "R1D6" !CDS_LOCATION = "R1D6" #SEC = "1" !CDS_SEC = "1";
"A":   PN = "1"  !CDS_PN = "1";
"B":   PN = "2"  !CDS_PN = "2";
BODY = "RES","I7": #LOCATION = "R1D7" !CDS_LOCATION = "R1D7" #SEC = "1" !CDS_SEC = "1";
"A":   PN = "1"  !CDS_PN = "1";
"B":   PN = "2"  !CDS_PN = "2";
BODY = "RES","I27": #LOCATION = "R1C23" !CDS_LOCATION = "R1C23" #SEC = "1" !CDS_SEC = "1";
"A":   PN = "1"  !CDS_PN = "1";
"B":   PN = "2"  !CDS_PN = "2";
BODY = "RES","I28": #LOCATION = "R1C25" !CDS_LOCATION = "R1C25" #SEC = "1" !CDS_SEC = "1";
"A":   PN = "1"  !CDS_PN = "1";
"B":   PN = "2"  !CDS_PN = "2";
BODY = "CAP_A","I29": #LOCATION = "C1C13" !CDS_LOCATION = "C1C13" &SEC = "1" #&CDS_SEC = "1";
"A":   PN = "1"  !CDS_PN = "1";
"B":   PN = "2"  !CDS_PN = "2";
BODY = "CAP_A","I31": #LOCATION = "C1C14" !CDS_LOCATION = "C1C14" #SEC = "1" !CDS_SEC = "1";
"A":   PN = "1"  !CDS_PN = "1";
"B":   PN = "2"  !CDS_PN = "2";
BODY = "RES","I33": #LOCATION = "R1D53" !CDS_LOCATION = "R1D53" #SEC = "1" !CDS_SEC = "1";
"A":   PN = "1"  !CDS_PN = "1";
"B":   PN = "2"  !CDS_PN = "2";
BODY = "RES","I34": #LOCATION = "R1C18" !CDS_LOCATION = "R1C18" #SEC = "1" !CDS_SEC = "1";
"A":   PN = "1"  !CDS_PN = "1";
"B":   PN = "2"  !CDS_PN = "2";
BODY = "RES","I35": #LOCATION = "R1C28" !CDS_LOCATION = "R1C28" #SEC = "1" !CDS_SEC = "1";
"A":   PN = "1"  !CDS_PN = "1";
"B":   PN = "2"  !CDS_PN = "2";
BODY = "RES","I36": #LOCATION = "R1D8" !CDS_LOCATION = "R1D8" #SEC = "1" !CDS_SEC = "1";
"A":   PN = "1"  !CDS_PN = "1";
"B":   PN = "2"  !CDS_PN = "2";
BODY = "RES","I37": #LOCATION = "R1D3" !CDS_LOCATION = "R1D3" #SEC = "1" !CDS_SEC = "1";
"A":   PN = "1"  !CDS_PN = "1";
"B":   PN = "2"  !CDS_PN = "2";
BODY = "RES","I38": #LOCATION = "R1D2" !CDS_LOCATION = "R1D2" #SEC = "1" !CDS_SEC = "1";
"A":   PN = "1"  !CDS_PN = "1";
"B":   PN = "2"  !CDS_PN = "2";
BODY = "CAP_A","I41": #LOCATION = "C1C7" !CDS_LOCATION = "C1C7" &SEC = "1" #&CDS_SEC = "1";
"A":   PN = "1"  !CDS_PN = "1";
"B":   PN = "2"  !CDS_PN = "2";
BODY = "CAP_A","I42": #LOCATION = "C1C9" !CDS_LOCATION = "C1C9" #SEC = "1" !CDS_SEC = "1";
"A":   PN = "1"  !CDS_PN = "1";
"B":   PN = "2"  !CDS_PN = "2";
BODY = "RES","I46": #LOCATION = "R1C14" !CDS_LOCATION = "R1C14" #SEC = "1" !CDS_SEC = "1";
"A":   PN = "1"  !CDS_PN = "1";
"B":   PN = "2"  !CDS_PN = "2";
BODY = "RES","I49": #LOCATION = "R1C13" !CDS_LOCATION = "R1C13" #SEC = "1" !CDS_SEC = "1";
"A":   PN = "1"  !CDS_PN = "1";
"B":   PN = "2"  !CDS_PN = "2";
BODY = "RES","I53": #LOCATION = "R9P2" !CDS_LOCATION = "R9P2" #SEC = "1" !CDS_SEC = "1";
"A":   PN = "1"  !CDS_PN = "1";
"B":   PN = "2"  !CDS_PN = "2";
BODY = "RES","I54": #LOCATION = "R1D9" !CDS_LOCATION = "R1D9" &SEC = "1" #&CDS_SEC = "1";
"A":   PN = "1"  !CDS_PN = "1";
"B":   PN = "2"  !CDS_PN = "2";
BODY = "RES","I56": #LOCATION = "R1C16" !CDS_LOCATION = "R1C16" #SEC = "1" !CDS_SEC = "1";
"A":   PN = "1"  !CDS_PN = "1";
"B":   PN = "2"  !CDS_PN = "2";
BODY = "CAP","I68": #LOCATION = "C1C16" !CDS_LOCATION = "C1C16" #SEC = "1" !CDS_SEC = "1";
"A":   PN = "1"  !CDS_PN = "1";
"B":   PN = "2"  !CDS_PN = "2";
BODY = "CAP","I69": #LOCATION = "C1C10" !CDS_LOCATION = "C1C10" #SEC = "1" !CDS_SEC = "1";
"A":   PN = "1"  !CDS_PN = "1";
"B":   PN = "2"  !CDS_PN = "2";
BODY = "CAP","I71": #LOCATION = "C1C11" !CDS_LOCATION = "C1C11" #SEC = "1" !CDS_SEC = "1";
"A":   PN = "1"  !CDS_PN = "1";
"B":   PN = "2"  !CDS_PN = "2";
BODY = "CAP","I73": #LOCATION = "C1C8" !CDS_LOCATION = "C1C8" #SEC = "1" !CDS_SEC = "1";
"A":   PN = "1"  !CDS_PN = "1";
"B":   PN = "2"  !CDS_PN = "2";
BODY = "RES","I77": #LOCATION = "R1C21" !CDS_LOCATION = "R1C21" #SEC = "1" !CDS_SEC = "1";
"A":   PN = "1"  !CDS_PN = "1";
"B":   PN = "2"  !CDS_PN = "2";
BODY = "CAP","I78": #LOCATION = "C1D1" !CDS_LOCATION = "C1D1" #SEC = "1" !CDS_SEC = "1";
"A":   PN = "1"  !CDS_PN = "1";
"B":   PN = "2"  !CDS_PN = "2";
BODY = "RES","I79": #LOCATION = "R1D4" !CDS_LOCATION = "R1D4" #SEC = "1" !CDS_SEC = "1";
"A":   PN = "1"  !CDS_PN = "1";
"B":   PN = "2"  !CDS_PN = "2";
BODY = "RES","I111": #LOCATION = "R9N7" !CDS_LOCATION = "R9N7" #SEC = "1" !CDS_SEC = "1";
"A":   PN = "1"  !CDS_PN = "1";
"B":   PN = "2"  !CDS_PN = "2";
BODY = "RES","I112": #LOCATION = "R9N8" !CDS_LOCATION = "R9N8" #SEC = "1" !CDS_SEC = "1";
"A":   PN = "1"  !CDS_PN = "1";
"B":   PN = "2"  !CDS_PN = "2";
BODY = "RES","I113": #LOCATION = "R1C30" !CDS_LOCATION = "R1C30" #SEC = "1" !CDS_SEC = "1";
"A":   PN = "1"  !CDS_PN = "1";
"B":   PN = "2"  !CDS_PN = "2";
BODY = "CAP","I114": #LOCATION = "C1C23" !CDS_LOCATION = "C1C23" #SEC = "1" !CDS_SEC = "1";
"A":   PN = "1"  !CDS_PN = "1";
"B":   PN = "2"  !CDS_PN = "2";
BODY = "RES","I116": #LOCATION = "R1D1" !CDS_LOCATION = "R1D1" #SEC = "1" !CDS_SEC = "1";
"A":   PN = "1"  !CDS_PN = "1";
"B":   PN = "2"  !CDS_PN = "2";
BODY = "RES","I117": #LOCATION = "R9P3" !CDS_LOCATION = "R9P3" #SEC = "1" !CDS_SEC = "1";
"A":   PN = "1"  !CDS_PN = "1";
"B":   PN = "2"  !CDS_PN = "2";
BODY = "RES","I119": #LOCATION = "R9N16" !CDS_LOCATION = "R9N16" #SEC = "1" !CDS_SEC = "1";
"A":   PN = "1"  !CDS_PN = "1";
"B":   PN = "2"  !CDS_PN = "2";
BODY = "RES","I120": #LOCATION = "R9N14" !CDS_LOCATION = "R9N14" #SEC = "1" !CDS_SEC = "1";
"A":   PN = "1"  !CDS_PN = "1";
"B":   PN = "2"  !CDS_PN = "2";
BODY = "RES","I122": #LOCATION = "R9N15" !CDS_LOCATION = "R9N15" #SEC = "1" !CDS_SEC = "1";
"A":   PN = "1"  !CDS_PN = "1";
"B":   PN = "2"  !CDS_PN = "2";
BODY = "RES","I123": #LOCATION = "R9N17" !CDS_LOCATION = "R9N17" #SEC = "1" !CDS_SEC = "1";
"A":   PN = "1"  !CDS_PN = "1";
"B":   PN = "2"  !CDS_PN = "2";
BODY = "RES","I124": #LOCATION = "R9N12" !CDS_LOCATION = "R9N12" #SEC = "1" !CDS_SEC = "1";
"A":   PN = "1"  !CDS_PN = "1";
"B":   PN = "2"  !CDS_PN = "2";
BODY = "RES","I125": #LOCATION = "R9N10" !CDS_LOCATION = "R9N10" #SEC = "1" !CDS_SEC = "1";
"A":   PN = "1"  !CDS_PN = "1";
"B":   PN = "2"  !CDS_PN = "2";
BODY = "RES","I126": #LOCATION = "R9N9" !CDS_LOCATION = "R9N9" #SEC = "1" !CDS_SEC = "1";
"A":   PN = "1"  !CDS_PN = "1";
"B":   PN = "2"  !CDS_PN = "2";
BODY = "RES","I128": #LOCATION = "R9N5" !CDS_LOCATION = "R9N5" #SEC = "1" !CDS_SEC = "1";
"A":   PN = "1"  !CDS_PN = "1";
"B":   PN = "2"  !CDS_PN = "2";
BODY = "PXE1610B","I130": #LOCATION = "EU1C2" !CDS_LOCATION = "EU1C2" #SEC = "1" !CDS_SEC = "1";
"AIREF1":   PN = "23"  !CDS_PN = "23";
"AIREF2":   PN = "25"  !CDS_PN = "25";
"AIREF3":   PN = "27"  !CDS_PN = "27";
"AIREF4":   PN = "29"  !CDS_PN = "29";
"AIREF5":   PN = "31"  !CDS_PN = "31";
"AIREF6":   PN = "33"  !CDS_PN = "33";
"AISEN1":   PN = "24"  !CDS_PN = "24";
"AISEN2":   PN = "26"  !CDS_PN = "26";
"AISEN3":   PN = "28"  !CDS_PN = "28";
"AISEN4":   PN = "30"  !CDS_PN = "30";
"AISEN5":   PN = "32"  !CDS_PN = "32";
"AISEN6":   PN = "34"  !CDS_PN = "34";
"APWM1":   PN = "7"  !CDS_PN = "7";
"APWM2":   PN = "6"  !CDS_PN = "6";
"APWM3":   PN = "5"  !CDS_PN = "5";
"APWM4":   PN = "4"  !CDS_PN = "4";
"APWM5":   PN = "3"  !CDS_PN = "3";
"APWM6":   PN = "2"  !CDS_PN = "2";
"ATSEN":   PN = "43"  !CDS_PN = "43";
"AVREF":   PN = "22"  !CDS_PN = "22";
"AVREN":   PN = "12"  !CDS_PN = "12";
"AVRRDY":   PN = "11"  !CDS_PN = "11";
"AVSEN":   PN = "21"  !CDS_PN = "21";
"BIREF1":   PN = "37"  !CDS_PN = "37";
"BISEN1":   PN = "38"  !CDS_PN = "38";
"BPWM1":   PN = "1"  !CDS_PN = "1";
"BTSEN":   PN = "42"  !CDS_PN = "42";
"BVREF":   PN = "36"  !CDS_PN = "36";
"BVSEN":   PN = "35"  !CDS_PN = "35";
"IINSEN":   PN = "46"  !CDS_PN = "46";
"MP0":   PN = "15"  !CDS_PN = "15";
"MP1":   PN = "16"  !CDS_PN = "16";
"MP2":   PN = "20"  !CDS_PN = "20";
"MP3":   PN = "39"  !CDS_PN = "39";
"MP4":   PN = "40"  !CDS_PN = "40";
"PINALRT_N":   PN = "14"  !CDS_PN = "14";
"RESET_N":   PN = "10"  !CDS_PN = "10";
"SCL":   PN = "9"  !CDS_PN = "9";
"SDA":   PN = "8"  !CDS_PN = "8";
"THPAD":   PN = "49"  !CDS_PN = "49";
"VALRT_N":   PN = "19"  !CDS_PN = "19";
"VCLK":   PN = "17"  !CDS_PN = "17";
"VD12":   PN = "48"  !CDS_PN = "48";
"VDD":   PN = "47"  !CDS_PN = "47";
"VDIO":   PN = "18"  !CDS_PN = "18";
"VINSEN":   PN = "45"  !CDS_PN = "45";
"VRHOT_N":   PN = "13"  !CDS_PN = "13";
"XADDR1":   PN = "44"  !CDS_PN = "44";
"XADDR2":   PN = "41"  !CDS_PN = "41";
DRAWING = "@baseboard_fab2_lib.baseboard_fab2(sch_1):page211";
BODY = "CAP_A","I11": #LOCATION = "C3P4" !CDS_LOCATION = "C3P4" #SEC = "1" !CDS_SEC = "1";
"A":   PN = "1"  !CDS_PN = "1";
"B":   PN = "2"  !CDS_PN = "2";
BODY = "CAP_A","I13": #LOCATION = "C3P5" !CDS_LOCATION = "C3P5" #SEC = "1" !CDS_SEC = "1";
"A":   PN = "1"  !CDS_PN = "1";
"B":   PN = "2"  !CDS_PN = "2";
BODY = "RES","I16": #LOCATION = "R3P11" !CDS_LOCATION = "R3P11" #SEC = "1" !CDS_SEC = "1";
"A":   PN = "1"  !CDS_PN = "1";
"B":   PN = "2"  !CDS_PN = "2";
BODY = "RES","I17": #LOCATION = "R3P13" !CDS_LOCATION = "R3P13" #SEC = "1" !CDS_SEC = "1";
"A":   PN = "1"  !CDS_PN = "1";
"B":   PN = "2"  !CDS_PN = "2";
BODY = "CAP_A","I20": #LOCATION = "C3P3" !CDS_LOCATION = "C3P3" &SEC = "1" #&CDS_SEC = "1";
"A":   PN = "1"  !CDS_PN = "1";
"B":   PN = "2"  !CDS_PN = "2";
BODY = "CAP_A","I22": #LOCATION = "C3P7" !CDS_LOCATION = "C3P7" #SEC = "1" !CDS_SEC = "1";
"A":   PN = "1"  !CDS_PN = "1";
"B":   PN = "2"  !CDS_PN = "2";
BODY = "RES","I24": #LOCATION = "R3P22" !CDS_LOCATION = "R3P22" #SEC = "1" !CDS_SEC = "1";
"A":   PN = "1"  !CDS_PN = "1";
"B":   PN = "2"  !CDS_PN = "2";
BODY = "RES","I28": #LOCATION = "R3P17" !CDS_LOCATION = "R3P17" #SEC = "1" !CDS_SEC = "1";
"A":   PN = "1"  !CDS_PN = "1";
"B":   PN = "2"  !CDS_PN = "2";
BODY = "RES","I29": #LOCATION = "R3P15" !CDS_LOCATION = "R3P15" #SEC = "1" !CDS_SEC = "1";
"A":   PN = "1"  !CDS_PN = "1";
"B":   PN = "2"  !CDS_PN = "2";
BODY = "RES","I31": #LOCATION = "R3P12" !CDS_LOCATION = "R3P12" #SEC = "1" !CDS_SEC = "1";
"A":   PN = "1"  !CDS_PN = "1";
"B":   PN = "2"  !CDS_PN = "2";
BODY = "RES","I32": #LOCATION = "R3P16" !CDS_LOCATION = "R3P16" #SEC = "1" !CDS_SEC = "1";
"A":   PN = "1"  !CDS_PN = "1";
"B":   PN = "2"  !CDS_PN = "2";
BODY = "CAP","I33": #LOCATION = "C3P2" !CDS_LOCATION = "C3P2" #SEC = "1" !CDS_SEC = "1";
"A":   PN = "1"  !CDS_PN = "1";
"B":   PN = "2"  !CDS_PN = "2";
BODY = "RES","I46": #LOCATION = "R3P24" !CDS_LOCATION = "R3P24" &SEC = "1" #&CDS_SEC = "1";
"A":   PN = "1"  !CDS_PN = "1";
"B":   PN = "2"  !CDS_PN = "2";
BODY = "RES","I47": #LOCATION = "R3P23" !CDS_LOCATION = "R3P23" &SEC = "1" #&CDS_SEC = "1";
"A":   PN = "1"  !CDS_PN = "1";
"B":   PN = "2"  !CDS_PN = "2";
BODY = "RES","I52": #LOCATION = "R3N31" !CDS_LOCATION = "R3N31" &SEC = "1" #&CDS_SEC = "1";
"A":   PN = "1"  !CDS_PN = "1";
"B":   PN = "2"  !CDS_PN = "2";
BODY = "RES","I56": #LOCATION = "R3P25" !CDS_LOCATION = "R3P25" #SEC = "1" !CDS_SEC = "1";
"A":   PN = "1"  !CDS_PN = "1";
"B":   PN = "2"  !CDS_PN = "2";
BODY = "RES","I58": #LOCATION = "R3P20" !CDS_LOCATION = "R3P20" #SEC = "1" !CDS_SEC = "1";
"A":   PN = "1"  !CDS_PN = "1";
"B":   PN = "2"  !CDS_PN = "2";
BODY = "RES","I60": #LOCATION = "R3N23" !CDS_LOCATION = "R3N23" #SEC = "1" !CDS_SEC = "1";
"A":   PN = "1"  !CDS_PN = "1";
"B":   PN = "2"  !CDS_PN = "2";
BODY = "RES","I61": #LOCATION = "R3P1" !CDS_LOCATION = "R3P1" #SEC = "1" !CDS_SEC = "1";
"A":   PN = "1"  !CDS_PN = "1";
"B":   PN = "2"  !CDS_PN = "2";
BODY = "RES","I64": #LOCATION = "R3P18" !CDS_LOCATION = "R3P18" #SEC = "1" !CDS_SEC = "1";
"A":   PN = "1"  !CDS_PN = "1";
"B":   PN = "2"  !CDS_PN = "2";
BODY = "RES","I65": #LOCATION = "R3N22" !CDS_LOCATION = "R3N22" &SEC = "1" #&CDS_SEC = "1";
"A":   PN = "1"  !CDS_PN = "1";
"B":   PN = "2"  !CDS_PN = "2";
BODY = "CAP","I71": #LOCATION = "C3P6" !CDS_LOCATION = "C3P6" #SEC = "1" !CDS_SEC = "1";
"A":   PN = "1"  !CDS_PN = "1";
"B":   PN = "2"  !CDS_PN = "2";
BODY = "RES","I81": #LOCATION = "R3N19" !CDS_LOCATION = "R3N19" &SEC = "1" #&CDS_SEC = "1";
"A":   PN = "1"  !CDS_PN = "1";
"B":   PN = "2"  !CDS_PN = "2";
BODY = "CAP","I83": #LOCATION = "C3N39" !CDS_LOCATION = "C3N39" #SEC = "1" !CDS_SEC = "1";
"A":   PN = "1"  !CDS_PN = "1";
"B":   PN = "2"  !CDS_PN = "2";
BODY = "RES","I87": #LOCATION = "R3P26" !CDS_LOCATION = "R3P26" &SEC = "1" #&CDS_SEC = "1";
"A":   PN = "1"  !CDS_PN = "1";
"B":   PN = "2"  !CDS_PN = "2";
BODY = "RES","I88": #LOCATION = "R3P21" !CDS_LOCATION = "R3P21" &SEC = "1" #&CDS_SEC = "1";
"A":   PN = "1"  !CDS_PN = "1";
"B":   PN = "2"  !CDS_PN = "2";
BODY = "RES","I91": #LOCATION = "R3P57" !CDS_LOCATION = "R3P57" &SEC = "1" #&CDS_SEC = "1";
"A":   PN = "1"  !CDS_PN = "1";
"B":   PN = "2"  !CDS_PN = "2";
BODY = "PXE1110B","I93": #LOCATION = "EU3P1" !CDS_LOCATION = "EU3P1" #SEC = "1" !CDS_SEC = "1";
"AIREF1":   PN = "21"  !CDS_PN = "21";
"AISEN1":   PN = "22"  !CDS_PN = "22";
"APWM1":   PN = "5"  !CDS_PN = "5";
"ATSEN":   PN = "35"  !CDS_PN = "35";
"AVREF":   PN = "20"  !CDS_PN = "20";
"AVREN":   PN = "10"  !CDS_PN = "10";
"AVRRDY":   PN = "9"  !CDS_PN = "9";
"AVSEN":   PN = "19"  !CDS_PN = "19";
"BIREF1":   PN = "25"  !CDS_PN = "25";
"BISEN1":   PN = "26"  !CDS_PN = "26";
"BPWM1":   PN = "3"  !CDS_PN = "3";
"BTSEN":   PN = "34"  !CDS_PN = "34";
"BVREF":   PN = "30"  !CDS_PN = "30";
"BVSEN":   PN = "29"  !CDS_PN = "29";
"DNC<0>":   PN = "1"  !CDS_PN = "1";
"DNC<1>":   PN = "2"  !CDS_PN = "2";
"DNC<2>":   PN = "4"  !CDS_PN = "4";
"DNC<3>":   PN = "24"  !CDS_PN = "24";
"DNC<4>":   PN = "28"  !CDS_PN = "28";
"GND<0>":   PN = "27"  !CDS_PN = "27";
"GND<1>":   PN = "23"  !CDS_PN = "23";
"IINSEN":   PN = "38"  !CDS_PN = "38";
"MP0":   PN = "13"  !CDS_PN = "13";
"MP1":   PN = "14"  !CDS_PN = "14";
"MP2":   PN = "18"  !CDS_PN = "18";
"MP3":   PN = "31"  !CDS_PN = "31";
"MP4":   PN = "32"  !CDS_PN = "32";
"PINALRT_N":   PN = "12"  !CDS_PN = "12";
"RESET_N":   PN = "8"  !CDS_PN = "8";
"SCL":   PN = "7"  !CDS_PN = "7";
"SDA":   PN = "6"  !CDS_PN = "6";
"THPAD":   PN = "41"  !CDS_PN = "41";
"VALRT_N":   PN = "17"  !CDS_PN = "17";
"VCLK":   PN = "15"  !CDS_PN = "15";
"VD12":   PN = "40"  !CDS_PN = "40";
"VDD":   PN = "39"  !CDS_PN = "39";
"VDIO":   PN = "16"  !CDS_PN = "16";
"VINSEN":   PN = "37"  !CDS_PN = "37";
"VRHOT_N":   PN = "11"  !CDS_PN = "11";
"XADDR1":   PN = "36"  !CDS_PN = "36";
"XADDR2":   PN = "33"  !CDS_PN = "33";
DRAWING = "@baseboard_fab2_lib.baseboard_fab2(sch_1):page213";
BODY = "CAP_A","I9": #LOCATION = "C4D31" !CDS_LOCATION = "C4D31" #SEC = "1" !CDS_SEC = "1";
"A":   PN = "1"  !CDS_PN = "1";
"B":   PN = "2"  !CDS_PN = "2";
BODY = "CAP_A","I11": #LOCATION = "C4D32" !CDS_LOCATION = "C4D32" #SEC = "1" !CDS_SEC = "1";
"A":   PN = "1"  !CDS_PN = "1";
"B":   PN = "2"  !CDS_PN = "2";
BODY = "RES","I13": #LOCATION = "R4D46" !CDS_LOCATION = "R4D46" #SEC = "1" !CDS_SEC = "1";
"A":   PN = "1"  !CDS_PN = "1";
"B":   PN = "2"  !CDS_PN = "2";
BODY = "RES","I14": #LOCATION = "R6P49" !CDS_LOCATION = "R6P49" #SEC = "1" !CDS_SEC = "1";
"A":   PN = "1"  !CDS_PN = "1";
"B":   PN = "2"  !CDS_PN = "2";
BODY = "RES","I15": #LOCATION = "R4D42" !CDS_LOCATION = "R4D42" &SEC = "1" #&CDS_SEC = "1";
"A":   PN = "1"  !CDS_PN = "1";
"B":   PN = "2"  !CDS_PN = "2";
BODY = "RES","I16": #LOCATION = "R4D56" !CDS_LOCATION = "R4D56" #SEC = "1" !CDS_SEC = "1";
"A":   PN = "1"  !CDS_PN = "1";
"B":   PN = "2"  !CDS_PN = "2";
BODY = "CAP_A","I17": #LOCATION = "C4D36" !CDS_LOCATION = "C4D36" &SEC = "1" #&CDS_SEC = "1";
"A":   PN = "1"  !CDS_PN = "1";
"B":   PN = "2"  !CDS_PN = "2";
BODY = "RES","I25": #LOCATION = "R4D47" !CDS_LOCATION = "R4D47" &SEC = "1" #&CDS_SEC = "1";
"A":   PN = "1"  !CDS_PN = "1";
"B":   PN = "2"  !CDS_PN = "2";
BODY = "RES","I27": #LOCATION = "R6P35" !CDS_LOCATION = "R6P35" &SEC = "1" #&CDS_SEC = "1";
"A":   PN = "1"  !CDS_PN = "1";
"B":   PN = "2"  !CDS_PN = "2";
BODY = "RES","I30": #LOCATION = "R6P33" !CDS_LOCATION = "R6P33" #SEC = "1" !CDS_SEC = "1";
"A":   PN = "1"  !CDS_PN = "1";
"B":   PN = "2"  !CDS_PN = "2";
BODY = "RES","I31": #LOCATION = "R4D60" !CDS_LOCATION = "R4D60" #SEC = "1" !CDS_SEC = "1";
"A":   PN = "1"  !CDS_PN = "1";
"B":   PN = "2"  !CDS_PN = "2";
BODY = "RES","I32": #LOCATION = "R4D57" !CDS_LOCATION = "R4D57" #SEC = "1" !CDS_SEC = "1";
"A":   PN = "1"  !CDS_PN = "1";
"B":   PN = "2"  !CDS_PN = "2";
BODY = "CAP","I33": #LOCATION = "C4D40" !CDS_LOCATION = "C4D40" #SEC = "1" !CDS_SEC = "1";
"A":   PN = "1"  !CDS_PN = "1";
"B":   PN = "2"  !CDS_PN = "2";
BODY = "CAP_A","I35": #LOCATION = "C4D38" !CDS_LOCATION = "C4D38" &SEC = "1" #&CDS_SEC = "1";
"A":   PN = "1"  !CDS_PN = "1";
"B":   PN = "2"  !CDS_PN = "2";
BODY = "RES","I37": #LOCATION = "R4D54" !CDS_LOCATION = "R4D54" &SEC = "1" #&CDS_SEC = "1";
"A":   PN = "1"  !CDS_PN = "1";
"B":   PN = "2"  !CDS_PN = "2";
BODY = "RES","I38": #LOCATION = "R4D44" !CDS_LOCATION = "R4D44" &SEC = "1" #&CDS_SEC = "1";
"A":   PN = "1"  !CDS_PN = "1";
"B":   PN = "2"  !CDS_PN = "2";
BODY = "RES","I39": #LOCATION = "R4D43" !CDS_LOCATION = "R4D43" &SEC = "1" #&CDS_SEC = "1";
"A":   PN = "1"  !CDS_PN = "1";
"B":   PN = "2"  !CDS_PN = "2";
BODY = "RES","I42": #LOCATION = "R4D64" !CDS_LOCATION = "R4D64" #SEC = "1" !CDS_SEC = "1";
"A":   PN = "1"  !CDS_PN = "1";
"B":   PN = "2"  !CDS_PN = "2";
BODY = "RES","I46": #LOCATION = "R4D51" !CDS_LOCATION = "R4D51" #SEC = "1" !CDS_SEC = "1";
"A":   PN = "1"  !CDS_PN = "1";
"B":   PN = "2"  !CDS_PN = "2";
BODY = "RES","I63": #LOCATION = "R4D49" !CDS_LOCATION = "R4D49" &SEC = "1" #&CDS_SEC = "1";
"A":   PN = "1"  !CDS_PN = "1";
"B":   PN = "2"  !CDS_PN = "2";
BODY = "RES","I65": #LOCATION = "R4E2" !CDS_LOCATION = "R4E2" &SEC = "1" #&CDS_SEC = "1";
"A":   PN = "1"  !CDS_PN = "1";
"B":   PN = "2"  !CDS_PN = "2";
BODY = "CAP","I73": #LOCATION = "C4D33" !CDS_LOCATION = "C4D33" #SEC = "1" !CDS_SEC = "1";
"A":   PN = "1"  !CDS_PN = "1";
"B":   PN = "2"  !CDS_PN = "2";
BODY = "CAP","I83": #LOCATION = "C4D44" !CDS_LOCATION = "C4D44" #SEC = "1" !CDS_SEC = "1";
"A":   PN = "1"  !CDS_PN = "1";
"B":   PN = "2"  !CDS_PN = "2";
BODY = "RES","I84": #LOCATION = "R4E7" !CDS_LOCATION = "R4E7" #SEC = "1" !CDS_SEC = "1";
"A":   PN = "1"  !CDS_PN = "1";
"B":   PN = "2"  !CDS_PN = "2";
BODY = "RES","I90": #LOCATION = "R6P41" !CDS_LOCATION = "R6P41" &SEC = "1" #&CDS_SEC = "1";
"A":   PN = "1"  !CDS_PN = "1";
"B":   PN = "2"  !CDS_PN = "2";
BODY = "RES","I91": #LOCATION = "R6P40" !CDS_LOCATION = "R6P40" &SEC = "1" #&CDS_SEC = "1";
"A":   PN = "1"  !CDS_PN = "1";
"B":   PN = "2"  !CDS_PN = "2";
BODY = "RES","I94": #LOCATION = "R4D45" !CDS_LOCATION = "R4D45" &SEC = "1" #&CDS_SEC = "1";
"A":   PN = "1"  !CDS_PN = "1";
"B":   PN = "2"  !CDS_PN = "2";
BODY = "PXE1110B","I96": #LOCATION = "EU4D5" !CDS_LOCATION = "EU4D5" #SEC = "1" !CDS_SEC = "1";
"AIREF1":   PN = "21"  !CDS_PN = "21";
"AISEN1":   PN = "22"  !CDS_PN = "22";
"APWM1":   PN = "5"  !CDS_PN = "5";
"ATSEN":   PN = "35"  !CDS_PN = "35";
"AVREF":   PN = "20"  !CDS_PN = "20";
"AVREN":   PN = "10"  !CDS_PN = "10";
"AVRRDY":   PN = "9"  !CDS_PN = "9";
"AVSEN":   PN = "19"  !CDS_PN = "19";
"BIREF1":   PN = "25"  !CDS_PN = "25";
"BISEN1":   PN = "26"  !CDS_PN = "26";
"BPWM1":   PN = "3"  !CDS_PN = "3";
"BTSEN":   PN = "34"  !CDS_PN = "34";
"BVREF":   PN = "30"  !CDS_PN = "30";
"BVSEN":   PN = "29"  !CDS_PN = "29";
"DNC<0>":   PN = "1"  !CDS_PN = "1";
"DNC<1>":   PN = "2"  !CDS_PN = "2";
"DNC<2>":   PN = "4"  !CDS_PN = "4";
"DNC<3>":   PN = "24"  !CDS_PN = "24";
"DNC<4>":   PN = "28"  !CDS_PN = "28";
"GND<0>":   PN = "27"  !CDS_PN = "27";
"GND<1>":   PN = "23"  !CDS_PN = "23";
"IINSEN":   PN = "38"  !CDS_PN = "38";
"MP0":   PN = "13"  !CDS_PN = "13";
"MP1":   PN = "14"  !CDS_PN = "14";
"MP2":   PN = "18"  !CDS_PN = "18";
"MP3":   PN = "31"  !CDS_PN = "31";
"MP4":   PN = "32"  !CDS_PN = "32";
"PINALRT_N":   PN = "12"  !CDS_PN = "12";
"RESET_N":   PN = "8"  !CDS_PN = "8";
"SCL":   PN = "7"  !CDS_PN = "7";
"SDA":   PN = "6"  !CDS_PN = "6";
"THPAD":   PN = "41"  !CDS_PN = "41";
"VALRT_N":   PN = "17"  !CDS_PN = "17";
"VCLK":   PN = "15"  !CDS_PN = "15";
"VD12":   PN = "40"  !CDS_PN = "40";
"VDD":   PN = "39"  !CDS_PN = "39";
"VDIO":   PN = "16"  !CDS_PN = "16";
"VINSEN":   PN = "37"  !CDS_PN = "37";
"VRHOT_N":   PN = "11"  !CDS_PN = "11";
"XADDR1":   PN = "36"  !CDS_PN = "36";
"XADDR2":   PN = "33"  !CDS_PN = "33";
DRAWING = "@baseboard_fab2_lib.baseboard_fab2(sch_1):page215";
BODY = "RES","I295": #LOCATION = "R3U2" !CDS_LOCATION = "R3U2" #SEC = "1" !CDS_SEC = "1";
"A":   PN = "1"  !CDS_PN = "1";
"B":   PN = "2"  !CDS_PN = "2";
BODY = "RES","I296": #LOCATION = "R7F24" !CDS_LOCATION = "R7F24" #SEC = "1" !CDS_SEC = "1";
"A":   PN = "1"  !CDS_PN = "1";
"B":   PN = "2"  !CDS_PN = "2";
BODY = "RES","I297": #LOCATION = "R7F23" !CDS_LOCATION = "R7F23" &SEC = "1" #&CDS_SEC = "1";
"A":   PN = "1"  !CDS_PN = "1";
"B":   PN = "2"  !CDS_PN = "2";
BODY = "RES","I298": #LOCATION = "R7F25" !CDS_LOCATION = "R7F25" &SEC = "1" #&CDS_SEC = "1";
"A":   PN = "1"  !CDS_PN = "1";
"B":   PN = "2"  !CDS_PN = "2";
BODY = "RES","I300": #LOCATION = "R7F36" !CDS_LOCATION = "R7F36" #SEC = "1" !CDS_SEC = "1";
"A":   PN = "1"  !CDS_PN = "1";
"B":   PN = "2"  !CDS_PN = "2";
BODY = "RES","I301": #LOCATION = "R7F22" !CDS_LOCATION = "R7F22" #SEC = "1" !CDS_SEC = "1";
"A":   PN = "1"  !CDS_PN = "1";
"B":   PN = "2"  !CDS_PN = "2";
BODY = "RES","I302": #LOCATION = "R7G4" !CDS_LOCATION = "R7G4" #SEC = "1" !CDS_SEC = "1";
"A":   PN = "1"  !CDS_PN = "1";
"B":   PN = "2"  !CDS_PN = "2";
BODY = "RES","I303": #LOCATION = "R7F27" !CDS_LOCATION = "R7F27" #SEC = "1" !CDS_SEC = "1";
"A":   PN = "1"  !CDS_PN = "1";
"B":   PN = "2"  !CDS_PN = "2";
BODY = "RES","I304": #LOCATION = "R7F26" !CDS_LOCATION = "R7F26" &SEC = "1" #&CDS_SEC = "1";
"A":   PN = "1"  !CDS_PN = "1";
"B":   PN = "2"  !CDS_PN = "2";
BODY = "CAP","I305": #LOCATION = "C7F14" !CDS_LOCATION = "C7F14" #SEC = "1" !CDS_SEC = "1";
"A":   PN = "1"  !CDS_PN = "1";
"B":   PN = "2"  !CDS_PN = "2";
BODY = "RES","I307": #LOCATION = "R7G2" !CDS_LOCATION = "R7G2" #SEC = "1" !CDS_SEC = "1";
"A":   PN = "1"  !CDS_PN = "1";
"B":   PN = "2"  !CDS_PN = "2";
BODY = "CAP_A","I309": #LOCATION = "C7F18" !CDS_LOCATION = "C7F18" &SEC = "1" #&CDS_SEC = "1";
"A":   PN = "1"  !CDS_PN = "1";
"B":   PN = "2"  !CDS_PN = "2";
BODY = "CAP_A","I311": #LOCATION = "C7F17" !CDS_LOCATION = "C7F17" #SEC = "1" !CDS_SEC = "1";
"A":   PN = "1"  !CDS_PN = "1";
"B":   PN = "2"  !CDS_PN = "2";
BODY = "RES","I313": #LOCATION = "R3T13" !CDS_LOCATION = "R3T13" #SEC = "1" !CDS_SEC = "1";
"A":   PN = "1"  !CDS_PN = "1";
"B":   PN = "2"  !CDS_PN = "2";
BODY = "RES","I315": #LOCATION = "R7F20" !CDS_LOCATION = "R7F20" &SEC = "1" #&CDS_SEC = "1";
"A":   PN = "1"  !CDS_PN = "1";
"B":   PN = "2"  !CDS_PN = "2";
BODY = "RES","I317": #LOCATION = "R7G10" !CDS_LOCATION = "R7G10" &SEC = "1" #&CDS_SEC = "1";
"A":   PN = "1"  !CDS_PN = "1";
"B":   PN = "2"  !CDS_PN = "2";
BODY = "CAP","I320": #LOCATION = "C7G3" !CDS_LOCATION = "C7G3" #SEC = "1" !CDS_SEC = "1";
"A":   PN = "1"  !CDS_PN = "1";
"B":   PN = "2"  !CDS_PN = "2";
BODY = "RES","I321": #LOCATION = "R7G8" !CDS_LOCATION = "R7G8" &SEC = "1" #&CDS_SEC = "1";
"A":   PN = "1"  !CDS_PN = "1";
"B":   PN = "2"  !CDS_PN = "2";
BODY = "CAP_A","I325": #LOCATION = "C7F16" !CDS_LOCATION = "C7F16" #SEC = "1" !CDS_SEC = "1";
"A":   PN = "1"  !CDS_PN = "1";
"B":   PN = "2"  !CDS_PN = "2";
BODY = "CAP_A","I327": #LOCATION = "C7F15" !CDS_LOCATION = "C7F15" #SEC = "1" !CDS_SEC = "1";
"A":   PN = "1"  !CDS_PN = "1";
"B":   PN = "2"  !CDS_PN = "2";
BODY = "RES","I330": #LOCATION = "R3T11" !CDS_LOCATION = "R3T11" #SEC = "1" !CDS_SEC = "1";
"A":   PN = "1"  !CDS_PN = "1";
"B":   PN = "2"  !CDS_PN = "2";
BODY = "RES","I331": #LOCATION = "R7G24" !CDS_LOCATION = "R7G24" #SEC = "1" !CDS_SEC = "1";
"A":   PN = "1"  !CDS_PN = "1";
"B":   PN = "2"  !CDS_PN = "2";
BODY = "RES","I332": #LOCATION = "R3U3" !CDS_LOCATION = "R3U3" &SEC = "1" #&CDS_SEC = "1";
"A":   PN = "1"  !CDS_PN = "1";
"B":   PN = "2"  !CDS_PN = "2";
BODY = "RES","I336": #LOCATION = "R7F34" !CDS_LOCATION = "R7F34" #SEC = "1" !CDS_SEC = "1";
"A":   PN = "1"  !CDS_PN = "1";
"B":   PN = "2"  !CDS_PN = "2";
BODY = "RES","I337": #LOCATION = "R7G3" !CDS_LOCATION = "R7G3" #SEC = "1" !CDS_SEC = "1";
"A":   PN = "1"  !CDS_PN = "1";
"B":   PN = "2"  !CDS_PN = "2";
BODY = "CAP","I339": #LOCATION = "C7G1" !CDS_LOCATION = "C7G1" #SEC = "1" !CDS_SEC = "1";
"A":   PN = "1"  !CDS_PN = "1";
"B":   PN = "2"  !CDS_PN = "2";
BODY = "RES","I341": #LOCATION = "R3U10" !CDS_LOCATION = "R3U10" &SEC = "1" #&CDS_SEC = "1";
"A":   PN = "1"  !CDS_PN = "1";
"B":   PN = "2"  !CDS_PN = "2";
BODY = "CAP","I342": #LOCATION = "C7G4" !CDS_LOCATION = "C7G4" #SEC = "1" !CDS_SEC = "1";
"A":   PN = "1"  !CDS_PN = "1";
"B":   PN = "2"  !CDS_PN = "2";
BODY = "RES","I343": #LOCATION = "R7F21" !CDS_LOCATION = "R7F21" &SEC = "1" #&CDS_SEC = "1";
"A":   PN = "1"  !CDS_PN = "1";
"B":   PN = "2"  !CDS_PN = "2";
BODY = "RES","I344": #LOCATION = "R7G9" !CDS_LOCATION = "R7G9" #SEC = "1" !CDS_SEC = "1";
"A":   PN = "1"  !CDS_PN = "1";
"B":   PN = "2"  !CDS_PN = "2";
BODY = "PXM1310B","I358": #LOCATION = "EU7G1" !CDS_LOCATION = "EU7G1" &SEC = "1" #&CDS_SEC = "1";
"AIREF1":   PN = "21"  !CDS_PN = "21";
"AIREF2":   PN = "23"  !CDS_PN = "23";
"AIREF3":   PN = "25"  !CDS_PN = "25";
"AISEN1":   PN = "22"  !CDS_PN = "22";
"AISEN2":   PN = "24"  !CDS_PN = "24";
"AISEN3":   PN = "26"  !CDS_PN = "26";
"APWM1":   PN = "5"  !CDS_PN = "5";
"APWM2":   PN = "4"  !CDS_PN = "4";
"APWM3":   PN = "3"  !CDS_PN = "3";
"ATSEN":   PN = "35"  !CDS_PN = "35";
"AVREF":   PN = "20"  !CDS_PN = "20";
"AVREN":   PN = "10"  !CDS_PN = "10";
"AVRRDY":   PN = "9"  !CDS_PN = "9";
"AVSEN":   PN = "19"  !CDS_PN = "19";
"BIREF1":   PN = "31"  !CDS_PN = "31";
"BISEN1":   PN = "32"  !CDS_PN = "32";
"BPWM1":   PN = "1"  !CDS_PN = "1";
"BTSEN":   PN = "34"  !CDS_PN = "34";
"BVREF":   PN = "30"  !CDS_PN = "30";
"BVSEN":   PN = "29"  !CDS_PN = "29";
"DNC<0>":   PN = "2"  !CDS_PN = "2";
"DNC<1>":   PN = "28"  !CDS_PN = "28";
"GND":   PN = "27"  !CDS_PN = "27";
"IINSEN":   PN = "38"  !CDS_PN = "38";
"MP0":   PN = "13"  !CDS_PN = "13";
"MP1":   PN = "14"  !CDS_PN = "14";
"MP2":   PN = "18"  !CDS_PN = "18";
"PINALRT_N":   PN = "12"  !CDS_PN = "12";
"RESET_N":   PN = "8"  !CDS_PN = "8";
"SCL":   PN = "7"  !CDS_PN = "7";
"SDA":   PN = "6"  !CDS_PN = "6";
"THPAD":   PN = "41"  !CDS_PN = "41";
"VALRT_N":   PN = "17"  !CDS_PN = "17";
"VCLK":   PN = "15"  !CDS_PN = "15";
"VD12":   PN = "40"  !CDS_PN = "40";
"VDD":   PN = "39"  !CDS_PN = "39";
"VDIO":   PN = "16"  !CDS_PN = "16";
"VINSEN":   PN = "37"  !CDS_PN = "37";
"VRHOT_N":   PN = "11"  !CDS_PN = "11";
"XADDR1":   PN = "36"  !CDS_PN = "36";
"XADDR2":   PN = "33"  !CDS_PN = "33";
BODY = "CAP_A","I360": #LOCATION = "C3U10" !CDS_LOCATION = "C3U10" #SEC = "1" !CDS_SEC = "1";
"A":   PN = "1"  !CDS_PN = "1";
"B":   PN = "2"  !CDS_PN = "2";
DRAWING = "@baseboard_fab2_lib.baseboard_fab2(sch_1):page217";
BODY = "RES","I58": #LOCATION = "R3U4" !CDS_LOCATION = "R3U4" &SEC = "1" #&CDS_SEC = "1";
"A":   PN = "1"  !CDS_PN = "1";
"B":   PN = "2"  !CDS_PN = "2";
BODY = "RES","I74": #LOCATION = "R4U6" !CDS_LOCATION = "R4U6" #SEC = "1" !CDS_SEC = "1";
"A":   PN = "1"  !CDS_PN = "1";
"B":   PN = "2"  !CDS_PN = "2";
BODY = "CAPP","I75": #LOCATION = "C7G28" !CDS_LOCATION = "C7G28" #SEC = "1" !CDS_SEC = "1";
"A":   PN = "1"  !CDS_PN = "1";
"B":   PN = "2"  !CDS_PN = "2";
BODY = "CAPP","I76": #LOCATION = "C3U1" !CDS_LOCATION = "C3U1" #SEC = "1" !CDS_SEC = "1";
"A":   PN = "1"  !CDS_PN = "1";
"B":   PN = "2"  !CDS_PN = "2";
BODY = "CAPP","I77": #LOCATION = "C3U5" !CDS_LOCATION = "C3U5" #SEC = "1" !CDS_SEC = "1";
"A":   PN = "1"  !CDS_PN = "1";
"B":   PN = "2"  !CDS_PN = "2";
BODY = "CAPP","I78": #LOCATION = "C3U8" !CDS_LOCATION = "C3U8" #SEC = "1" !CDS_SEC = "1";
"A":   PN = "1"  !CDS_PN = "1";
"B":   PN = "2"  !CDS_PN = "2";
BODY = "CAP","I82": #LOCATION = "C5U13" !CDS_LOCATION = "C5U13" #SEC = "1" !CDS_SEC = "1";
"A":   PN = "1"  !CDS_PN = "1";
"B":   PN = "2"  !CDS_PN = "2";
BODY = "CAP","I83": #LOCATION = "C5U10" !CDS_LOCATION = "C5U10" #SEC = "1" !CDS_SEC = "1";
"A":   PN = "1"  !CDS_PN = "1";
"B":   PN = "2"  !CDS_PN = "2";
BODY = "CAP","I88": #LOCATION = "C5U1" !CDS_LOCATION = "C5U1" #SEC = "1" !CDS_SEC = "1";
"A":   PN = "1"  !CDS_PN = "1";
"B":   PN = "2"  !CDS_PN = "2";
BODY = "CAP","I89": #LOCATION = "C5U14" !CDS_LOCATION = "C5U14" #SEC = "1" !CDS_SEC = "1";
"A":   PN = "1"  !CDS_PN = "1";
"B":   PN = "2"  !CDS_PN = "2";
BODY = "CAP","I90": #LOCATION = "C5U15" !CDS_LOCATION = "C5U15" #SEC = "1" !CDS_SEC = "1";
"A":   PN = "1"  !CDS_PN = "1";
"B":   PN = "2"  !CDS_PN = "2";
BODY = "CAP","I91": #LOCATION = "C4T4" !CDS_LOCATION = "C4T4" #SEC = "1" !CDS_SEC = "1";
"A":   PN = "1"  !CDS_PN = "1";
"B":   PN = "2"  !CDS_PN = "2";
BODY = "CAP","I92": #LOCATION = "C5G9" !CDS_LOCATION = "C5G9" #SEC = "1" !CDS_SEC = "1";
"A":   PN = "1"  !CDS_PN = "1";
"B":   PN = "2"  !CDS_PN = "2";
BODY = "CAP","I110": #LOCATION = "C5G20" !CDS_LOCATION = "C5G20" #SEC = "1" !CDS_SEC = "1";
"A":   PN = "1"  !CDS_PN = "1";
"B":   PN = "2"  !CDS_PN = "2";
BODY = "INDUCTOR","I124": #LOCATION = "L7F2" !CDS_LOCATION = "L7F2" #SEC = "1" !CDS_SEC = "1";
"INA":   PN = "1"  !CDS_PN = "1";
"INB":   PN = "2"  !CDS_PN = "2";
BODY = "CAPP","I175": #LOCATION = "C7G2" !CDS_LOCATION = "C7G2" #SEC = "1" !CDS_SEC = "1";
"A":   PN = "1"  !CDS_PN = "1";
"B":   PN = "2"  !CDS_PN = "2";
BODY = "CAP","I184": #LOCATION = "C5P39" !CDS_LOCATION = "C5P39" #SEC = "1" !CDS_SEC = "1";
"A":   PN = "1"  !CDS_PN = "1";
"B":   PN = "2"  !CDS_PN = "2";
BODY = "CAP","I186": #LOCATION = "C5D57" !CDS_LOCATION = "C5D57" #SEC = "1" !CDS_SEC = "1";
"A":   PN = "1"  !CDS_PN = "1";
"B":   PN = "2"  !CDS_PN = "2";
BODY = "CAP","I188": #LOCATION = "C5D56" !CDS_LOCATION = "C5D56" #SEC = "1" !CDS_SEC = "1";
"A":   PN = "1"  !CDS_PN = "1";
"B":   PN = "2"  !CDS_PN = "2";
BODY = "CAP","I189": #LOCATION = "C5D55" !CDS_LOCATION = "C5D55" #SEC = "1" !CDS_SEC = "1";
"A":   PN = "1"  !CDS_PN = "1";
"B":   PN = "2"  !CDS_PN = "2";
BODY = "CAP","I190": #LOCATION = "C5D54" !CDS_LOCATION = "C5D54" #SEC = "1" !CDS_SEC = "1";
"A":   PN = "1"  !CDS_PN = "1";
"B":   PN = "2"  !CDS_PN = "2";
BODY = "CAP","I193": #LOCATION = "C5P38" !CDS_LOCATION = "C5P38" #SEC = "1" !CDS_SEC = "1";
"A":   PN = "1"  !CDS_PN = "1";
"B":   PN = "2"  !CDS_PN = "2";
BODY = "CAP_A","I205": #LOCATION = "C5F2" !CDS_LOCATION = "C5F2" #SEC = "1" !CDS_SEC = "1";
"A":   PN = "1"  !CDS_PN = "1";
"B":   PN = "2"  !CDS_PN = "2";
BODY = "CAP_A","I206": #LOCATION = "C5F1" !CDS_LOCATION = "C5F1" #SEC = "1" !CDS_SEC = "1";
"A":   PN = "1"  !CDS_PN = "1";
"B":   PN = "2"  !CDS_PN = "2";
BODY = "CAP_A","I207": #LOCATION = "C5G10" !CDS_LOCATION = "C5G10" #SEC = "1" !CDS_SEC = "1";
"A":   PN = "1"  !CDS_PN = "1";
"B":   PN = "2"  !CDS_PN = "2";
BODY = "CAP_A","I208": #LOCATION = "C5T2" !CDS_LOCATION = "C5T2" #SEC = "1" !CDS_SEC = "1";
"A":   PN = "1"  !CDS_PN = "1";
"B":   PN = "2"  !CDS_PN = "2";
BODY = "CAP_A","I209": #LOCATION = "C5U11" !CDS_LOCATION = "C5U11" #SEC = "1" !CDS_SEC = "1";
"A":   PN = "1"  !CDS_PN = "1";
"B":   PN = "2"  !CDS_PN = "2";
BODY = "CAP_A","I210": #LOCATION = "C5T13" !CDS_LOCATION = "C5T13" #SEC = "1" !CDS_SEC = "1";
"A":   PN = "1"  !CDS_PN = "1";
"B":   PN = "2"  !CDS_PN = "2";
BODY = "CAP_A","I211": #LOCATION = "C5T4" !CDS_LOCATION = "C5T4" #SEC = "1" !CDS_SEC = "1";
"A":   PN = "1"  !CDS_PN = "1";
"B":   PN = "2"  !CDS_PN = "2";
BODY = "CAP_A","I212": #LOCATION = "C5T1" !CDS_LOCATION = "C5T1" #SEC = "1" !CDS_SEC = "1";
"A":   PN = "1"  !CDS_PN = "1";
"B":   PN = "2"  !CDS_PN = "2";
BODY = "CAP_A","I213": #LOCATION = "C5G19" !CDS_LOCATION = "C5G19" #SEC = "1" !CDS_SEC = "1";
"A":   PN = "1"  !CDS_PN = "1";
"B":   PN = "2"  !CDS_PN = "2";
BODY = "CAP_A","I216": #LOCATION = "C5T5" !CDS_LOCATION = "C5T5" &SEC = "1" #&CDS_SEC = "1";
"A":   PN = "1"  !CDS_PN = "1";
"B":   PN = "2"  !CDS_PN = "2";
BODY = "CAP_A","I217": #LOCATION = "C5G3" !CDS_LOCATION = "C5G3" &SEC = "1" #&CDS_SEC = "1";
"A":   PN = "1"  !CDS_PN = "1";
"B":   PN = "2"  !CDS_PN = "2";
BODY = "CAP_A","I218": #LOCATION = "C5T6" !CDS_LOCATION = "C5T6" &SEC = "1" #&CDS_SEC = "1";
"A":   PN = "1"  !CDS_PN = "1";
"B":   PN = "2"  !CDS_PN = "2";
BODY = "CAP_A","I219": #LOCATION = "C5T7" !CDS_LOCATION = "C5T7" &SEC = "1" #&CDS_SEC = "1";
"A":   PN = "1"  !CDS_PN = "1";
"B":   PN = "2"  !CDS_PN = "2";
BODY = "CAP_A","I220": #LOCATION = "C5G15" !CDS_LOCATION = "C5G15" &SEC = "1" #&CDS_SEC = "1";
"A":   PN = "1"  !CDS_PN = "1";
"B":   PN = "2"  !CDS_PN = "2";
BODY = "CAP_A","I221": #LOCATION = "C5G16" !CDS_LOCATION = "C5G16" &SEC = "1" #&CDS_SEC = "1";
"A":   PN = "1"  !CDS_PN = "1";
"B":   PN = "2"  !CDS_PN = "2";
BODY = "CAP_A","I222": #LOCATION = "C5T8" !CDS_LOCATION = "C5T8" &SEC = "1" #&CDS_SEC = "1";
"A":   PN = "1"  !CDS_PN = "1";
"B":   PN = "2"  !CDS_PN = "2";
BODY = "CAP_A","I223": #LOCATION = "C5G14" !CDS_LOCATION = "C5G14" #SEC = "1" !CDS_SEC = "1";
"A":   PN = "1"  !CDS_PN = "1";
"B":   PN = "2"  !CDS_PN = "2";
BODY = "CAP_A","I224": #LOCATION = "C5T9" !CDS_LOCATION = "C5T9" &SEC = "1" #&CDS_SEC = "1";
"A":   PN = "1"  !CDS_PN = "1";
"B":   PN = "2"  !CDS_PN = "2";
BODY = "CAP_A","I225": #LOCATION = "C5T10" !CDS_LOCATION = "C5T10" &SEC = "1" #&CDS_SEC = "1";
"A":   PN = "1"  !CDS_PN = "1";
"B":   PN = "2"  !CDS_PN = "2";
BODY = "CAP_A","I226": #LOCATION = "C5G17" !CDS_LOCATION = "C5G17" &SEC = "1" #&CDS_SEC = "1";
"A":   PN = "1"  !CDS_PN = "1";
"B":   PN = "2"  !CDS_PN = "2";
BODY = "CAP_A","I227": #LOCATION = "C5G18" !CDS_LOCATION = "C5G18" &SEC = "1" #&CDS_SEC = "1";
"A":   PN = "1"  !CDS_PN = "1";
"B":   PN = "2"  !CDS_PN = "2";
BODY = "CAP_A","I228": #LOCATION = "C5T11" !CDS_LOCATION = "C5T11" &SEC = "1" #&CDS_SEC = "1";
"A":   PN = "1"  !CDS_PN = "1";
"B":   PN = "2"  !CDS_PN = "2";
BODY = "CAP_A","I229": #LOCATION = "C5T12" !CDS_LOCATION = "C5T12" &SEC = "1" #&CDS_SEC = "1";
"A":   PN = "1"  !CDS_PN = "1";
"B":   PN = "2"  !CDS_PN = "2";
BODY = "CAP_A","I230": #LOCATION = "C5G8" !CDS_LOCATION = "C5G8" &SEC = "1" #&CDS_SEC = "1";
"A":   PN = "1"  !CDS_PN = "1";
"B":   PN = "2"  !CDS_PN = "2";
BODY = "CAP_A","I231": #LOCATION = "C5G1" !CDS_LOCATION = "C5G1" #SEC = "1" !CDS_SEC = "1";
"A":   PN = "1"  !CDS_PN = "1";
"B":   PN = "2"  !CDS_PN = "2";
BODY = "CAP_A","I232": #LOCATION = "C5U9" !CDS_LOCATION = "C5U9" &SEC = "1" #&CDS_SEC = "1";
"A":   PN = "1"  !CDS_PN = "1";
"B":   PN = "2"  !CDS_PN = "2";
BODY = "CAP_A","I233": #LOCATION = "C5U8" !CDS_LOCATION = "C5U8" &SEC = "1" #&CDS_SEC = "1";
"A":   PN = "1"  !CDS_PN = "1";
"B":   PN = "2"  !CDS_PN = "2";
BODY = "CAP_A","I234": #LOCATION = "C5G7" !CDS_LOCATION = "C5G7" &SEC = "1" #&CDS_SEC = "1";
"A":   PN = "1"  !CDS_PN = "1";
"B":   PN = "2"  !CDS_PN = "2";
BODY = "CAP_A","I235": #LOCATION = "C5G5" !CDS_LOCATION = "C5G5" &SEC = "1" #&CDS_SEC = "1";
"A":   PN = "1"  !CDS_PN = "1";
"B":   PN = "2"  !CDS_PN = "2";
BODY = "CAP_A","I236": #LOCATION = "C5U7" !CDS_LOCATION = "C5U7" &SEC = "1" #&CDS_SEC = "1";
"A":   PN = "1"  !CDS_PN = "1";
"B":   PN = "2"  !CDS_PN = "2";
BODY = "CAP_A","I237": #LOCATION = "C5G6" !CDS_LOCATION = "C5G6" &SEC = "1" #&CDS_SEC = "1";
"A":   PN = "1"  !CDS_PN = "1";
"B":   PN = "2"  !CDS_PN = "2";
BODY = "CAP_A","I238": #LOCATION = "C5U6" !CDS_LOCATION = "C5U6" &SEC = "1" #&CDS_SEC = "1";
"A":   PN = "1"  !CDS_PN = "1";
"B":   PN = "2"  !CDS_PN = "2";
BODY = "CAP_A","I239": #LOCATION = "C5U5" !CDS_LOCATION = "C5U5" &SEC = "1" #&CDS_SEC = "1";
"A":   PN = "1"  !CDS_PN = "1";
"B":   PN = "2"  !CDS_PN = "2";
BODY = "CAP_A","I240": #LOCATION = "C5G13" !CDS_LOCATION = "C5G13" #SEC = "1" !CDS_SEC = "1";
"A":   PN = "1"  !CDS_PN = "1";
"B":   PN = "2"  !CDS_PN = "2";
BODY = "CAP_A","I241": #LOCATION = "C5G4" !CDS_LOCATION = "C5G4" &SEC = "1" #&CDS_SEC = "1";
"A":   PN = "1"  !CDS_PN = "1";
"B":   PN = "2"  !CDS_PN = "2";
BODY = "CAP_A","I243": #LOCATION = "C5U4" !CDS_LOCATION = "C5U4" &SEC = "1" #&CDS_SEC = "1";
"A":   PN = "1"  !CDS_PN = "1";
"B":   PN = "2"  !CDS_PN = "2";
BODY = "CAP_A","I244": #LOCATION = "C5U3" !CDS_LOCATION = "C5U3" &SEC = "1" #&CDS_SEC = "1";
"A":   PN = "1"  !CDS_PN = "1";
"B":   PN = "2"  !CDS_PN = "2";
BODY = "CAP_A","I245": #LOCATION = "C5G2" !CDS_LOCATION = "C5G2" &SEC = "1" #&CDS_SEC = "1";
"A":   PN = "1"  !CDS_PN = "1";
"B":   PN = "2"  !CDS_PN = "2";
BODY = "CAP_A","I246": #LOCATION = "C5G12" !CDS_LOCATION = "C5G12" &SEC = "1" #&CDS_SEC = "1";
"A":   PN = "1"  !CDS_PN = "1";
"B":   PN = "2"  !CDS_PN = "2";
BODY = "CAP_A","I247": #LOCATION = "C5U2" !CDS_LOCATION = "C5U2" &SEC = "1" #&CDS_SEC = "1";
"A":   PN = "1"  !CDS_PN = "1";
"B":   PN = "2"  !CDS_PN = "2";
BODY = "CAP_A","I250": #LOCATION = "C5G11" !CDS_LOCATION = "C5G11" #SEC = "1" !CDS_SEC = "1";
"A":   PN = "1"  !CDS_PN = "1";
"B":   PN = "2"  !CDS_PN = "2";
BODY = "SHUNT","I259": #LOCATION = "SH4U1" !CDS_LOCATION = "SH4U1" #SEC = "1" !CDS_SEC = "1";
"A":   PN = "1"  !CDS_PN = "1";
"B":   PN = "2"  !CDS_PN = "2";
BODY = "SHUNT","I260": #LOCATION = "SH4U2" !CDS_LOCATION = "SH4U2" #SEC = "1" !CDS_SEC = "1";
"A":   PN = "1"  !CDS_PN = "1";
"B":   PN = "2"  !CDS_PN = "2";
DRAWING = "@baseboard_fab2_lib.baseboard_fab2(sch_1):page218";
BODY = "RES","I7": #LOCATION = "R3L11" !CDS_LOCATION = "R3L11" #SEC = "1" !CDS_SEC = "1";
"A":   PN = "1"  !CDS_PN = "1";
"B":   PN = "2"  !CDS_PN = "2";
BODY = "RES","I11": #LOCATION = "R3M3" !CDS_LOCATION = "R3M3" &SEC = "1" #&CDS_SEC = "1";
"A":   PN = "1"  !CDS_PN = "1";
"B":   PN = "2"  !CDS_PN = "2";
BODY = "RES","I12": #LOCATION = "R7B1" !CDS_LOCATION = "R7B1" &SEC = "1" #&CDS_SEC = "1";
"A":   PN = "1"  !CDS_PN = "1";
"B":   PN = "2"  !CDS_PN = "2";
BODY = "RES","I14": #LOCATION = "R7A9" !CDS_LOCATION = "R7A9" #SEC = "1" !CDS_SEC = "1";
"A":   PN = "1"  !CDS_PN = "1";
"B":   PN = "2"  !CDS_PN = "2";
BODY = "RES","I15": #LOCATION = "R7A11" !CDS_LOCATION = "R7A11" #SEC = "1" !CDS_SEC = "1";
"A":   PN = "1"  !CDS_PN = "1";
"B":   PN = "2"  !CDS_PN = "2";
BODY = "RES","I16": #LOCATION = "R7B5" !CDS_LOCATION = "R7B5" #SEC = "1" !CDS_SEC = "1";
"A":   PN = "1"  !CDS_PN = "1";
"B":   PN = "2"  !CDS_PN = "2";
BODY = "RES","I17": #LOCATION = "R7B4" !CDS_LOCATION = "R7B4" #SEC = "1" !CDS_SEC = "1";
"A":   PN = "1"  !CDS_PN = "1";
"B":   PN = "2"  !CDS_PN = "2";
BODY = "RES","I21": #LOCATION = "R7B3" !CDS_LOCATION = "R7B3" &SEC = "1" #&CDS_SEC = "1";
"A":   PN = "1"  !CDS_PN = "1";
"B":   PN = "2"  !CDS_PN = "2";
BODY = "CAP_A","I22": #LOCATION = "C7B1" !CDS_LOCATION = "C7B1" #SEC = "1" !CDS_SEC = "1";
"A":   PN = "1"  !CDS_PN = "1";
"B":   PN = "2"  !CDS_PN = "2";
BODY = "CAP_A","I23": #LOCATION = "C7B2" !CDS_LOCATION = "C7B2" #SEC = "1" !CDS_SEC = "1";
"A":   PN = "1"  !CDS_PN = "1";
"B":   PN = "2"  !CDS_PN = "2";
BODY = "RES","I24": #LOCATION = "R7B2" !CDS_LOCATION = "R7B2" &SEC = "1" #&CDS_SEC = "1";
"A":   PN = "1"  !CDS_PN = "1";
"B":   PN = "2"  !CDS_PN = "2";
BODY = "RES","I25": #LOCATION = "R7A12" !CDS_LOCATION = "R7A12" #SEC = "1" !CDS_SEC = "1";
"A":   PN = "1"  !CDS_PN = "1";
"B":   PN = "2"  !CDS_PN = "2";
BODY = "CAP","I26": #LOCATION = "C7B3" !CDS_LOCATION = "C7B3" #SEC = "1" !CDS_SEC = "1";
"A":   PN = "1"  !CDS_PN = "1";
"B":   PN = "2"  !CDS_PN = "2";
BODY = "CAP_A","I29": #LOCATION = "C7A37" !CDS_LOCATION = "C7A37" #SEC = "1" !CDS_SEC = "1";
"A":   PN = "1"  !CDS_PN = "1";
"B":   PN = "2"  !CDS_PN = "2";
BODY = "CAP_A","I31": #LOCATION = "C7A38" !CDS_LOCATION = "C7A38" #SEC = "1" !CDS_SEC = "1";
"A":   PN = "1"  !CDS_PN = "1";
"B":   PN = "2"  !CDS_PN = "2";
BODY = "RES","I34": #LOCATION = "R3M1" !CDS_LOCATION = "R3M1" #SEC = "1" !CDS_SEC = "1";
"A":   PN = "1"  !CDS_PN = "1";
"B":   PN = "2"  !CDS_PN = "2";
BODY = "RES","I35": #LOCATION = "R3M5" !CDS_LOCATION = "R3M5" &SEC = "1" #&CDS_SEC = "1";
"A":   PN = "1"  !CDS_PN = "1";
"B":   PN = "2"  !CDS_PN = "2";
BODY = "RES","I37": #LOCATION = "R7A8" !CDS_LOCATION = "R7A8" &SEC = "1" #&CDS_SEC = "1";
"A":   PN = "1"  !CDS_PN = "1";
"B":   PN = "2"  !CDS_PN = "2";
BODY = "CAP","I39": #LOCATION = "C7A29" !CDS_LOCATION = "C7A29" #SEC = "1" !CDS_SEC = "1";
"A":   PN = "1"  !CDS_PN = "1";
"B":   PN = "2"  !CDS_PN = "2";
BODY = "RES","I40": #LOCATION = "R7A10" !CDS_LOCATION = "R7A10" &SEC = "1" #&CDS_SEC = "1";
"A":   PN = "1"  !CDS_PN = "1";
"B":   PN = "2"  !CDS_PN = "2";
BODY = "RES","I47": #LOCATION = "R3L13" !CDS_LOCATION = "R3L13" #SEC = "1" !CDS_SEC = "1";
"A":   PN = "1"  !CDS_PN = "1";
"B":   PN = "2"  !CDS_PN = "2";
BODY = "RES","I48": #LOCATION = "R7A17" !CDS_LOCATION = "R7A17" #SEC = "1" !CDS_SEC = "1";
"A":   PN = "1"  !CDS_PN = "1";
"B":   PN = "2"  !CDS_PN = "2";
BODY = "RES","I50": #LOCATION = "R3L10" !CDS_LOCATION = "R3L10" &SEC = "1" #&CDS_SEC = "1";
"A":   PN = "1"  !CDS_PN = "1";
"B":   PN = "2"  !CDS_PN = "2";
BODY = "RES","I53": #LOCATION = "R3L12" !CDS_LOCATION = "R3L12" #SEC = "1" !CDS_SEC = "1";
"A":   PN = "1"  !CDS_PN = "1";
"B":   PN = "2"  !CDS_PN = "2";
BODY = "RES","I54": #LOCATION = "R7A16" !CDS_LOCATION = "R7A16" #SEC = "1" !CDS_SEC = "1";
"A":   PN = "1"  !CDS_PN = "1";
"B":   PN = "2"  !CDS_PN = "2";
BODY = "CAP","I55": #LOCATION = "C7A35" !CDS_LOCATION = "C7A35" #SEC = "1" !CDS_SEC = "1";
"A":   PN = "1"  !CDS_PN = "1";
"B":   PN = "2"  !CDS_PN = "2";
BODY = "RES","I57": #LOCATION = "R3L9" !CDS_LOCATION = "R3L9" &SEC = "1" #&CDS_SEC = "1";
"A":   PN = "1"  !CDS_PN = "1";
"B":   PN = "2"  !CDS_PN = "2";
BODY = "RES","I59": #LOCATION = "R3M6" !CDS_LOCATION = "R3M6" &SEC = "1" #&CDS_SEC = "1";
"A":   PN = "1"  !CDS_PN = "1";
"B":   PN = "2"  !CDS_PN = "2";
BODY = "RES","I60": #LOCATION = "R7A7" !CDS_LOCATION = "R7A7" #SEC = "1" !CDS_SEC = "1";
"A":   PN = "1"  !CDS_PN = "1";
"B":   PN = "2"  !CDS_PN = "2";
BODY = "CAP","I61": #LOCATION = "C7A28" !CDS_LOCATION = "C7A28" #SEC = "1" !CDS_SEC = "1";
"A":   PN = "1"  !CDS_PN = "1";
"B":   PN = "2"  !CDS_PN = "2";
BODY = "PXM1310B","I75": #LOCATION = "EU7A5" !CDS_LOCATION = "EU7A5" #SEC = "1" !CDS_SEC = "1";
"AIREF1":   PN = "21"  !CDS_PN = "21";
"AIREF2":   PN = "23"  !CDS_PN = "23";
"AIREF3":   PN = "25"  !CDS_PN = "25";
"AISEN1":   PN = "22"  !CDS_PN = "22";
"AISEN2":   PN = "24"  !CDS_PN = "24";
"AISEN3":   PN = "26"  !CDS_PN = "26";
"APWM1":   PN = "5"  !CDS_PN = "5";
"APWM2":   PN = "4"  !CDS_PN = "4";
"APWM3":   PN = "3"  !CDS_PN = "3";
"ATSEN":   PN = "35"  !CDS_PN = "35";
"AVREF":   PN = "20"  !CDS_PN = "20";
"AVREN":   PN = "10"  !CDS_PN = "10";
"AVRRDY":   PN = "9"  !CDS_PN = "9";
"AVSEN":   PN = "19"  !CDS_PN = "19";
"BIREF1":   PN = "31"  !CDS_PN = "31";
"BISEN1":   PN = "32"  !CDS_PN = "32";
"BPWM1":   PN = "1"  !CDS_PN = "1";
"BTSEN":   PN = "34"  !CDS_PN = "34";
"BVREF":   PN = "30"  !CDS_PN = "30";
"BVSEN":   PN = "29"  !CDS_PN = "29";
"DNC<0>":   PN = "2"  !CDS_PN = "2";
"DNC<1>":   PN = "28"  !CDS_PN = "28";
"GND":   PN = "27"  !CDS_PN = "27";
"IINSEN":   PN = "38"  !CDS_PN = "38";
"MP0":   PN = "13"  !CDS_PN = "13";
"MP1":   PN = "14"  !CDS_PN = "14";
"MP2":   PN = "18"  !CDS_PN = "18";
"PINALRT_N":   PN = "12"  !CDS_PN = "12";
"RESET_N":   PN = "8"  !CDS_PN = "8";
"SCL":   PN = "7"  !CDS_PN = "7";
"SDA":   PN = "6"  !CDS_PN = "6";
"THPAD":   PN = "41"  !CDS_PN = "41";
"VALRT_N":   PN = "17"  !CDS_PN = "17";
"VCLK":   PN = "15"  !CDS_PN = "15";
"VD12":   PN = "40"  !CDS_PN = "40";
"VDD":   PN = "39"  !CDS_PN = "39";
"VDIO":   PN = "16"  !CDS_PN = "16";
"VINSEN":   PN = "37"  !CDS_PN = "37";
"VRHOT_N":   PN = "11"  !CDS_PN = "11";
"XADDR1":   PN = "36"  !CDS_PN = "36";
"XADDR2":   PN = "33"  !CDS_PN = "33";
BODY = "CAP_A","I77": #LOCATION = "C3L31" !CDS_LOCATION = "C3L31" #SEC = "1" !CDS_SEC = "1";
"A":   PN = "1"  !CDS_PN = "1";
"B":   PN = "2"  !CDS_PN = "2";
DRAWING = "@baseboard_fab2_lib.baseboard_fab2(sch_1):page220";
BODY = "RES","I58": #LOCATION = "R4L4" !CDS_LOCATION = "R4L4" &SEC = "1" #&CDS_SEC = "1";
"A":   PN = "1"  !CDS_PN = "1";
"B":   PN = "2"  !CDS_PN = "2";
BODY = "RES","I74": #LOCATION = "R4L2" !CDS_LOCATION = "R4L2" #SEC = "1" !CDS_SEC = "1";
"A":   PN = "1"  !CDS_PN = "1";
"B":   PN = "2"  !CDS_PN = "2";
BODY = "CAPP","I75": #LOCATION = "C3L6" !CDS_LOCATION = "C3L6" #SEC = "1" !CDS_SEC = "1";
"A":   PN = "1"  !CDS_PN = "1";
"B":   PN = "2"  !CDS_PN = "2";
BODY = "CAPP","I76": #LOCATION = "C3L14" !CDS_LOCATION = "C3L14" #SEC = "1" !CDS_SEC = "1";
"A":   PN = "1"  !CDS_PN = "1";
"B":   PN = "2"  !CDS_PN = "2";
BODY = "CAPP","I77": #LOCATION = "C6A5" !CDS_LOCATION = "C6A5" #SEC = "1" !CDS_SEC = "1";
"A":   PN = "1"  !CDS_PN = "1";
"B":   PN = "2"  !CDS_PN = "2";
BODY = "CAPP","I78": #LOCATION = "C4L5" !CDS_LOCATION = "C4L5" #SEC = "1" !CDS_SEC = "1";
"A":   PN = "1"  !CDS_PN = "1";
"B":   PN = "2"  !CDS_PN = "2";
BODY = "CAP","I82": #LOCATION = "C5M8" !CDS_LOCATION = "C5M8" #SEC = "1" !CDS_SEC = "1";
"A":   PN = "1"  !CDS_PN = "1";
"B":   PN = "2"  !CDS_PN = "2";
BODY = "CAP","I83": #LOCATION = "C5L14" !CDS_LOCATION = "C5L14" #SEC = "1" !CDS_SEC = "1";
"A":   PN = "1"  !CDS_PN = "1";
"B":   PN = "2"  !CDS_PN = "2";
BODY = "CAP","I88": #LOCATION = "C5M12" !CDS_LOCATION = "C5M12" #SEC = "1" !CDS_SEC = "1";
"A":   PN = "1"  !CDS_PN = "1";
"B":   PN = "2"  !CDS_PN = "2";
BODY = "CAP","I89": #LOCATION = "C5L3" !CDS_LOCATION = "C5L3" #SEC = "1" !CDS_SEC = "1";
"A":   PN = "1"  !CDS_PN = "1";
"B":   PN = "2"  !CDS_PN = "2";
BODY = "CAP","I90": #LOCATION = "C5L2" !CDS_LOCATION = "C5L2" #SEC = "1" !CDS_SEC = "1";
"A":   PN = "1"  !CDS_PN = "1";
"B":   PN = "2"  !CDS_PN = "2";
BODY = "CAP","I91": #LOCATION = "C5L1" !CDS_LOCATION = "C5L1" #SEC = "1" !CDS_SEC = "1";
"A":   PN = "1"  !CDS_PN = "1";
"B":   PN = "2"  !CDS_PN = "2";
BODY = "CAP","I92": #LOCATION = "C5A20" !CDS_LOCATION = "C5A20" #SEC = "1" !CDS_SEC = "1";
"A":   PN = "1"  !CDS_PN = "1";
"B":   PN = "2"  !CDS_PN = "2";
BODY = "CAP","I110": #LOCATION = "C5A10" !CDS_LOCATION = "C5A10" #SEC = "1" !CDS_SEC = "1";
"A":   PN = "1"  !CDS_PN = "1";
"B":   PN = "2"  !CDS_PN = "2";
BODY = "INDUCTOR","I124": #LOCATION = "L7A5" !CDS_LOCATION = "L7A5" #SEC = "1" !CDS_SEC = "1";
"INA":   PN = "1"  !CDS_PN = "1";
"INB":   PN = "2"  !CDS_PN = "2";
BODY = "CAPP","I175": #LOCATION = "C7A19" !CDS_LOCATION = "C7A19" #SEC = "1" !CDS_SEC = "1";
"A":   PN = "1"  !CDS_PN = "1";
"B":   PN = "2"  !CDS_PN = "2";
BODY = "CAP","I177": #LOCATION = "C5P2" !CDS_LOCATION = "C5P2" #SEC = "1" !CDS_SEC = "1";
"A":   PN = "1"  !CDS_PN = "1";
"B":   PN = "2"  !CDS_PN = "2";
BODY = "CAP","I179": #LOCATION = "C5P1" !CDS_LOCATION = "C5P1" #SEC = "1" !CDS_SEC = "1";
"A":   PN = "1"  !CDS_PN = "1";
"B":   PN = "2"  !CDS_PN = "2";
BODY = "CAP","I180": #LOCATION = "C5D9" !CDS_LOCATION = "C5D9" #SEC = "1" !CDS_SEC = "1";
"A":   PN = "1"  !CDS_PN = "1";
"B":   PN = "2"  !CDS_PN = "2";
BODY = "CAP","I182": #LOCATION = "C5D6" !CDS_LOCATION = "C5D6" #SEC = "1" !CDS_SEC = "1";
"A":   PN = "1"  !CDS_PN = "1";
"B":   PN = "2"  !CDS_PN = "2";
BODY = "CAP","I183": #LOCATION = "C5D7" !CDS_LOCATION = "C5D7" #SEC = "1" !CDS_SEC = "1";
"A":   PN = "1"  !CDS_PN = "1";
"B":   PN = "2"  !CDS_PN = "2";
BODY = "CAP","I184": #LOCATION = "C5D8" !CDS_LOCATION = "C5D8" #SEC = "1" !CDS_SEC = "1";
"A":   PN = "1"  !CDS_PN = "1";
"B":   PN = "2"  !CDS_PN = "2";
BODY = "CAP_A","I192": #LOCATION = "C5L15" !CDS_LOCATION = "C5L15" #SEC = "1" !CDS_SEC = "1";
"A":   PN = "1"  !CDS_PN = "1";
"B":   PN = "2"  !CDS_PN = "2";
BODY = "CAP_A","I193": #LOCATION = "C5A5" !CDS_LOCATION = "C5A5" #SEC = "1" !CDS_SEC = "1";
"A":   PN = "1"  !CDS_PN = "1";
"B":   PN = "2"  !CDS_PN = "2";
BODY = "CAP_A","I194": #LOCATION = "C5B1" !CDS_LOCATION = "C5B1" #SEC = "1" !CDS_SEC = "1";
"A":   PN = "1"  !CDS_PN = "1";
"B":   PN = "2"  !CDS_PN = "2";
BODY = "CAP_A","I195": #LOCATION = "C5M9" !CDS_LOCATION = "C5M9" #SEC = "1" !CDS_SEC = "1";
"A":   PN = "1"  !CDS_PN = "1";
"B":   PN = "2"  !CDS_PN = "2";
BODY = "CAP_A","I196": #LOCATION = "C4M5" !CDS_LOCATION = "C4M5" #SEC = "1" !CDS_SEC = "1";
"A":   PN = "1"  !CDS_PN = "1";
"B":   PN = "2"  !CDS_PN = "2";
BODY = "CAP_A","I197": #LOCATION = "C5B2" !CDS_LOCATION = "C5B2" #SEC = "1" !CDS_SEC = "1";
"A":   PN = "1"  !CDS_PN = "1";
"B":   PN = "2"  !CDS_PN = "2";
BODY = "CAP_A","I198": #LOCATION = "C5M10" !CDS_LOCATION = "C5M10" #SEC = "1" !CDS_SEC = "1";
"A":   PN = "1"  !CDS_PN = "1";
"B":   PN = "2"  !CDS_PN = "2";
BODY = "CAP_A","I199": #LOCATION = "C5M3" !CDS_LOCATION = "C5M3" #SEC = "1" !CDS_SEC = "1";
"A":   PN = "1"  !CDS_PN = "1";
"B":   PN = "2"  !CDS_PN = "2";
BODY = "CAP_A","I200": #LOCATION = "C5M11" !CDS_LOCATION = "C5M11" #SEC = "1" !CDS_SEC = "1";
"A":   PN = "1"  !CDS_PN = "1";
"B":   PN = "2"  !CDS_PN = "2";
BODY = "CAP_A","I203": #LOCATION = "C5A19" !CDS_LOCATION = "C5A19" &SEC = "1" #&CDS_SEC = "1";
"A":   PN = "1"  !CDS_PN = "1";
"B":   PN = "2"  !CDS_PN = "2";
BODY = "CAP_A","I204": #LOCATION = "C5A18" !CDS_LOCATION = "C5A18" &SEC = "1" #&CDS_SEC = "1";
"A":   PN = "1"  !CDS_PN = "1";
"B":   PN = "2"  !CDS_PN = "2";
BODY = "CAP_A","I205": #LOCATION = "C5A17" !CDS_LOCATION = "C5A17" &SEC = "1" #&CDS_SEC = "1";
"A":   PN = "1"  !CDS_PN = "1";
"B":   PN = "2"  !CDS_PN = "2";
BODY = "CAP_A","I206": #LOCATION = "C5A4" !CDS_LOCATION = "C5A4" #SEC = "1" !CDS_SEC = "1";
"A":   PN = "1"  !CDS_PN = "1";
"B":   PN = "2"  !CDS_PN = "2";
BODY = "CAP_A","I207": #LOCATION = "C5A16" !CDS_LOCATION = "C5A16" &SEC = "1" #&CDS_SEC = "1";
"A":   PN = "1"  !CDS_PN = "1";
"B":   PN = "2"  !CDS_PN = "2";
BODY = "CAP_A","I208": #LOCATION = "C5A9" !CDS_LOCATION = "C5A9" &SEC = "1" #&CDS_SEC = "1";
"A":   PN = "1"  !CDS_PN = "1";
"B":   PN = "2"  !CDS_PN = "2";
BODY = "CAP_A","I209": #LOCATION = "C5A8" !CDS_LOCATION = "C5A8" &SEC = "1" #&CDS_SEC = "1";
"A":   PN = "1"  !CDS_PN = "1";
"B":   PN = "2"  !CDS_PN = "2";
BODY = "CAP_A","I210": #LOCATION = "C5A3" !CDS_LOCATION = "C5A3" #SEC = "1" !CDS_SEC = "1";
"A":   PN = "1"  !CDS_PN = "1";
"B":   PN = "2"  !CDS_PN = "2";
BODY = "CAP_A","I211": #LOCATION = "C5A7" !CDS_LOCATION = "C5A7" &SEC = "1" #&CDS_SEC = "1";
"A":   PN = "1"  !CDS_PN = "1";
"B":   PN = "2"  !CDS_PN = "2";
BODY = "CAP_A","I212": #LOCATION = "C5A6" !CDS_LOCATION = "C5A6" &SEC = "1" #&CDS_SEC = "1";
"A":   PN = "1"  !CDS_PN = "1";
"B":   PN = "2"  !CDS_PN = "2";
BODY = "CAP_A","I213": #LOCATION = "C5A14" !CDS_LOCATION = "C5A14" &SEC = "1" #&CDS_SEC = "1";
"A":   PN = "1"  !CDS_PN = "1";
"B":   PN = "2"  !CDS_PN = "2";
BODY = "CAP_A","I214": #LOCATION = "C5A2" !CDS_LOCATION = "C5A2" #SEC = "1" !CDS_SEC = "1";
"A":   PN = "1"  !CDS_PN = "1";
"B":   PN = "2"  !CDS_PN = "2";
BODY = "CAP_A","I215": #LOCATION = "C5A13" !CDS_LOCATION = "C5A13" &SEC = "1" #&CDS_SEC = "1";
"A":   PN = "1"  !CDS_PN = "1";
"B":   PN = "2"  !CDS_PN = "2";
BODY = "CAP_A","I216": #LOCATION = "C5A12" !CDS_LOCATION = "C5A12" &SEC = "1" #&CDS_SEC = "1";
"A":   PN = "1"  !CDS_PN = "1";
"B":   PN = "2"  !CDS_PN = "2";
BODY = "CAP_A","I217": #LOCATION = "C5A15" !CDS_LOCATION = "C5A15" &SEC = "1" #&CDS_SEC = "1";
"A":   PN = "1"  !CDS_PN = "1";
"B":   PN = "2"  !CDS_PN = "2";
BODY = "CAP_A","I219": #LOCATION = "C5A1" !CDS_LOCATION = "C5A1" #SEC = "1" !CDS_SEC = "1";
"A":   PN = "1"  !CDS_PN = "1";
"B":   PN = "2"  !CDS_PN = "2";
BODY = "CAP_A","I221": #LOCATION = "C5A11" !CDS_LOCATION = "C5A11" &SEC = "1" #&CDS_SEC = "1";
"A":   PN = "1"  !CDS_PN = "1";
"B":   PN = "2"  !CDS_PN = "2";
BODY = "CAP_A","I222": #LOCATION = "C4M2" !CDS_LOCATION = "C4M2" &SEC = "1" #&CDS_SEC = "1";
"A":   PN = "1"  !CDS_PN = "1";
"B":   PN = "2"  !CDS_PN = "2";
BODY = "CAP_A","I223": #LOCATION = "C5M1" !CDS_LOCATION = "C5M1" &SEC = "1" #&CDS_SEC = "1";
"A":   PN = "1"  !CDS_PN = "1";
"B":   PN = "2"  !CDS_PN = "2";
BODY = "CAP_A","I224": #LOCATION = "C5M2" !CDS_LOCATION = "C5M2" &SEC = "1" #&CDS_SEC = "1";
"A":   PN = "1"  !CDS_PN = "1";
"B":   PN = "2"  !CDS_PN = "2";
BODY = "CAP_A","I225": #LOCATION = "C5M4" !CDS_LOCATION = "C5M4" &SEC = "1" #&CDS_SEC = "1";
"A":   PN = "1"  !CDS_PN = "1";
"B":   PN = "2"  !CDS_PN = "2";
BODY = "CAP_A","I226": #LOCATION = "C5M5" !CDS_LOCATION = "C5M5" &SEC = "1" #&CDS_SEC = "1";
"A":   PN = "1"  !CDS_PN = "1";
"B":   PN = "2"  !CDS_PN = "2";
BODY = "CAP_A","I227": #LOCATION = "C5M6" !CDS_LOCATION = "C5M6" &SEC = "1" #&CDS_SEC = "1";
"A":   PN = "1"  !CDS_PN = "1";
"B":   PN = "2"  !CDS_PN = "2";
BODY = "CAP_A","I228": #LOCATION = "C5M7" !CDS_LOCATION = "C5M7" &SEC = "1" #&CDS_SEC = "1";
"A":   PN = "1"  !CDS_PN = "1";
"B":   PN = "2"  !CDS_PN = "2";
BODY = "CAP_A","I229": #LOCATION = "C5L13" !CDS_LOCATION = "C5L13" &SEC = "1" #&CDS_SEC = "1";
"A":   PN = "1"  !CDS_PN = "1";
"B":   PN = "2"  !CDS_PN = "2";
BODY = "CAP_A","I230": #LOCATION = "C5L12" !CDS_LOCATION = "C5L12" &SEC = "1" #&CDS_SEC = "1";
"A":   PN = "1"  !CDS_PN = "1";
"B":   PN = "2"  !CDS_PN = "2";
BODY = "CAP_A","I231": #LOCATION = "C5L11" !CDS_LOCATION = "C5L11" &SEC = "1" #&CDS_SEC = "1";
"A":   PN = "1"  !CDS_PN = "1";
"B":   PN = "2"  !CDS_PN = "2";
BODY = "CAP_A","I232": #LOCATION = "C5L10" !CDS_LOCATION = "C5L10" &SEC = "1" #&CDS_SEC = "1";
"A":   PN = "1"  !CDS_PN = "1";
"B":   PN = "2"  !CDS_PN = "2";
BODY = "CAP_A","I233": #LOCATION = "C5L9" !CDS_LOCATION = "C5L9" &SEC = "1" #&CDS_SEC = "1";
"A":   PN = "1"  !CDS_PN = "1";
"B":   PN = "2"  !CDS_PN = "2";
BODY = "CAP_A","I234": #LOCATION = "C5L8" !CDS_LOCATION = "C5L8" &SEC = "1" #&CDS_SEC = "1";
"A":   PN = "1"  !CDS_PN = "1";
"B":   PN = "2"  !CDS_PN = "2";
BODY = "CAP_A","I236": #LOCATION = "C5L7" !CDS_LOCATION = "C5L7" &SEC = "1" #&CDS_SEC = "1";
"A":   PN = "1"  !CDS_PN = "1";
"B":   PN = "2"  !CDS_PN = "2";
BODY = "CAP_A","I237": #LOCATION = "C5L6" !CDS_LOCATION = "C5L6" &SEC = "1" #&CDS_SEC = "1";
"A":   PN = "1"  !CDS_PN = "1";
"B":   PN = "2"  !CDS_PN = "2";
BODY = "SHUNT","I239": #LOCATION = "SH4L2" !CDS_LOCATION = "SH4L2" #SEC = "1" !CDS_SEC = "1";
"A":   PN = "1"  !CDS_PN = "1";
"B":   PN = "2"  !CDS_PN = "2";
BODY = "SHUNT","I240": #LOCATION = "SH4L1" !CDS_LOCATION = "SH4L1" #SEC = "1" !CDS_SEC = "1";
"A":   PN = "1"  !CDS_PN = "1";
"B":   PN = "2"  !CDS_PN = "2";
DRAWING = "@baseboard_fab2_lib.baseboard_fab2(sch_1):page221";
BODY = "MIC5166","I1": #LOCATION = "EU4G3" !CDS_LOCATION = "EU4G3" #SEC = "1" !CDS_SEC = "1";
"AGND":   PN = "3"  !CDS_PN = "3";
"BIAS":   PN = "2"  !CDS_PN = "2";
"EN":   PN = "7"  !CDS_PN = "7";
"PG":   PN = "5"  !CDS_PN = "5";
"PGND":   PN = "8"  !CDS_PN = "8";
"SNS":   PN = "6"  !CDS_PN = "6";
"THPAD":   PN = "11"  !CDS_PN = "11";
"VDDQ":   PN = "4"  !CDS_PN = "4";
"VIN":   PN = "10"  !CDS_PN = "10";
"VREF":   PN = "1"  !CDS_PN = "1";
"VTT":   PN = "9"  !CDS_PN = "9";
BODY = "CAP","I15": #LOCATION = "C4G14" !CDS_LOCATION = "C4G14" #SEC = "1" !CDS_SEC = "1";
"A":   PN = "1"  !CDS_PN = "1";
"B":   PN = "2"  !CDS_PN = "2";
BODY = "CAP","I20": #LOCATION = "C4G24" !CDS_LOCATION = "C4G24" #SEC = "1" !CDS_SEC = "1";
"A":   PN = "1"  !CDS_PN = "1";
"B":   PN = "2"  !CDS_PN = "2";
BODY = "CAP","I22": #LOCATION = "C6U16" !CDS_LOCATION = "C6U16" #SEC = "1" !CDS_SEC = "1";
"A":   PN = "1"  !CDS_PN = "1";
"B":   PN = "2"  !CDS_PN = "2";
BODY = "CAP","I24": #LOCATION = "C4G15" !CDS_LOCATION = "C4G15" &SEC = "1" #&CDS_SEC = "1";
"A":   PN = "1"  !CDS_PN = "1";
"B":   PN = "2"  !CDS_PN = "2";
BODY = "CAP","I26": #LOCATION = "C6U15" !CDS_LOCATION = "C6U15" #SEC = "1" !CDS_SEC = "1";
"A":   PN = "1"  !CDS_PN = "1";
"B":   PN = "2"  !CDS_PN = "2";
BODY = "RES","I28": #LOCATION = "R6U4" !CDS_LOCATION = "R6U4" #SEC = "1" !CDS_SEC = "1";
"A":   PN = "1"  !CDS_PN = "1";
"B":   PN = "2"  !CDS_PN = "2";
BODY = "RES","I32": #LOCATION = "R6U5" !CDS_LOCATION = "R6U5" #SEC = "1" !CDS_SEC = "1";
"A":   PN = "1"  !CDS_PN = "1";
"B":   PN = "2"  !CDS_PN = "2";
BODY = "CAP","I34": #LOCATION = "C4G16" !CDS_LOCATION = "C4G16" #SEC = "1" !CDS_SEC = "1";
"A":   PN = "1"  !CDS_PN = "1";
"B":   PN = "2"  !CDS_PN = "2";
BODY = "RES","I37": #LOCATION = "R6U15" !CDS_LOCATION = "R6U15" #SEC = "1" !CDS_SEC = "1";
"A":   PN = "1"  !CDS_PN = "1";
"B":   PN = "2"  !CDS_PN = "2";
BODY = "RES","I38": #LOCATION = "R4G23" !CDS_LOCATION = "R4G23" #SEC = "1" !CDS_SEC = "1";
"A":   PN = "1"  !CDS_PN = "1";
"B":   PN = "2"  !CDS_PN = "2";
BODY = "CAP","I39": #LOCATION = "C4G23" !CDS_LOCATION = "C4G23" #SEC = "1" !CDS_SEC = "1";
"A":   PN = "1"  !CDS_PN = "1";
"B":   PN = "2"  !CDS_PN = "2";
BODY = "RES","I45": #LOCATION = "R4G18" !CDS_LOCATION = "R4G18" #SEC = "1" !CDS_SEC = "1";
"A":   PN = "1"  !CDS_PN = "1";
"B":   PN = "2"  !CDS_PN = "2";
BODY = "CAP","I49": #LOCATION = "C6U12" !CDS_LOCATION = "C6U12" #SEC = "1" !CDS_SEC = "1";
"A":   PN = "1"  !CDS_PN = "1";
"B":   PN = "2"  !CDS_PN = "2";
BODY = "CAP_A","I50": #LOCATION = "C5U12" !CDS_LOCATION = "C5U12" #SEC = "1" !CDS_SEC = "1";
"A":   PN = "1"  !CDS_PN = "1";
"B":   PN = "2"  !CDS_PN = "2";
BODY = "CAP_A","I51": #LOCATION = "C5T3" !CDS_LOCATION = "C5T3" #SEC = "1" !CDS_SEC = "1";
"A":   PN = "1"  !CDS_PN = "1";
"B":   PN = "2"  !CDS_PN = "2";
BODY = "CAP_A","I52": #LOCATION = "C5U16" !CDS_LOCATION = "C5U16" #SEC = "1" !CDS_SEC = "1";
"A":   PN = "1"  !CDS_PN = "1";
"B":   PN = "2"  !CDS_PN = "2";
BODY = "RES","I54": #LOCATION = "R4G19" !CDS_LOCATION = "R4G19" #SEC = "1" !CDS_SEC = "1";
"A":   PN = "1"  !CDS_PN = "1";
"B":   PN = "2"  !CDS_PN = "2";
BODY = "RES","I55": #LOCATION = "R6U16" !CDS_LOCATION = "R6U16" &SEC = "1" #&CDS_SEC = "1";
"A":   PN = "1"  !CDS_PN = "1";
"B":   PN = "2"  !CDS_PN = "2";
BODY = "SHUNT","I56": #LOCATION = "SH5U1" !CDS_LOCATION = "SH5U1" #SEC = "1" !CDS_SEC = "1";
"A":   PN = "1"  !CDS_PN = "1";
"B":   PN = "2"  !CDS_PN = "2";
DRAWING = "@baseboard_fab2_lib.baseboard_fab2(sch_1):page222";
BODY = "CAP","I12": #LOCATION = "C4A12" !CDS_LOCATION = "C4A12" #SEC = "1" !CDS_SEC = "1";
"A":   PN = "1"  !CDS_PN = "1";
"B":   PN = "2"  !CDS_PN = "2";
BODY = "CAP","I16": #LOCATION = "C4A1" !CDS_LOCATION = "C4A1" #SEC = "1" !CDS_SEC = "1";
"A":   PN = "1"  !CDS_PN = "1";
"B":   PN = "2"  !CDS_PN = "2";
BODY = "RES","I19": #LOCATION = "R6L9" !CDS_LOCATION = "R6L9" #SEC = "1" !CDS_SEC = "1";
"A":   PN = "1"  !CDS_PN = "1";
"B":   PN = "2"  !CDS_PN = "2";
BODY = "CAP","I21": #LOCATION = "C4A9" !CDS_LOCATION = "C4A9" #SEC = "1" !CDS_SEC = "1";
"A":   PN = "1"  !CDS_PN = "1";
"B":   PN = "2"  !CDS_PN = "2";
BODY = "CAP","I24": #LOCATION = "C6L3" !CDS_LOCATION = "C6L3" #SEC = "1" !CDS_SEC = "1";
"A":   PN = "1"  !CDS_PN = "1";
"B":   PN = "2"  !CDS_PN = "2";
BODY = "CAP","I26": #LOCATION = "C6L4" !CDS_LOCATION = "C6L4" #SEC = "1" !CDS_SEC = "1";
"A":   PN = "1"  !CDS_PN = "1";
"B":   PN = "2"  !CDS_PN = "2";
BODY = "CAP","I28": #LOCATION = "C4A10" !CDS_LOCATION = "C4A10" #SEC = "1" !CDS_SEC = "1";
"A":   PN = "1"  !CDS_PN = "1";
"B":   PN = "2"  !CDS_PN = "2";
BODY = "RES","I30": #LOCATION = "R6L11" !CDS_LOCATION = "R6L11" #SEC = "1" !CDS_SEC = "1";
"A":   PN = "1"  !CDS_PN = "1";
"B":   PN = "2"  !CDS_PN = "2";
BODY = "MIC5166","I31": #LOCATION = "EU4A1" !CDS_LOCATION = "EU4A1" #SEC = "1" !CDS_SEC = "1";
"AGND":   PN = "3"  !CDS_PN = "3";
"BIAS":   PN = "2"  !CDS_PN = "2";
"EN":   PN = "7"  !CDS_PN = "7";
"PG":   PN = "5"  !CDS_PN = "5";
"PGND":   PN = "8"  !CDS_PN = "8";
"SNS":   PN = "6"  !CDS_PN = "6";
"THPAD":   PN = "11"  !CDS_PN = "11";
"VDDQ":   PN = "4"  !CDS_PN = "4";
"VIN":   PN = "10"  !CDS_PN = "10";
"VREF":   PN = "1"  !CDS_PN = "1";
"VTT":   PN = "9"  !CDS_PN = "9";
BODY = "RES","I34": #LOCATION = "R6L10" !CDS_LOCATION = "R6L10" #SEC = "1" !CDS_SEC = "1";
"A":   PN = "1"  !CDS_PN = "1";
"B":   PN = "2"  !CDS_PN = "2";
BODY = "RES","I37": #LOCATION = "R6L4" !CDS_LOCATION = "R6L4" #SEC = "1" !CDS_SEC = "1";
"A":   PN = "1"  !CDS_PN = "1";
"B":   PN = "2"  !CDS_PN = "2";
BODY = "RES","I38": #LOCATION = "R4A2" !CDS_LOCATION = "R4A2" #SEC = "1" !CDS_SEC = "1";
"A":   PN = "1"  !CDS_PN = "1";
"B":   PN = "2"  !CDS_PN = "2";
BODY = "CAP","I40": #LOCATION = "C4A2" !CDS_LOCATION = "C4A2" #SEC = "1" !CDS_SEC = "1";
"A":   PN = "1"  !CDS_PN = "1";
"B":   PN = "2"  !CDS_PN = "2";
BODY = "CAP","I46": #LOCATION = "C4A11" !CDS_LOCATION = "C4A11" #SEC = "1" !CDS_SEC = "1";
"A":   PN = "1"  !CDS_PN = "1";
"B":   PN = "2"  !CDS_PN = "2";
BODY = "CAP_A","I47": #LOCATION = "C5L4" !CDS_LOCATION = "C5L4" #SEC = "1" !CDS_SEC = "1";
"A":   PN = "1"  !CDS_PN = "1";
"B":   PN = "2"  !CDS_PN = "2";
BODY = "CAP_A","I48": #LOCATION = "C5M13" !CDS_LOCATION = "C5M13" #SEC = "1" !CDS_SEC = "1";
"A":   PN = "1"  !CDS_PN = "1";
"B":   PN = "2"  !CDS_PN = "2";
BODY = "CAP_A","I49": #LOCATION = "C5L5" !CDS_LOCATION = "C5L5" #SEC = "1" !CDS_SEC = "1";
"A":   PN = "1"  !CDS_PN = "1";
"B":   PN = "2"  !CDS_PN = "2";
BODY = "RES","I51": #LOCATION = "R4A6" !CDS_LOCATION = "R4A6" #SEC = "1" !CDS_SEC = "1";
"A":   PN = "1"  !CDS_PN = "1";
"B":   PN = "2"  !CDS_PN = "2";
BODY = "RES","I52": #LOCATION = "R4A1" !CDS_LOCATION = "R4A1" &SEC = "1" #&CDS_SEC = "1";
"A":   PN = "1"  !CDS_PN = "1";
"B":   PN = "2"  !CDS_PN = "2";
BODY = "SHUNT","I53": #LOCATION = "SH5L1" !CDS_LOCATION = "SH5L1" #SEC = "1" !CDS_SEC = "1";
"A":   PN = "1"  !CDS_PN = "1";
"B":   PN = "2"  !CDS_PN = "2";
DRAWING = "@baseboard_fab2_lib.baseboard_fab2(sch_1):page223";
BODY = "RES","I8": #LOCATION = "R9U3" !CDS_LOCATION = "R9U3" #SEC = "1" !CDS_SEC = "1";
"A":   PN = "1"  !CDS_PN = "1";
"B":   PN = "2"  !CDS_PN = "2";
BODY = "RES","I13": #LOCATION = "R1G6" !CDS_LOCATION = "R1G6" #SEC = "1" !CDS_SEC = "1";
"A":   PN = "1"  !CDS_PN = "1";
"B":   PN = "2"  !CDS_PN = "2";
BODY = "RES","I14": #LOCATION = "R1G12" !CDS_LOCATION = "R1G12" &SEC = "1" #&CDS_SEC = "1";
"A":   PN = "1"  !CDS_PN = "1";
"B":   PN = "2"  !CDS_PN = "2";
BODY = "RES","I16": #LOCATION = "R1G9" !CDS_LOCATION = "R1G9" #SEC = "1" !CDS_SEC = "1";
"A":   PN = "1"  !CDS_PN = "1";
"B":   PN = "2"  !CDS_PN = "2";
BODY = "RES","I17": #LOCATION = "R1G16" !CDS_LOCATION = "R1G16" #SEC = "1" !CDS_SEC = "1";
"A":   PN = "1"  !CDS_PN = "1";
"B":   PN = "2"  !CDS_PN = "2";
BODY = "RES","I21": #LOCATION = "R1G19" !CDS_LOCATION = "R1G19" &SEC = "1" #&CDS_SEC = "1";
"A":   PN = "1"  !CDS_PN = "1";
"B":   PN = "2"  !CDS_PN = "2";
BODY = "RES","I22": #LOCATION = "R1G21" !CDS_LOCATION = "R1G21" &SEC = "1" #&CDS_SEC = "1";
"A":   PN = "1"  !CDS_PN = "1";
"B":   PN = "2"  !CDS_PN = "2";
BODY = "RES","I23": #LOCATION = "R1G10" !CDS_LOCATION = "R1G10" #SEC = "1" !CDS_SEC = "1";
"A":   PN = "1"  !CDS_PN = "1";
"B":   PN = "2"  !CDS_PN = "2";
BODY = "CAP_A","I25": #LOCATION = "C1G27" !CDS_LOCATION = "C1G27" &SEC = "1" #&CDS_SEC = "1";
"A":   PN = "1"  !CDS_PN = "1";
"B":   PN = "2"  !CDS_PN = "2";
BODY = "CAP_A","I27": #LOCATION = "C1G25" !CDS_LOCATION = "C1G25" #SEC = "1" !CDS_SEC = "1";
"A":   PN = "1"  !CDS_PN = "1";
"B":   PN = "2"  !CDS_PN = "2";
BODY = "RES","I30": #LOCATION = "R9U10" !CDS_LOCATION = "R9U10" #SEC = "1" !CDS_SEC = "1";
"A":   PN = "1"  !CDS_PN = "1";
"B":   PN = "2"  !CDS_PN = "2";
BODY = "RES","I32": #LOCATION = "R1G5" !CDS_LOCATION = "R1G5" #SEC = "1" !CDS_SEC = "1";
"A":   PN = "1"  !CDS_PN = "1";
"B":   PN = "2"  !CDS_PN = "2";
BODY = "CAP","I36": #LOCATION = "C1G24" !CDS_LOCATION = "C1G24" #SEC = "1" !CDS_SEC = "1";
"A":   PN = "1"  !CDS_PN = "1";
"B":   PN = "2"  !CDS_PN = "2";
BODY = "CAP","I39": #LOCATION = "C1G16" !CDS_LOCATION = "C1G16" #SEC = "1" !CDS_SEC = "1";
"A":   PN = "1"  !CDS_PN = "1";
"B":   PN = "2"  !CDS_PN = "2";
BODY = "CAP_A","I41": #LOCATION = "C1G23" !CDS_LOCATION = "C1G23" &SEC = "1" #&CDS_SEC = "1";
"A":   PN = "1"  !CDS_PN = "1";
"B":   PN = "2"  !CDS_PN = "2";
BODY = "CAP_A","I44": #LOCATION = "C1G22" !CDS_LOCATION = "C1G22" #SEC = "1" !CDS_SEC = "1";
"A":   PN = "1"  !CDS_PN = "1";
"B":   PN = "2"  !CDS_PN = "2";
BODY = "RES","I50": #LOCATION = "R9U4" !CDS_LOCATION = "R9U4" #SEC = "1" !CDS_SEC = "1";
"A":   PN = "1"  !CDS_PN = "1";
"B":   PN = "2"  !CDS_PN = "2";
BODY = "RES","I53": #LOCATION = "R1G7" !CDS_LOCATION = "R1G7" #SEC = "1" !CDS_SEC = "1";
"A":   PN = "1"  !CDS_PN = "1";
"B":   PN = "2"  !CDS_PN = "2";
BODY = "RES","I57": #LOCATION = "R9U11" !CDS_LOCATION = "R9U11" #SEC = "1" !CDS_SEC = "1";
"A":   PN = "1"  !CDS_PN = "1";
"B":   PN = "2"  !CDS_PN = "2";
BODY = "RES","I58": #LOCATION = "R1G24" !CDS_LOCATION = "R1G24" #SEC = "1" !CDS_SEC = "1";
"A":   PN = "1"  !CDS_PN = "1";
"B":   PN = "2"  !CDS_PN = "2";
BODY = "CAP","I59": #LOCATION = "C1G26" !CDS_LOCATION = "C1G26" #SEC = "1" !CDS_SEC = "1";
"A":   PN = "1"  !CDS_PN = "1";
"B":   PN = "2"  !CDS_PN = "2";
BODY = "RES","I77": #LOCATION = "R1G23" !CDS_LOCATION = "R1G23" #SEC = "1" !CDS_SEC = "1";
"A":   PN = "1"  !CDS_PN = "1";
"B":   PN = "2"  !CDS_PN = "2";
BODY = "RES","I78": #LOCATION = "R1G22" !CDS_LOCATION = "R1G22" #SEC = "1" !CDS_SEC = "1";
"A":   PN = "1"  !CDS_PN = "1";
"B":   PN = "2"  !CDS_PN = "2";
BODY = "RES","I79": #LOCATION = "R1G11" !CDS_LOCATION = "R1G11" #SEC = "1" !CDS_SEC = "1";
"A":   PN = "1"  !CDS_PN = "1";
"B":   PN = "2"  !CDS_PN = "2";
BODY = "CAP","I80": #LOCATION = "C1G21" !CDS_LOCATION = "C1G21" #SEC = "1" !CDS_SEC = "1";
"A":   PN = "1"  !CDS_PN = "1";
"B":   PN = "2"  !CDS_PN = "2";
BODY = "RES","I82": #LOCATION = "R1G8" !CDS_LOCATION = "R1G8" #SEC = "1" !CDS_SEC = "1";
"A":   PN = "1"  !CDS_PN = "1";
"B":   PN = "2"  !CDS_PN = "2";
BODY = "RES","I84": #LOCATION = "R9U7" !CDS_LOCATION = "R9U7" &SEC = "1" #&CDS_SEC = "1";
"A":   PN = "1"  !CDS_PN = "1";
"B":   PN = "2"  !CDS_PN = "2";
BODY = "RES","I85": #LOCATION = "R9U8" !CDS_LOCATION = "R9U8" &SEC = "1" #&CDS_SEC = "1";
"A":   PN = "1"  !CDS_PN = "1";
"B":   PN = "2"  !CDS_PN = "2";
BODY = "RES","I87": #LOCATION = "R1G28" !CDS_LOCATION = "R1G28" &SEC = "1" #&CDS_SEC = "1";
"A":   PN = "1"  !CDS_PN = "1";
"B":   PN = "2"  !CDS_PN = "2";
BODY = "RES","I88": #LOCATION = "R1G27" !CDS_LOCATION = "R1G27" &SEC = "1" #&CDS_SEC = "1";
"A":   PN = "1"  !CDS_PN = "1";
"B":   PN = "2"  !CDS_PN = "2";
BODY = "PXM1310B","I90": #LOCATION = "EU1G2" !CDS_LOCATION = "EU1G2" #SEC = "1" !CDS_SEC = "1";
"AIREF1":   PN = "21"  !CDS_PN = "21";
"AIREF2":   PN = "23"  !CDS_PN = "23";
"AIREF3":   PN = "25"  !CDS_PN = "25";
"AISEN1":   PN = "22"  !CDS_PN = "22";
"AISEN2":   PN = "24"  !CDS_PN = "24";
"AISEN3":   PN = "26"  !CDS_PN = "26";
"APWM1":   PN = "5"  !CDS_PN = "5";
"APWM2":   PN = "4"  !CDS_PN = "4";
"APWM3":   PN = "3"  !CDS_PN = "3";
"ATSEN":   PN = "35"  !CDS_PN = "35";
"AVREF":   PN = "20"  !CDS_PN = "20";
"AVREN":   PN = "10"  !CDS_PN = "10";
"AVRRDY":   PN = "9"  !CDS_PN = "9";
"AVSEN":   PN = "19"  !CDS_PN = "19";
"BIREF1":   PN = "31"  !CDS_PN = "31";
"BISEN1":   PN = "32"  !CDS_PN = "32";
"BPWM1":   PN = "1"  !CDS_PN = "1";
"BTSEN":   PN = "34"  !CDS_PN = "34";
"BVREF":   PN = "30"  !CDS_PN = "30";
"BVSEN":   PN = "29"  !CDS_PN = "29";
"DNC<0>":   PN = "2"  !CDS_PN = "2";
"DNC<1>":   PN = "28"  !CDS_PN = "28";
"GND":   PN = "27"  !CDS_PN = "27";
"IINSEN":   PN = "38"  !CDS_PN = "38";
"MP0":   PN = "13"  !CDS_PN = "13";
"MP1":   PN = "14"  !CDS_PN = "14";
"MP2":   PN = "18"  !CDS_PN = "18";
"PINALRT_N":   PN = "12"  !CDS_PN = "12";
"RESET_N":   PN = "8"  !CDS_PN = "8";
"SCL":   PN = "7"  !CDS_PN = "7";
"SDA":   PN = "6"  !CDS_PN = "6";
"THPAD":   PN = "41"  !CDS_PN = "41";
"VALRT_N":   PN = "17"  !CDS_PN = "17";
"VCLK":   PN = "15"  !CDS_PN = "15";
"VD12":   PN = "40"  !CDS_PN = "40";
"VDD":   PN = "39"  !CDS_PN = "39";
"VDIO":   PN = "16"  !CDS_PN = "16";
"VINSEN":   PN = "37"  !CDS_PN = "37";
"VRHOT_N":   PN = "11"  !CDS_PN = "11";
"XADDR1":   PN = "36"  !CDS_PN = "36";
"XADDR2":   PN = "33"  !CDS_PN = "33";
BODY = "CAP_A","I92": #LOCATION = "C9U12" !CDS_LOCATION = "C9U12" #SEC = "1" !CDS_SEC = "1";
"A":   PN = "1"  !CDS_PN = "1";
"B":   PN = "2"  !CDS_PN = "2";
DRAWING = "@baseboard_fab2_lib.baseboard_fab2(sch_1):page225";
BODY = "RES","I58": #LOCATION = "R1G20" !CDS_LOCATION = "R1G20" &SEC = "1" #&CDS_SEC = "1";
"A":   PN = "1"  !CDS_PN = "1";
"B":   PN = "2"  !CDS_PN = "2";
BODY = "RES","I74": #LOCATION = "R7U2" !CDS_LOCATION = "R7U2" #SEC = "1" !CDS_SEC = "1";
"A":   PN = "1"  !CDS_PN = "1";
"B":   PN = "2"  !CDS_PN = "2";
BODY = "CAPP","I75": #LOCATION = "C9T5" !CDS_LOCATION = "C9T5" #SEC = "1" !CDS_SEC = "1";
"A":   PN = "1"  !CDS_PN = "1";
"B":   PN = "2"  !CDS_PN = "2";
BODY = "CAPP","I76": #LOCATION = "C9U2" !CDS_LOCATION = "C9U2" #SEC = "1" !CDS_SEC = "1";
"A":   PN = "1"  !CDS_PN = "1";
"B":   PN = "2"  !CDS_PN = "2";
BODY = "CAPP","I77": #LOCATION = "C9U9" !CDS_LOCATION = "C9U9" #SEC = "1" !CDS_SEC = "1";
"A":   PN = "1"  !CDS_PN = "1";
"B":   PN = "2"  !CDS_PN = "2";
BODY = "CAPP","I78": #LOCATION = "C9U5" !CDS_LOCATION = "C9U5" #SEC = "1" !CDS_SEC = "1";
"A":   PN = "1"  !CDS_PN = "1";
"B":   PN = "2"  !CDS_PN = "2";
BODY = "CAP","I82": #LOCATION = "C8U1" !CDS_LOCATION = "C8U1" #SEC = "1" !CDS_SEC = "1";
"A":   PN = "1"  !CDS_PN = "1";
"B":   PN = "2"  !CDS_PN = "2";
BODY = "CAP","I83": #LOCATION = "C8U8" !CDS_LOCATION = "C8U8" #SEC = "1" !CDS_SEC = "1";
"A":   PN = "1"  !CDS_PN = "1";
"B":   PN = "2"  !CDS_PN = "2";
BODY = "CAP","I88": #LOCATION = "C8U12" !CDS_LOCATION = "C8U12" #SEC = "1" !CDS_SEC = "1";
"A":   PN = "1"  !CDS_PN = "1";
"B":   PN = "2"  !CDS_PN = "2";
BODY = "CAP","I89": #LOCATION = "C8U11" !CDS_LOCATION = "C8U11" #SEC = "1" !CDS_SEC = "1";
"A":   PN = "1"  !CDS_PN = "1";
"B":   PN = "2"  !CDS_PN = "2";
BODY = "CAP","I90": #LOCATION = "C7T1" !CDS_LOCATION = "C7T1" #SEC = "1" !CDS_SEC = "1";
"A":   PN = "1"  !CDS_PN = "1";
"B":   PN = "2"  !CDS_PN = "2";
BODY = "CAP","I91": #LOCATION = "C7U7" !CDS_LOCATION = "C7U7" #SEC = "1" !CDS_SEC = "1";
"A":   PN = "1"  !CDS_PN = "1";
"B":   PN = "2"  !CDS_PN = "2";
BODY = "CAP","I92": #LOCATION = "C2G7" !CDS_LOCATION = "C2G7" #SEC = "1" !CDS_SEC = "1";
"A":   PN = "1"  !CDS_PN = "1";
"B":   PN = "2"  !CDS_PN = "2";
BODY = "CAP","I110": #LOCATION = "C2G16" !CDS_LOCATION = "C2G16" #SEC = "1" !CDS_SEC = "1";
"A":   PN = "1"  !CDS_PN = "1";
"B":   PN = "2"  !CDS_PN = "2";
BODY = "INDUCTOR","I124": #LOCATION = "L1F1" !CDS_LOCATION = "L1F1" #SEC = "1" !CDS_SEC = "1";
"INA":   PN = "1"  !CDS_PN = "1";
"INB":   PN = "2"  !CDS_PN = "2";
BODY = "CAP","I178": #LOCATION = "C8P31" !CDS_LOCATION = "C8P31" #SEC = "1" !CDS_SEC = "1";
"A":   PN = "1"  !CDS_PN = "1";
"B":   PN = "2"  !CDS_PN = "2";
BODY = "CAP","I179": #LOCATION = "C2D43" !CDS_LOCATION = "C2D43" #SEC = "1" !CDS_SEC = "1";
"A":   PN = "1"  !CDS_PN = "1";
"B":   PN = "2"  !CDS_PN = "2";
BODY = "CAP","I180": #LOCATION = "C2D41" !CDS_LOCATION = "C2D41" #SEC = "1" !CDS_SEC = "1";
"A":   PN = "1"  !CDS_PN = "1";
"B":   PN = "2"  !CDS_PN = "2";
BODY = "CAP","I181": #LOCATION = "C2D44" !CDS_LOCATION = "C2D44" #SEC = "1" !CDS_SEC = "1";
"A":   PN = "1"  !CDS_PN = "1";
"B":   PN = "2"  !CDS_PN = "2";
BODY = "CAP","I183": #LOCATION = "C2D42" !CDS_LOCATION = "C2D42" #SEC = "1" !CDS_SEC = "1";
"A":   PN = "1"  !CDS_PN = "1";
"B":   PN = "2"  !CDS_PN = "2";
BODY = "CAP","I184": #LOCATION = "C8P30" !CDS_LOCATION = "C8P30" #SEC = "1" !CDS_SEC = "1";
"A":   PN = "1"  !CDS_PN = "1";
"B":   PN = "2"  !CDS_PN = "2";
BODY = "CAP","I192": #LOCATION = "C1G15" !CDS_LOCATION = "C1G15" #SEC = "1" !CDS_SEC = "1";
"A":   PN = "1"  !CDS_PN = "1";
"B":   PN = "2"  !CDS_PN = "2";
BODY = "CAP","I193": #LOCATION = "C1G12" !CDS_LOCATION = "C1G12" #SEC = "1" !CDS_SEC = "1";
"A":   PN = "1"  !CDS_PN = "1";
"B":   PN = "2"  !CDS_PN = "2";
BODY = "CAP","I194": #LOCATION = "C1G2" !CDS_LOCATION = "C1G2" #SEC = "1" !CDS_SEC = "1";
"A":   PN = "1"  !CDS_PN = "1";
"B":   PN = "2"  !CDS_PN = "2";
BODY = "CAP","I195": #LOCATION = "C1G7" !CDS_LOCATION = "C1G7" #SEC = "1" !CDS_SEC = "1";
"A":   PN = "1"  !CDS_PN = "1";
"B":   PN = "2"  !CDS_PN = "2";
BODY = "CAP_A","I196": #LOCATION = "C8T4" !CDS_LOCATION = "C8T4" #SEC = "1" !CDS_SEC = "1";
"A":   PN = "1"  !CDS_PN = "1";
"B":   PN = "2"  !CDS_PN = "2";
BODY = "CAP_A","I197": #LOCATION = "C2G8" !CDS_LOCATION = "C2G8" #SEC = "1" !CDS_SEC = "1";
"A":   PN = "1"  !CDS_PN = "1";
"B":   PN = "2"  !CDS_PN = "2";
BODY = "CAP_A","I198": #LOCATION = "C8T2" !CDS_LOCATION = "C8T2" #SEC = "1" !CDS_SEC = "1";
"A":   PN = "1"  !CDS_PN = "1";
"B":   PN = "2"  !CDS_PN = "2";
BODY = "CAP_A","I199": #LOCATION = "C8U13" !CDS_LOCATION = "C8U13" #SEC = "1" !CDS_SEC = "1";
"A":   PN = "1"  !CDS_PN = "1";
"B":   PN = "2"  !CDS_PN = "2";
BODY = "CAP_A","I200": #LOCATION = "C2G15" !CDS_LOCATION = "C2G15" #SEC = "1" !CDS_SEC = "1";
"A":   PN = "1"  !CDS_PN = "1";
"B":   PN = "2"  !CDS_PN = "2";
BODY = "CAP_A","I201": #LOCATION = "C2F1" !CDS_LOCATION = "C2F1" #SEC = "1" !CDS_SEC = "1";
"A":   PN = "1"  !CDS_PN = "1";
"B":   PN = "2"  !CDS_PN = "2";
BODY = "CAP_A","I202": #LOCATION = "C8T1" !CDS_LOCATION = "C8T1" #SEC = "1" !CDS_SEC = "1";
"A":   PN = "1"  !CDS_PN = "1";
"B":   PN = "2"  !CDS_PN = "2";
BODY = "CAP_A","I203": #LOCATION = "C8U9" !CDS_LOCATION = "C8U9" #SEC = "1" !CDS_SEC = "1";
"A":   PN = "1"  !CDS_PN = "1";
"B":   PN = "2"  !CDS_PN = "2";
BODY = "CAP_A","I204": #LOCATION = "C8T11" !CDS_LOCATION = "C8T11" #SEC = "1" !CDS_SEC = "1";
"A":   PN = "1"  !CDS_PN = "1";
"B":   PN = "2"  !CDS_PN = "2";
BODY = "CAP_A","I207": #LOCATION = "C3G6" !CDS_LOCATION = "C3G6" #SEC = "1" !CDS_SEC = "1";
"A":   PN = "1"  !CDS_PN = "1";
"B":   PN = "2"  !CDS_PN = "2";
BODY = "CAP_A","I208": #LOCATION = "C3G5" !CDS_LOCATION = "C3G5" #SEC = "1" !CDS_SEC = "1";
"A":   PN = "1"  !CDS_PN = "1";
"B":   PN = "2"  !CDS_PN = "2";
BODY = "CAP_A","I209": #LOCATION = "C2G14" !CDS_LOCATION = "C2G14" #SEC = "1" !CDS_SEC = "1";
"A":   PN = "1"  !CDS_PN = "1";
"B":   PN = "2"  !CDS_PN = "2";
BODY = "CAP_A","I210": #LOCATION = "C2G13" !CDS_LOCATION = "C2G13" #SEC = "1" !CDS_SEC = "1";
"A":   PN = "1"  !CDS_PN = "1";
"B":   PN = "2"  !CDS_PN = "2";
BODY = "CAP_A","I211": #LOCATION = "C3G2" !CDS_LOCATION = "C3G2" #SEC = "1" !CDS_SEC = "1";
"A":   PN = "1"  !CDS_PN = "1";
"B":   PN = "2"  !CDS_PN = "2";
BODY = "CAP_A","I212": #LOCATION = "C3G1" !CDS_LOCATION = "C3G1" #SEC = "1" !CDS_SEC = "1";
"A":   PN = "1"  !CDS_PN = "1";
"B":   PN = "2"  !CDS_PN = "2";
BODY = "CAP_A","I213": #LOCATION = "C2G6" !CDS_LOCATION = "C2G6" #SEC = "1" !CDS_SEC = "1";
"A":   PN = "1"  !CDS_PN = "1";
"B":   PN = "2"  !CDS_PN = "2";
BODY = "CAP_A","I214": #LOCATION = "C2G5" !CDS_LOCATION = "C2G5" #SEC = "1" !CDS_SEC = "1";
"A":   PN = "1"  !CDS_PN = "1";
"B":   PN = "2"  !CDS_PN = "2";
BODY = "CAP_A","I215": #LOCATION = "C2G4" !CDS_LOCATION = "C2G4" #SEC = "1" !CDS_SEC = "1";
"A":   PN = "1"  !CDS_PN = "1";
"B":   PN = "2"  !CDS_PN = "2";
BODY = "CAP_A","I216": #LOCATION = "C2G3" !CDS_LOCATION = "C2G3" #SEC = "1" !CDS_SEC = "1";
"A":   PN = "1"  !CDS_PN = "1";
"B":   PN = "2"  !CDS_PN = "2";
BODY = "CAP_A","I217": #LOCATION = "C2G2" !CDS_LOCATION = "C2G2" #SEC = "1" !CDS_SEC = "1";
"A":   PN = "1"  !CDS_PN = "1";
"B":   PN = "2"  !CDS_PN = "2";
BODY = "CAP_A","I218": #LOCATION = "C2G9" !CDS_LOCATION = "C2G9" #SEC = "1" !CDS_SEC = "1";
"A":   PN = "1"  !CDS_PN = "1";
"B":   PN = "2"  !CDS_PN = "2";
BODY = "CAP_A","I219": #LOCATION = "C2G1" !CDS_LOCATION = "C2G1" #SEC = "1" !CDS_SEC = "1";
"A":   PN = "1"  !CDS_PN = "1";
"B":   PN = "2"  !CDS_PN = "2";
BODY = "CAP_A","I220": #LOCATION = "C2G12" !CDS_LOCATION = "C2G12" #SEC = "1" !CDS_SEC = "1";
"A":   PN = "1"  !CDS_PN = "1";
"B":   PN = "2"  !CDS_PN = "2";
BODY = "CAP_A","I221": #LOCATION = "C2G11" !CDS_LOCATION = "C2G11" #SEC = "1" !CDS_SEC = "1";
"A":   PN = "1"  !CDS_PN = "1";
"B":   PN = "2"  !CDS_PN = "2";
BODY = "CAP_A","I223": #LOCATION = "C2G10" !CDS_LOCATION = "C2G10" #SEC = "1" !CDS_SEC = "1";
"A":   PN = "1"  !CDS_PN = "1";
"B":   PN = "2"  !CDS_PN = "2";
BODY = "CAP_A","I225": #LOCATION = "C8U4" !CDS_LOCATION = "C8U4" #SEC = "1" !CDS_SEC = "1";
"A":   PN = "1"  !CDS_PN = "1";
"B":   PN = "2"  !CDS_PN = "2";
BODY = "CAP_A","I226": #LOCATION = "C8T10" !CDS_LOCATION = "C8T10" #SEC = "1" !CDS_SEC = "1";
"A":   PN = "1"  !CDS_PN = "1";
"B":   PN = "2"  !CDS_PN = "2";
BODY = "CAP_A","I227": #LOCATION = "C8T9" !CDS_LOCATION = "C8T9" #SEC = "1" !CDS_SEC = "1";
"A":   PN = "1"  !CDS_PN = "1";
"B":   PN = "2"  !CDS_PN = "2";
BODY = "CAP_A","I228": #LOCATION = "C8U5" !CDS_LOCATION = "C8U5" #SEC = "1" !CDS_SEC = "1";
"A":   PN = "1"  !CDS_PN = "1";
"B":   PN = "2"  !CDS_PN = "2";
BODY = "CAP_A","I229": #LOCATION = "C8T8" !CDS_LOCATION = "C8T8" #SEC = "1" !CDS_SEC = "1";
"A":   PN = "1"  !CDS_PN = "1";
"B":   PN = "2"  !CDS_PN = "2";
BODY = "CAP_A","I230": #LOCATION = "C8T7" !CDS_LOCATION = "C8T7" #SEC = "1" !CDS_SEC = "1";
"A":   PN = "1"  !CDS_PN = "1";
"B":   PN = "2"  !CDS_PN = "2";
BODY = "CAP_A","I231": #LOCATION = "C8T6" !CDS_LOCATION = "C8T6" #SEC = "1" !CDS_SEC = "1";
"A":   PN = "1"  !CDS_PN = "1";
"B":   PN = "2"  !CDS_PN = "2";
BODY = "CAP_A","I232": #LOCATION = "C8U6" !CDS_LOCATION = "C8U6" #SEC = "1" !CDS_SEC = "1";
"A":   PN = "1"  !CDS_PN = "1";
"B":   PN = "2"  !CDS_PN = "2";
BODY = "CAP_A","I233": #LOCATION = "C8T5" !CDS_LOCATION = "C8T5" #SEC = "1" !CDS_SEC = "1";
"A":   PN = "1"  !CDS_PN = "1";
"B":   PN = "2"  !CDS_PN = "2";
BODY = "CAP_A","I234": #LOCATION = "C7T5" !CDS_LOCATION = "C7T5" #SEC = "1" !CDS_SEC = "1";
"A":   PN = "1"  !CDS_PN = "1";
"B":   PN = "2"  !CDS_PN = "2";
BODY = "CAP_A","I235": #LOCATION = "C7T4" !CDS_LOCATION = "C7T4" #SEC = "1" !CDS_SEC = "1";
"A":   PN = "1"  !CDS_PN = "1";
"B":   PN = "2"  !CDS_PN = "2";
BODY = "CAP_A","I236": #LOCATION = "C8U3" !CDS_LOCATION = "C8U3" #SEC = "1" !CDS_SEC = "1";
"A":   PN = "1"  !CDS_PN = "1";
"B":   PN = "2"  !CDS_PN = "2";
BODY = "CAP_A","I237": #LOCATION = "C7U1" !CDS_LOCATION = "C7U1" #SEC = "1" !CDS_SEC = "1";
"A":   PN = "1"  !CDS_PN = "1";
"B":   PN = "2"  !CDS_PN = "2";
BODY = "CAP_A","I238": #LOCATION = "C7U2" !CDS_LOCATION = "C7U2" #SEC = "1" !CDS_SEC = "1";
"A":   PN = "1"  !CDS_PN = "1";
"B":   PN = "2"  !CDS_PN = "2";
BODY = "CAP_A","I239": #LOCATION = "C8U2" !CDS_LOCATION = "C8U2" #SEC = "1" !CDS_SEC = "1";
"A":   PN = "1"  !CDS_PN = "1";
"B":   PN = "2"  !CDS_PN = "2";
BODY = "CAP_A","I241": #LOCATION = "C8U7" !CDS_LOCATION = "C8U7" #SEC = "1" !CDS_SEC = "1";
"A":   PN = "1"  !CDS_PN = "1";
"B":   PN = "2"  !CDS_PN = "2";
BODY = "SHUNT","I243": #LOCATION = "SH7U1" !CDS_LOCATION = "SH7U1" #SEC = "1" !CDS_SEC = "1";
"A":   PN = "1"  !CDS_PN = "1";
"B":   PN = "2"  !CDS_PN = "2";
BODY = "SHUNT","I244": #LOCATION = "SH7U2" !CDS_LOCATION = "SH7U2" #SEC = "1" !CDS_SEC = "1";
"A":   PN = "1"  !CDS_PN = "1";
"B":   PN = "2"  !CDS_PN = "2";
DRAWING = "@baseboard_fab2_lib.baseboard_fab2(sch_1):page226";
BODY = "RES","I8": #LOCATION = "R9M7" !CDS_LOCATION = "R9M7" #SEC = "1" !CDS_SEC = "1";
"A":   PN = "1"  !CDS_PN = "1";
"B":   PN = "2"  !CDS_PN = "2";
BODY = "RES","I13": #LOCATION = "R1B13" !CDS_LOCATION = "R1B13" #SEC = "1" !CDS_SEC = "1";
"A":   PN = "1"  !CDS_PN = "1";
"B":   PN = "2"  !CDS_PN = "2";
BODY = "RES","I14": #LOCATION = "R1B5" !CDS_LOCATION = "R1B5" #SEC = "1" !CDS_SEC = "1";
"A":   PN = "1"  !CDS_PN = "1";
"B":   PN = "2"  !CDS_PN = "2";
BODY = "RES","I16": #LOCATION = "R1B11" !CDS_LOCATION = "R1B11" #SEC = "1" !CDS_SEC = "1";
"A":   PN = "1"  !CDS_PN = "1";
"B":   PN = "2"  !CDS_PN = "2";
BODY = "RES","I17": #LOCATION = "R1B2" !CDS_LOCATION = "R1B2" #SEC = "1" !CDS_SEC = "1";
"A":   PN = "1"  !CDS_PN = "1";
"B":   PN = "2"  !CDS_PN = "2";
BODY = "RES","I21": #LOCATION = "R1B6" !CDS_LOCATION = "R1B6" &SEC = "1" #&CDS_SEC = "1";
"A":   PN = "1"  !CDS_PN = "1";
"B":   PN = "2"  !CDS_PN = "2";
BODY = "RES","I22": #LOCATION = "R1B7" !CDS_LOCATION = "R1B7" &SEC = "1" #&CDS_SEC = "1";
"A":   PN = "1"  !CDS_PN = "1";
"B":   PN = "2"  !CDS_PN = "2";
BODY = "RES","I23": #LOCATION = "R1B10" !CDS_LOCATION = "R1B10" #SEC = "1" !CDS_SEC = "1";
"A":   PN = "1"  !CDS_PN = "1";
"B":   PN = "2"  !CDS_PN = "2";
BODY = "CAP_A","I25": #LOCATION = "C1B6" !CDS_LOCATION = "C1B6" &SEC = "1" #&CDS_SEC = "1";
"A":   PN = "1"  !CDS_PN = "1";
"B":   PN = "2"  !CDS_PN = "2";
BODY = "CAP_A","I27": #LOCATION = "C1B5" !CDS_LOCATION = "C1B5" #SEC = "1" !CDS_SEC = "1";
"A":   PN = "1"  !CDS_PN = "1";
"B":   PN = "2"  !CDS_PN = "2";
BODY = "RES","I30": #LOCATION = "R9M3" !CDS_LOCATION = "R9M3" #SEC = "1" !CDS_SEC = "1";
"A":   PN = "1"  !CDS_PN = "1";
"B":   PN = "2"  !CDS_PN = "2";
BODY = "RES","I32": #LOCATION = "R1B16" !CDS_LOCATION = "R1B16" #SEC = "1" !CDS_SEC = "1";
"A":   PN = "1"  !CDS_PN = "1";
"B":   PN = "2"  !CDS_PN = "2";
BODY = "CAP","I36": #LOCATION = "C1B11" !CDS_LOCATION = "C1B11" #SEC = "1" !CDS_SEC = "1";
"A":   PN = "1"  !CDS_PN = "1";
"B":   PN = "2"  !CDS_PN = "2";
BODY = "CAP","I39": #LOCATION = "C1B12" !CDS_LOCATION = "C1B12" #SEC = "1" !CDS_SEC = "1";
"A":   PN = "1"  !CDS_PN = "1";
"B":   PN = "2"  !CDS_PN = "2";
BODY = "CAP_A","I41": #LOCATION = "C1B3" !CDS_LOCATION = "C1B3" #SEC = "1" !CDS_SEC = "1";
"A":   PN = "1"  !CDS_PN = "1";
"B":   PN = "2"  !CDS_PN = "2";
BODY = "CAP_A","I44": #LOCATION = "C1B2" !CDS_LOCATION = "C1B2" #SEC = "1" !CDS_SEC = "1";
"A":   PN = "1"  !CDS_PN = "1";
"B":   PN = "2"  !CDS_PN = "2";
BODY = "RES","I50": #LOCATION = "R9M6" !CDS_LOCATION = "R9M6" #SEC = "1" !CDS_SEC = "1";
"A":   PN = "1"  !CDS_PN = "1";
"B":   PN = "2"  !CDS_PN = "2";
BODY = "RES","I53": #LOCATION = "R1B8" !CDS_LOCATION = "R1B8" #SEC = "1" !CDS_SEC = "1";
"A":   PN = "1"  !CDS_PN = "1";
"B":   PN = "2"  !CDS_PN = "2";
BODY = "RES","I57": #LOCATION = "R9M8" !CDS_LOCATION = "R9M8" #SEC = "1" !CDS_SEC = "1";
"A":   PN = "1"  !CDS_PN = "1";
"B":   PN = "2"  !CDS_PN = "2";
BODY = "RES","I58": #LOCATION = "R1B9" !CDS_LOCATION = "R1B9" #SEC = "1" !CDS_SEC = "1";
"A":   PN = "1"  !CDS_PN = "1";
"B":   PN = "2"  !CDS_PN = "2";
BODY = "CAP","I59": #LOCATION = "C1B8" !CDS_LOCATION = "C1B8" #SEC = "1" !CDS_SEC = "1";
"A":   PN = "1"  !CDS_PN = "1";
"B":   PN = "2"  !CDS_PN = "2";
BODY = "RES","I77": #LOCATION = "R1B15" !CDS_LOCATION = "R1B15" &SEC = "1" #&CDS_SEC = "1";
"A":   PN = "1"  !CDS_PN = "1";
"B":   PN = "2"  !CDS_PN = "2";
BODY = "RES","I78": #LOCATION = "R1B12" !CDS_LOCATION = "R1B12" &SEC = "1" #&CDS_SEC = "1";
"A":   PN = "1"  !CDS_PN = "1";
"B":   PN = "2"  !CDS_PN = "2";
BODY = "RES","I79": #LOCATION = "R1B1" !CDS_LOCATION = "R1B1" #SEC = "1" !CDS_SEC = "1";
"A":   PN = "1"  !CDS_PN = "1";
"B":   PN = "2"  !CDS_PN = "2";
BODY = "CAP","I80": #LOCATION = "C1B4" !CDS_LOCATION = "C1B4" #SEC = "1" !CDS_SEC = "1";
"A":   PN = "1"  !CDS_PN = "1";
"B":   PN = "2"  !CDS_PN = "2";
BODY = "RES","I82": #LOCATION = "R1B4" !CDS_LOCATION = "R1B4" #SEC = "1" !CDS_SEC = "1";
"A":   PN = "1"  !CDS_PN = "1";
"B":   PN = "2"  !CDS_PN = "2";
BODY = "RES","I84": #LOCATION = "R9M9" !CDS_LOCATION = "R9M9" &SEC = "1" #&CDS_SEC = "1";
"A":   PN = "1"  !CDS_PN = "1";
"B":   PN = "2"  !CDS_PN = "2";
BODY = "RES","I85": #LOCATION = "R9M5" !CDS_LOCATION = "R9M5" #SEC = "1" !CDS_SEC = "1";
"A":   PN = "1"  !CDS_PN = "1";
"B":   PN = "2"  !CDS_PN = "2";
BODY = "RES","I87": #LOCATION = "R9M11" !CDS_LOCATION = "R9M11" &SEC = "1" #&CDS_SEC = "1";
"A":   PN = "1"  !CDS_PN = "1";
"B":   PN = "2"  !CDS_PN = "2";
BODY = "RES","I88": #LOCATION = "R9M10" !CDS_LOCATION = "R9M10" &SEC = "1" #&CDS_SEC = "1";
"A":   PN = "1"  !CDS_PN = "1";
"B":   PN = "2"  !CDS_PN = "2";
BODY = "PXM1310B","I90": #LOCATION = "EU1B1" !CDS_LOCATION = "EU1B1" #SEC = "1" !CDS_SEC = "1";
"AIREF1":   PN = "21"  !CDS_PN = "21";
"AIREF2":   PN = "23"  !CDS_PN = "23";
"AIREF3":   PN = "25"  !CDS_PN = "25";
"AISEN1":   PN = "22"  !CDS_PN = "22";
"AISEN2":   PN = "24"  !CDS_PN = "24";
"AISEN3":   PN = "26"  !CDS_PN = "26";
"APWM1":   PN = "5"  !CDS_PN = "5";
"APWM2":   PN = "4"  !CDS_PN = "4";
"APWM3":   PN = "3"  !CDS_PN = "3";
"ATSEN":   PN = "35"  !CDS_PN = "35";
"AVREF":   PN = "20"  !CDS_PN = "20";
"AVREN":   PN = "10"  !CDS_PN = "10";
"AVRRDY":   PN = "9"  !CDS_PN = "9";
"AVSEN":   PN = "19"  !CDS_PN = "19";
"BIREF1":   PN = "31"  !CDS_PN = "31";
"BISEN1":   PN = "32"  !CDS_PN = "32";
"BPWM1":   PN = "1"  !CDS_PN = "1";
"BTSEN":   PN = "34"  !CDS_PN = "34";
"BVREF":   PN = "30"  !CDS_PN = "30";
"BVSEN":   PN = "29"  !CDS_PN = "29";
"DNC<0>":   PN = "2"  !CDS_PN = "2";
"DNC<1>":   PN = "28"  !CDS_PN = "28";
"GND":   PN = "27"  !CDS_PN = "27";
"IINSEN":   PN = "38"  !CDS_PN = "38";
"MP0":   PN = "13"  !CDS_PN = "13";
"MP1":   PN = "14"  !CDS_PN = "14";
"MP2":   PN = "18"  !CDS_PN = "18";
"PINALRT_N":   PN = "12"  !CDS_PN = "12";
"RESET_N":   PN = "8"  !CDS_PN = "8";
"SCL":   PN = "7"  !CDS_PN = "7";
"SDA":   PN = "6"  !CDS_PN = "6";
"THPAD":   PN = "41"  !CDS_PN = "41";
"VALRT_N":   PN = "17"  !CDS_PN = "17";
"VCLK":   PN = "15"  !CDS_PN = "15";
"VD12":   PN = "40"  !CDS_PN = "40";
"VDD":   PN = "39"  !CDS_PN = "39";
"VDIO":   PN = "16"  !CDS_PN = "16";
"VINSEN":   PN = "37"  !CDS_PN = "37";
"VRHOT_N":   PN = "11"  !CDS_PN = "11";
"XADDR1":   PN = "36"  !CDS_PN = "36";
"XADDR2":   PN = "33"  !CDS_PN = "33";
BODY = "CAP_A","I92": #LOCATION = "C9M11" !CDS_LOCATION = "C9M11" #SEC = "1" !CDS_SEC = "1";
"A":   PN = "1"  !CDS_PN = "1";
"B":   PN = "2"  !CDS_PN = "2";
DRAWING = "@baseboard_fab2_lib.baseboard_fab2(sch_1):page228";
BODY = "RES","I58": #LOCATION = "R1A1" !CDS_LOCATION = "R1A1" &SEC = "1" #&CDS_SEC = "1";
"A":   PN = "1"  !CDS_PN = "1";
"B":   PN = "2"  !CDS_PN = "2";
BODY = "RES","I74": #LOCATION = "R7L2" !CDS_LOCATION = "R7L2" #SEC = "1" !CDS_SEC = "1";
"A":   PN = "1"  !CDS_PN = "1";
"B":   PN = "2"  !CDS_PN = "2";
BODY = "CAPP","I75": #LOCATION = "C9L9" !CDS_LOCATION = "C9L9" #SEC = "1" !CDS_SEC = "1";
"A":   PN = "1"  !CDS_PN = "1";
"B":   PN = "2"  !CDS_PN = "2";
BODY = "CAPP","I76": #LOCATION = "C9L12" !CDS_LOCATION = "C9L12" #SEC = "1" !CDS_SEC = "1";
"A":   PN = "1"  !CDS_PN = "1";
"B":   PN = "2"  !CDS_PN = "2";
BODY = "CAPP","I77": #LOCATION = "C9L4" !CDS_LOCATION = "C9L4" #SEC = "1" !CDS_SEC = "1";
"A":   PN = "1"  !CDS_PN = "1";
"B":   PN = "2"  !CDS_PN = "2";
BODY = "CAPP","I78": #LOCATION = "C9L2" !CDS_LOCATION = "C9L2" #SEC = "1" !CDS_SEC = "1";
"A":   PN = "1"  !CDS_PN = "1";
"B":   PN = "2"  !CDS_PN = "2";
BODY = "CAP","I82": #LOCATION = "C2A8" !CDS_LOCATION = "C2A8" #SEC = "1" !CDS_SEC = "1";
"A":   PN = "1"  !CDS_PN = "1";
"B":   PN = "2"  !CDS_PN = "2";
BODY = "CAP","I83": #LOCATION = "C8L2" !CDS_LOCATION = "C8L2" #SEC = "1" !CDS_SEC = "1";
"A":   PN = "1"  !CDS_PN = "1";
"B":   PN = "2"  !CDS_PN = "2";
BODY = "CAP","I88": #LOCATION = "C8L11" !CDS_LOCATION = "C8L11" #SEC = "1" !CDS_SEC = "1";
"A":   PN = "1"  !CDS_PN = "1";
"B":   PN = "2"  !CDS_PN = "2";
BODY = "CAP","I89": #LOCATION = "C2A16" !CDS_LOCATION = "C2A16" #SEC = "1" !CDS_SEC = "1";
"A":   PN = "1"  !CDS_PN = "1";
"B":   PN = "2"  !CDS_PN = "2";
BODY = "CAP","I90": #LOCATION = "C8M7" !CDS_LOCATION = "C8M7" #SEC = "1" !CDS_SEC = "1";
"A":   PN = "1"  !CDS_PN = "1";
"B":   PN = "2"  !CDS_PN = "2";
BODY = "CAP","I91": #LOCATION = "C8M11" !CDS_LOCATION = "C8M11" #SEC = "1" !CDS_SEC = "1";
"A":   PN = "1"  !CDS_PN = "1";
"B":   PN = "2"  !CDS_PN = "2";
BODY = "CAP","I92": #LOCATION = "C7L1" !CDS_LOCATION = "C7L1" #SEC = "1" !CDS_SEC = "1";
"A":   PN = "1"  !CDS_PN = "1";
"B":   PN = "2"  !CDS_PN = "2";
BODY = "CAP","I110": #LOCATION = "C8L1" !CDS_LOCATION = "C8L1" #SEC = "1" !CDS_SEC = "1";
"A":   PN = "1"  !CDS_PN = "1";
"B":   PN = "2"  !CDS_PN = "2";
BODY = "INDUCTOR","I124": #LOCATION = "L1B1" !CDS_LOCATION = "L1B1" #SEC = "1" !CDS_SEC = "1";
"INA":   PN = "1"  !CDS_PN = "1";
"INB":   PN = "2"  !CDS_PN = "2";
BODY = "CAPP","I175": #LOCATION = "C1B10" !CDS_LOCATION = "C1B10" #SEC = "1" !CDS_SEC = "1";
"A":   PN = "1"  !CDS_PN = "1";
"B":   PN = "2"  !CDS_PN = "2";
BODY = "CAP","I183": #LOCATION = "C8P2" !CDS_LOCATION = "C8P2" #SEC = "1" !CDS_SEC = "1";
"A":   PN = "1"  !CDS_PN = "1";
"B":   PN = "2"  !CDS_PN = "2";
BODY = "CAP","I185": #LOCATION = "C8P1" !CDS_LOCATION = "C8P1" #SEC = "1" !CDS_SEC = "1";
"A":   PN = "1"  !CDS_PN = "1";
"B":   PN = "2"  !CDS_PN = "2";
BODY = "CAP","I186": #LOCATION = "C2D7" !CDS_LOCATION = "C2D7" #SEC = "1" !CDS_SEC = "1";
"A":   PN = "1"  !CDS_PN = "1";
"B":   PN = "2"  !CDS_PN = "2";
BODY = "CAP","I187": #LOCATION = "C2D4" !CDS_LOCATION = "C2D4" #SEC = "1" !CDS_SEC = "1";
"A":   PN = "1"  !CDS_PN = "1";
"B":   PN = "2"  !CDS_PN = "2";
BODY = "CAP","I188": #LOCATION = "C2D5" !CDS_LOCATION = "C2D5" #SEC = "1" !CDS_SEC = "1";
"A":   PN = "1"  !CDS_PN = "1";
"B":   PN = "2"  !CDS_PN = "2";
BODY = "CAP","I190": #LOCATION = "C2D6" !CDS_LOCATION = "C2D6" #SEC = "1" !CDS_SEC = "1";
"A":   PN = "1"  !CDS_PN = "1";
"B":   PN = "2"  !CDS_PN = "2";
BODY = "CAP_A","I198": #LOCATION = "C8M8" !CDS_LOCATION = "C8M8" #SEC = "1" !CDS_SEC = "1";
"A":   PN = "1"  !CDS_PN = "1";
"B":   PN = "2"  !CDS_PN = "2";
BODY = "CAP_A","I199": #LOCATION = "C2A5" !CDS_LOCATION = "C2A5" #SEC = "1" !CDS_SEC = "1";
"A":   PN = "1"  !CDS_PN = "1";
"B":   PN = "2"  !CDS_PN = "2";
BODY = "CAP_A","I200": #LOCATION = "C2B1" !CDS_LOCATION = "C2B1" #SEC = "1" !CDS_SEC = "1";
"A":   PN = "1"  !CDS_PN = "1";
"B":   PN = "2"  !CDS_PN = "2";
BODY = "CAP_A","I201": #LOCATION = "C8L12" !CDS_LOCATION = "C8L12" #SEC = "1" !CDS_SEC = "1";
"A":   PN = "1"  !CDS_PN = "1";
"B":   PN = "2"  !CDS_PN = "2";
BODY = "CAP_A","I202": #LOCATION = "C7M5" !CDS_LOCATION = "C7M5" #SEC = "1" !CDS_SEC = "1";
"A":   PN = "1"  !CDS_PN = "1";
"B":   PN = "2"  !CDS_PN = "2";
BODY = "CAP_A","I203": #LOCATION = "C8M10" !CDS_LOCATION = "C8M10" #SEC = "1" !CDS_SEC = "1";
"A":   PN = "1"  !CDS_PN = "1";
"B":   PN = "2"  !CDS_PN = "2";
BODY = "CAP_A","I204": #LOCATION = "C2B2" !CDS_LOCATION = "C2B2" #SEC = "1" !CDS_SEC = "1";
"A":   PN = "1"  !CDS_PN = "1";
"B":   PN = "2"  !CDS_PN = "2";
BODY = "CAP_A","I205": #LOCATION = "C8M9" !CDS_LOCATION = "C8M9" #SEC = "1" !CDS_SEC = "1";
"A":   PN = "1"  !CDS_PN = "1";
"B":   PN = "2"  !CDS_PN = "2";
BODY = "CAP_A","I206": #LOCATION = "C8M2" !CDS_LOCATION = "C8M2" #SEC = "1" !CDS_SEC = "1";
"A":   PN = "1"  !CDS_PN = "1";
"B":   PN = "2"  !CDS_PN = "2";
BODY = "CAP_A","I209": #LOCATION = "C2A2" !CDS_LOCATION = "C2A2" #SEC = "1" !CDS_SEC = "1";
"A":   PN = "1"  !CDS_PN = "1";
"B":   PN = "2"  !CDS_PN = "2";
BODY = "CAP_A","I210": #LOCATION = "C2A1" !CDS_LOCATION = "C2A1" #SEC = "1" !CDS_SEC = "1";
"A":   PN = "1"  !CDS_PN = "1";
"B":   PN = "2"  !CDS_PN = "2";
BODY = "CAP_A","I211": #LOCATION = "C2A12" !CDS_LOCATION = "C2A12" #SEC = "1" !CDS_SEC = "1";
"A":   PN = "1"  !CDS_PN = "1";
"B":   PN = "2"  !CDS_PN = "2";
BODY = "CAP_A","I212": #LOCATION = "C2A13" !CDS_LOCATION = "C2A13" #SEC = "1" !CDS_SEC = "1";
"A":   PN = "1"  !CDS_PN = "1";
"B":   PN = "2"  !CDS_PN = "2";
BODY = "CAP_A","I213": #LOCATION = "C2A11" !CDS_LOCATION = "C2A11" #SEC = "1" !CDS_SEC = "1";
"A":   PN = "1"  !CDS_PN = "1";
"B":   PN = "2"  !CDS_PN = "2";
BODY = "CAP_A","I214": #LOCATION = "C2A10" !CDS_LOCATION = "C2A10" #SEC = "1" !CDS_SEC = "1";
"A":   PN = "1"  !CDS_PN = "1";
"B":   PN = "2"  !CDS_PN = "2";
BODY = "CAP_A","I215": #LOCATION = "C2A9" !CDS_LOCATION = "C2A9" #SEC = "1" !CDS_SEC = "1";
"A":   PN = "1"  !CDS_PN = "1";
"B":   PN = "2"  !CDS_PN = "2";
BODY = "CAP_A","I216": #LOCATION = "C3A2" !CDS_LOCATION = "C3A2" #SEC = "1" !CDS_SEC = "1";
"A":   PN = "1"  !CDS_PN = "1";
"B":   PN = "2"  !CDS_PN = "2";
BODY = "CAP_A","I217": #LOCATION = "C3A1" !CDS_LOCATION = "C3A1" #SEC = "1" !CDS_SEC = "1";
"A":   PN = "1"  !CDS_PN = "1";
"B":   PN = "2"  !CDS_PN = "2";
BODY = "CAP_A","I218": #LOCATION = "C2A7" !CDS_LOCATION = "C2A7" #SEC = "1" !CDS_SEC = "1";
"A":   PN = "1"  !CDS_PN = "1";
"B":   PN = "2"  !CDS_PN = "2";
BODY = "CAP_A","I219": #LOCATION = "C2A6" !CDS_LOCATION = "C2A6" #SEC = "1" !CDS_SEC = "1";
"A":   PN = "1"  !CDS_PN = "1";
"B":   PN = "2"  !CDS_PN = "2";
BODY = "CAP_A","I220": #LOCATION = "C2A14" !CDS_LOCATION = "C2A14" #SEC = "1" !CDS_SEC = "1";
"A":   PN = "1"  !CDS_PN = "1";
"B":   PN = "2"  !CDS_PN = "2";
BODY = "CAP_A","I221": #LOCATION = "C2A15" !CDS_LOCATION = "C2A15" #SEC = "1" !CDS_SEC = "1";
"A":   PN = "1"  !CDS_PN = "1";
"B":   PN = "2"  !CDS_PN = "2";
BODY = "CAP_A","I222": #LOCATION = "C3A5" !CDS_LOCATION = "C3A5" #SEC = "1" !CDS_SEC = "1";
"A":   PN = "1"  !CDS_PN = "1";
"B":   PN = "2"  !CDS_PN = "2";
BODY = "CAP_A","I223": #LOCATION = "C3A6" !CDS_LOCATION = "C3A6" #SEC = "1" !CDS_SEC = "1";
"A":   PN = "1"  !CDS_PN = "1";
"B":   PN = "2"  !CDS_PN = "2";
BODY = "CAP_A","I225": #LOCATION = "C7L5" !CDS_LOCATION = "C7L5" #SEC = "1" !CDS_SEC = "1";
"A":   PN = "1"  !CDS_PN = "1";
"B":   PN = "2"  !CDS_PN = "2";
BODY = "CAP_A","I227": #LOCATION = "C8M3" !CDS_LOCATION = "C8M3" #SEC = "1" !CDS_SEC = "1";
"A":   PN = "1"  !CDS_PN = "1";
"B":   PN = "2"  !CDS_PN = "2";
BODY = "CAP_A","I228": #LOCATION = "C8M5" !CDS_LOCATION = "C8M5" #SEC = "1" !CDS_SEC = "1";
"A":   PN = "1"  !CDS_PN = "1";
"B":   PN = "2"  !CDS_PN = "2";
BODY = "CAP_A","I229": #LOCATION = "C8L10" !CDS_LOCATION = "C8L10" #SEC = "1" !CDS_SEC = "1";
"A":   PN = "1"  !CDS_PN = "1";
"B":   PN = "2"  !CDS_PN = "2";
BODY = "CAP_A","I230": #LOCATION = "C2A3" !CDS_LOCATION = "C2A3" #SEC = "1" !CDS_SEC = "1";
"A":   PN = "1"  !CDS_PN = "1";
"B":   PN = "2"  !CDS_PN = "2";
BODY = "CAP_A","I231": #LOCATION = "C7M1" !CDS_LOCATION = "C7M1" #SEC = "1" !CDS_SEC = "1";
"A":   PN = "1"  !CDS_PN = "1";
"B":   PN = "2"  !CDS_PN = "2";
BODY = "CAP_A","I232": #LOCATION = "C7M2" !CDS_LOCATION = "C7M2" #SEC = "1" !CDS_SEC = "1";
"A":   PN = "1"  !CDS_PN = "1";
"B":   PN = "2"  !CDS_PN = "2";
BODY = "CAP_A","I233": #LOCATION = "C8M4" !CDS_LOCATION = "C8M4" #SEC = "1" !CDS_SEC = "1";
"A":   PN = "1"  !CDS_PN = "1";
"B":   PN = "2"  !CDS_PN = "2";
BODY = "CAP_A","I234": #LOCATION = "C2A4" !CDS_LOCATION = "C2A4" #SEC = "1" !CDS_SEC = "1";
"A":   PN = "1"  !CDS_PN = "1";
"B":   PN = "2"  !CDS_PN = "2";
BODY = "CAP_A","I235": #LOCATION = "C8M6" !CDS_LOCATION = "C8M6" #SEC = "1" !CDS_SEC = "1";
"A":   PN = "1"  !CDS_PN = "1";
"B":   PN = "2"  !CDS_PN = "2";
BODY = "CAP_A","I236": #LOCATION = "C8L9" !CDS_LOCATION = "C8L9" #SEC = "1" !CDS_SEC = "1";
"A":   PN = "1"  !CDS_PN = "1";
"B":   PN = "2"  !CDS_PN = "2";
BODY = "CAP_A","I237": #LOCATION = "C8L8" !CDS_LOCATION = "C8L8" #SEC = "1" !CDS_SEC = "1";
"A":   PN = "1"  !CDS_PN = "1";
"B":   PN = "2"  !CDS_PN = "2";
BODY = "CAP_A","I238": #LOCATION = "C7L4" !CDS_LOCATION = "C7L4" #SEC = "1" !CDS_SEC = "1";
"A":   PN = "1"  !CDS_PN = "1";
"B":   PN = "2"  !CDS_PN = "2";
BODY = "CAP_A","I239": #LOCATION = "C8L7" !CDS_LOCATION = "C8L7" #SEC = "1" !CDS_SEC = "1";
"A":   PN = "1"  !CDS_PN = "1";
"B":   PN = "2"  !CDS_PN = "2";
BODY = "CAP_A","I240": #LOCATION = "C8L6" !CDS_LOCATION = "C8L6" #SEC = "1" !CDS_SEC = "1";
"A":   PN = "1"  !CDS_PN = "1";
"B":   PN = "2"  !CDS_PN = "2";
BODY = "CAP_A","I241": #LOCATION = "C8L5" !CDS_LOCATION = "C8L5" #SEC = "1" !CDS_SEC = "1";
"A":   PN = "1"  !CDS_PN = "1";
"B":   PN = "2"  !CDS_PN = "2";
BODY = "CAP_A","I243": #LOCATION = "C8M1" !CDS_LOCATION = "C8M1" #SEC = "1" !CDS_SEC = "1";
"A":   PN = "1"  !CDS_PN = "1";
"B":   PN = "2"  !CDS_PN = "2";
BODY = "SHUNT","I245": #LOCATION = "SH7L2" !CDS_LOCATION = "SH7L2" #SEC = "1" !CDS_SEC = "1";
"A":   PN = "1"  !CDS_PN = "1";
"B":   PN = "2"  !CDS_PN = "2";
BODY = "SHUNT","I246": #LOCATION = "SH7L1" !CDS_LOCATION = "SH7L1" #SEC = "1" !CDS_SEC = "1";
"A":   PN = "1"  !CDS_PN = "1";
"B":   PN = "2"  !CDS_PN = "2";
DRAWING = "@baseboard_fab2_lib.baseboard_fab2(sch_1):page229";
BODY = "RES","I14": #LOCATION = "R4G17" !CDS_LOCATION = "R4G17" #SEC = "1" !CDS_SEC = "1";
"A":   PN = "1"  !CDS_PN = "1";
"B":   PN = "2"  !CDS_PN = "2";
BODY = "CAP","I15": #LOCATION = "C4G13" !CDS_LOCATION = "C4G13" #SEC = "1" !CDS_SEC = "1";
"A":   PN = "1"  !CDS_PN = "1";
"B":   PN = "2"  !CDS_PN = "2";
BODY = "CAP","I17": #LOCATION = "C4G20" !CDS_LOCATION = "C4G20" #SEC = "1" !CDS_SEC = "1";
"A":   PN = "1"  !CDS_PN = "1";
"B":   PN = "2"  !CDS_PN = "2";
BODY = "CAP","I21": #LOCATION = "C4G21" !CDS_LOCATION = "C4G21" #SEC = "1" !CDS_SEC = "1";
"A":   PN = "1"  !CDS_PN = "1";
"B":   PN = "2"  !CDS_PN = "2";
BODY = "MIC5166","I24": #LOCATION = "EU4G2" !CDS_LOCATION = "EU4G2" #SEC = "1" !CDS_SEC = "1";
"AGND":   PN = "3"  !CDS_PN = "3";
"BIAS":   PN = "2"  !CDS_PN = "2";
"EN":   PN = "7"  !CDS_PN = "7";
"PG":   PN = "5"  !CDS_PN = "5";
"PGND":   PN = "8"  !CDS_PN = "8";
"SNS":   PN = "6"  !CDS_PN = "6";
"THPAD":   PN = "11"  !CDS_PN = "11";
"VDDQ":   PN = "4"  !CDS_PN = "4";
"VIN":   PN = "10"  !CDS_PN = "10";
"VREF":   PN = "1"  !CDS_PN = "1";
"VTT":   PN = "9"  !CDS_PN = "9";
BODY = "CAP","I25": #LOCATION = "C6U14" !CDS_LOCATION = "C6U14" #SEC = "1" !CDS_SEC = "1";
"A":   PN = "1"  !CDS_PN = "1";
"B":   PN = "2"  !CDS_PN = "2";
BODY = "CAP","I27": #LOCATION = "C4G18" !CDS_LOCATION = "C4G18" #SEC = "1" !CDS_SEC = "1";
"A":   PN = "1"  !CDS_PN = "1";
"B":   PN = "2"  !CDS_PN = "2";
BODY = "CAP","I29": #LOCATION = "C6U13" !CDS_LOCATION = "C6U13" #SEC = "1" !CDS_SEC = "1";
"A":   PN = "1"  !CDS_PN = "1";
"B":   PN = "2"  !CDS_PN = "2";
BODY = "RES","I32": #LOCATION = "R6U7" !CDS_LOCATION = "R6U7" #SEC = "1" !CDS_SEC = "1";
"A":   PN = "1"  !CDS_PN = "1";
"B":   PN = "2"  !CDS_PN = "2";
BODY = "RES","I34": #LOCATION = "R6U3" !CDS_LOCATION = "R6U3" #SEC = "1" !CDS_SEC = "1";
"A":   PN = "1"  !CDS_PN = "1";
"B":   PN = "2"  !CDS_PN = "2";
BODY = "RES","I35": #LOCATION = "R4G16" !CDS_LOCATION = "R4G16" #SEC = "1" !CDS_SEC = "1";
"A":   PN = "1"  !CDS_PN = "1";
"B":   PN = "2"  !CDS_PN = "2";
BODY = "CAP","I36": #LOCATION = "C4G12" !CDS_LOCATION = "C4G12" #SEC = "1" !CDS_SEC = "1";
"A":   PN = "1"  !CDS_PN = "1";
"B":   PN = "2"  !CDS_PN = "2";
BODY = "RES","I39": #LOCATION = "R6U6" !CDS_LOCATION = "R6U6" #SEC = "1" !CDS_SEC = "1";
"A":   PN = "1"  !CDS_PN = "1";
"B":   PN = "2"  !CDS_PN = "2";
BODY = "CAP","I46": #LOCATION = "C6U11" !CDS_LOCATION = "C6U11" #SEC = "1" !CDS_SEC = "1";
"A":   PN = "1"  !CDS_PN = "1";
"B":   PN = "2"  !CDS_PN = "2";
BODY = "CAP_A","I47": #LOCATION = "C2F2" !CDS_LOCATION = "C2F2" #SEC = "1" !CDS_SEC = "1";
"A":   PN = "1"  !CDS_PN = "1";
"B":   PN = "2"  !CDS_PN = "2";
BODY = "CAP_A","I48": #LOCATION = "C8T3" !CDS_LOCATION = "C8T3" #SEC = "1" !CDS_SEC = "1";
"A":   PN = "1"  !CDS_PN = "1";
"B":   PN = "2"  !CDS_PN = "2";
BODY = "CAP_A","I49": #LOCATION = "C8U10" !CDS_LOCATION = "C8U10" #SEC = "1" !CDS_SEC = "1";
"A":   PN = "1"  !CDS_PN = "1";
"B":   PN = "2"  !CDS_PN = "2";
BODY = "RES","I51": #LOCATION = "R4G15" !CDS_LOCATION = "R4G15" #SEC = "1" !CDS_SEC = "1";
"A":   PN = "1"  !CDS_PN = "1";
"B":   PN = "2"  !CDS_PN = "2";
BODY = "RES","I52": #LOCATION = "R6U8" !CDS_LOCATION = "R6U8" &SEC = "1" #&CDS_SEC = "1";
"A":   PN = "1"  !CDS_PN = "1";
"B":   PN = "2"  !CDS_PN = "2";
BODY = "SHUNT","I53": #LOCATION = "SH8U1" !CDS_LOCATION = "SH8U1" #SEC = "1" !CDS_SEC = "1";
"A":   PN = "1"  !CDS_PN = "1";
"B":   PN = "2"  !CDS_PN = "2";
DRAWING = "@baseboard_fab2_lib.baseboard_fab2(sch_1):page230";
BODY = "CAP","I16": #LOCATION = "C4A3" !CDS_LOCATION = "C4A3" #SEC = "1" !CDS_SEC = "1";
"A":   PN = "1"  !CDS_PN = "1";
"B":   PN = "2"  !CDS_PN = "2";
BODY = "RES","I17": #LOCATION = "R4A5" !CDS_LOCATION = "R4A5" #SEC = "1" !CDS_SEC = "1";
"A":   PN = "1"  !CDS_PN = "1";
"B":   PN = "2"  !CDS_PN = "2";
BODY = "CAP","I18": #LOCATION = "C4A13" !CDS_LOCATION = "C4A13" #SEC = "1" !CDS_SEC = "1";
"A":   PN = "1"  !CDS_PN = "1";
"B":   PN = "2"  !CDS_PN = "2";
BODY = "CAP","I21": #LOCATION = "C4A14" !CDS_LOCATION = "C4A14" #SEC = "1" !CDS_SEC = "1";
"A":   PN = "1"  !CDS_PN = "1";
"B":   PN = "2"  !CDS_PN = "2";
BODY = "CAP","I25": #LOCATION = "C4A15" !CDS_LOCATION = "C4A15" #SEC = "1" !CDS_SEC = "1";
"A":   PN = "1"  !CDS_PN = "1";
"B":   PN = "2"  !CDS_PN = "2";
BODY = "CAP","I26": #LOCATION = "C6L5" !CDS_LOCATION = "C6L5" #SEC = "1" !CDS_SEC = "1";
"A":   PN = "1"  !CDS_PN = "1";
"B":   PN = "2"  !CDS_PN = "2";
BODY = "CAP","I28": #LOCATION = "C4A8" !CDS_LOCATION = "C4A8" #SEC = "1" !CDS_SEC = "1";
"A":   PN = "1"  !CDS_PN = "1";
"B":   PN = "2"  !CDS_PN = "2";
BODY = "RES","I30": #LOCATION = "R6L8" !CDS_LOCATION = "R6L8" #SEC = "1" !CDS_SEC = "1";
"A":   PN = "1"  !CDS_PN = "1";
"B":   PN = "2"  !CDS_PN = "2";
BODY = "MIC5166","I31": #LOCATION = "EU4A2" !CDS_LOCATION = "EU4A2" #SEC = "1" !CDS_SEC = "1";
"AGND":   PN = "3"  !CDS_PN = "3";
"BIAS":   PN = "2"  !CDS_PN = "2";
"EN":   PN = "7"  !CDS_PN = "7";
"PG":   PN = "5"  !CDS_PN = "5";
"PGND":   PN = "8"  !CDS_PN = "8";
"SNS":   PN = "6"  !CDS_PN = "6";
"THPAD":   PN = "11"  !CDS_PN = "11";
"VDDQ":   PN = "4"  !CDS_PN = "4";
"VIN":   PN = "10"  !CDS_PN = "10";
"VREF":   PN = "1"  !CDS_PN = "1";
"VTT":   PN = "9"  !CDS_PN = "9";
BODY = "RES","I34": #LOCATION = "R6L6" !CDS_LOCATION = "R6L6" #SEC = "1" !CDS_SEC = "1";
"A":   PN = "1"  !CDS_PN = "1";
"B":   PN = "2"  !CDS_PN = "2";
BODY = "RES","I37": #LOCATION = "R6L5" !CDS_LOCATION = "R6L5" #SEC = "1" !CDS_SEC = "1";
"A":   PN = "1"  !CDS_PN = "1";
"B":   PN = "2"  !CDS_PN = "2";
BODY = "RES","I38": #LOCATION = "R4A3" !CDS_LOCATION = "R4A3" #SEC = "1" !CDS_SEC = "1";
"A":   PN = "1"  !CDS_PN = "1";
"B":   PN = "2"  !CDS_PN = "2";
BODY = "CAP","I39": #LOCATION = "C4A6" !CDS_LOCATION = "C4A6" #SEC = "1" !CDS_SEC = "1";
"A":   PN = "1"  !CDS_PN = "1";
"B":   PN = "2"  !CDS_PN = "2";
BODY = "CAP","I46": #LOCATION = "C4A7" !CDS_LOCATION = "C4A7" #SEC = "1" !CDS_SEC = "1";
"A":   PN = "1"  !CDS_PN = "1";
"B":   PN = "2"  !CDS_PN = "2";
BODY = "CAP_A","I47": #LOCATION = "C8M12" !CDS_LOCATION = "C8M12" #SEC = "1" !CDS_SEC = "1";
"A":   PN = "1"  !CDS_PN = "1";
"B":   PN = "2"  !CDS_PN = "2";
BODY = "CAP_A","I48": #LOCATION = "C8L3" !CDS_LOCATION = "C8L3" #SEC = "1" !CDS_SEC = "1";
"A":   PN = "1"  !CDS_PN = "1";
"B":   PN = "2"  !CDS_PN = "2";
BODY = "CAP_A","I49": #LOCATION = "C8L4" !CDS_LOCATION = "C8L4" #SEC = "1" !CDS_SEC = "1";
"A":   PN = "1"  !CDS_PN = "1";
"B":   PN = "2"  !CDS_PN = "2";
BODY = "RES","I51": #LOCATION = "R4A4" !CDS_LOCATION = "R4A4" #SEC = "1" !CDS_SEC = "1";
"A":   PN = "1"  !CDS_PN = "1";
"B":   PN = "2"  !CDS_PN = "2";
BODY = "RES","I52": #LOCATION = "R6L7" !CDS_LOCATION = "R6L7" &SEC = "1" #&CDS_SEC = "1";
"A":   PN = "1"  !CDS_PN = "1";
"B":   PN = "2"  !CDS_PN = "2";
BODY = "SHUNT","I53": #LOCATION = "SH8L1" !CDS_LOCATION = "SH8L1" #SEC = "1" !CDS_SEC = "1";
"A":   PN = "1"  !CDS_PN = "1";
"B":   PN = "2"  !CDS_PN = "2";
DRAWING = "@baseboard_fab2_lib.baseboard_fab2(sch_1):page231";
BODY = "CAP","I122": #LOCATION = "C6F6" !CDS_LOCATION = "C6F6" &SEC = "1" #&CDS_SEC = "1";
"A":   PN = "1"  !CDS_PN = "1";
"B":   PN = "2"  !CDS_PN = "2";
BODY = "CAP","I124": #LOCATION = "C4T6" !CDS_LOCATION = "C4T6" &SEC = "1" #&CDS_SEC = "1";
"A":   PN = "1"  !CDS_PN = "1";
"B":   PN = "2"  !CDS_PN = "2";
BODY = "CAP","I125": #LOCATION = "C4T5" !CDS_LOCATION = "C4T5" &SEC = "1" #&CDS_SEC = "1";
"A":   PN = "1"  !CDS_PN = "1";
"B":   PN = "2"  !CDS_PN = "2";
BODY = "CAP","I126": #LOCATION = "C6G1" !CDS_LOCATION = "C6G1" &SEC = "1" #&CDS_SEC = "1";
"A":   PN = "1"  !CDS_PN = "1";
"B":   PN = "2"  !CDS_PN = "2";
BODY = "CAP","I128": #LOCATION = "C6G2" !CDS_LOCATION = "C6G2" &SEC = "1" #&CDS_SEC = "1";
"A":   PN = "1"  !CDS_PN = "1";
"B":   PN = "2"  !CDS_PN = "2";
BODY = "CAP","I129": #LOCATION = "C4U2" !CDS_LOCATION = "C4U2" &SEC = "1" #&CDS_SEC = "1";
"A":   PN = "1"  !CDS_PN = "1";
"B":   PN = "2"  !CDS_PN = "2";
BODY = "CAP","I130": #LOCATION = "C4U1" !CDS_LOCATION = "C4U1" &SEC = "1" #&CDS_SEC = "1";
"A":   PN = "1"  !CDS_PN = "1";
"B":   PN = "2"  !CDS_PN = "2";
BODY = "CAP","I131": #LOCATION = "C6G4" !CDS_LOCATION = "C6G4" &SEC = "1" #&CDS_SEC = "1";
"A":   PN = "1"  !CDS_PN = "1";
"B":   PN = "2"  !CDS_PN = "2";
BODY = "RES","I134": #LOCATION = "R7F15" !CDS_LOCATION = "R7F15" &SEC = "1" #&CDS_SEC = "1";
"A":   PN = "1"  !CDS_PN = "1";
"B":   PN = "2"  !CDS_PN = "2";
BODY = "RES","I136": #LOCATION = "R7F14" !CDS_LOCATION = "R7F14" &SEC = "1" #&CDS_SEC = "1";
"A":   PN = "1"  !CDS_PN = "1";
"B":   PN = "2"  !CDS_PN = "2";
BODY = "CAP","I140": #LOCATION = "C7F8" !CDS_LOCATION = "C7F8" &SEC = "1" #&CDS_SEC = "1";
"A":   PN = "1"  !CDS_PN = "1";
"B":   PN = "2"  !CDS_PN = "2";
BODY = "CAP","I142": #LOCATION = "C7F11" !CDS_LOCATION = "C7F11" &SEC = "1" #&CDS_SEC = "1";
"A":   PN = "1"  !CDS_PN = "1";
"B":   PN = "2"  !CDS_PN = "2";
BODY = "RES","I143": #LOCATION = "R7F19" !CDS_LOCATION = "R7F19" #SEC = "1" !CDS_SEC = "1";
"A":   PN = "1"  !CDS_PN = "1";
"B":   PN = "2"  !CDS_PN = "2";
BODY = "CAP","I145": #LOCATION = "C6G5" !CDS_LOCATION = "C6G5" &SEC = "1" #&CDS_SEC = "1";
"A":   PN = "1"  !CDS_PN = "1";
"B":   PN = "2"  !CDS_PN = "2";
BODY = "CAP","I146": #LOCATION = "C4U4" !CDS_LOCATION = "C4U4" &SEC = "1" #&CDS_SEC = "1";
"A":   PN = "1"  !CDS_PN = "1";
"B":   PN = "2"  !CDS_PN = "2";
BODY = "CAP","I148": #LOCATION = "C4U3" !CDS_LOCATION = "C4U3" &SEC = "1" #&CDS_SEC = "1";
"A":   PN = "1"  !CDS_PN = "1";
"B":   PN = "2"  !CDS_PN = "2";
BODY = "CAP","I149": #LOCATION = "C6F5" !CDS_LOCATION = "C6F5" #SEC = "1" !CDS_SEC = "1";
"A":   PN = "1"  !CDS_PN = "1";
"B":   PN = "2"  !CDS_PN = "2";
BODY = "CAP","I151": #LOCATION = "C7F7" !CDS_LOCATION = "C7F7" &SEC = "1" #&CDS_SEC = "1";
"A":   PN = "1"  !CDS_PN = "1";
"B":   PN = "2"  !CDS_PN = "2";
BODY = "RES","I154": #LOCATION = "R7F8" !CDS_LOCATION = "R7F8" &SEC = "1" #&CDS_SEC = "1";
"A":   PN = "1"  !CDS_PN = "1";
"B":   PN = "2"  !CDS_PN = "2";
BODY = "CAP","I159": #LOCATION = "C7F4" !CDS_LOCATION = "C7F4" &SEC = "1" #&CDS_SEC = "1";
"A":   PN = "1"  !CDS_PN = "1";
"B":   PN = "2"  !CDS_PN = "2";
BODY = "CAP","I161": #LOCATION = "C3T10" !CDS_LOCATION = "C3T10" &SEC = "1" #&CDS_SEC = "1";
"A":   PN = "1"  !CDS_PN = "1";
"B":   PN = "2"  !CDS_PN = "2";
BODY = "FERRITE","I162": #LOCATION = "FB7F1" !CDS_LOCATION = "FB7F1" #SEC = "1" !CDS_SEC = "1";
"A":   PN = "1"  !CDS_PN = "1";
"B":   PN = "2"  !CDS_PN = "2";
BODY = "RES","I166": #LOCATION = "R7F11" !CDS_LOCATION = "R7F11" &SEC = "1" #&CDS_SEC = "1";
"A":   PN = "1"  !CDS_PN = "1";
"B":   PN = "2"  !CDS_PN = "2";
BODY = "RES","I167": #LOCATION = "R7F13" !CDS_LOCATION = "R7F13" &SEC = "1" #&CDS_SEC = "1";
"A":   PN = "1"  !CDS_PN = "1";
"B":   PN = "2"  !CDS_PN = "2";
BODY = "RES","I168": #LOCATION = "R7F12" !CDS_LOCATION = "R7F12" #SEC = "1" !CDS_SEC = "1";
"A":   PN = "1"  !CDS_PN = "1";
"B":   PN = "2"  !CDS_PN = "2";
BODY = "RES","I170": #LOCATION = "R7F35" !CDS_LOCATION = "R7F35" &SEC = "1" #&CDS_SEC = "1";
"A":   PN = "1"  !CDS_PN = "1";
"B":   PN = "2"  !CDS_PN = "2";
BODY = "RES","I174": #LOCATION = "R7F7" !CDS_LOCATION = "R7F7" &SEC = "1" #&CDS_SEC = "1";
"A":   PN = "1"  !CDS_PN = "1";
"B":   PN = "2"  !CDS_PN = "2";
BODY = "CAP","I175": #LOCATION = "C7F3" !CDS_LOCATION = "C7F3" &SEC = "1" #&CDS_SEC = "1";
"A":   PN = "1"  !CDS_PN = "1";
"B":   PN = "2"  !CDS_PN = "2";
BODY = "RES","I177": #LOCATION = "R7F10" !CDS_LOCATION = "R7F10" #SEC = "1" !CDS_SEC = "1";
"A":   PN = "1"  !CDS_PN = "1";
"B":   PN = "2"  !CDS_PN = "2";
BODY = "INDUCTOR","I178": #LOCATION = "L7F1" !CDS_LOCATION = "L7F1" &SEC = "1" #&CDS_SEC = "1";
"INA":   PN = "1"  !CDS_PN = "1";
"INB":   PN = "2"  !CDS_PN = "2";
BODY = "CAPP","I180": #LOCATION = "C6F4" !CDS_LOCATION = "C6F4" &SEC = "1" #&CDS_SEC = "1";
"A":   PN = "1"  !CDS_PN = "1";
"B":   PN = "2"  !CDS_PN = "2";
BODY = "CAP","I184": #LOCATION = "C3T7" !CDS_LOCATION = "C3T7" &SEC = "1" #&CDS_SEC = "1";
"A":   PN = "1"  !CDS_PN = "1";
"B":   PN = "2"  !CDS_PN = "2";
BODY = "CAP","I186": #LOCATION = "C3T9" !CDS_LOCATION = "C3T9" &SEC = "1" #&CDS_SEC = "1";
"A":   PN = "1"  !CDS_PN = "1";
"B":   PN = "2"  !CDS_PN = "2";
BODY = "NCP3232L","I193": #LOCATION = "EU7F1" !CDS_LOCATION = "EU7F1" #SEC = "1" !CDS_SEC = "1";
"AGND":   PN = "5"  !CDS_PN = "5";
"BST":   PN = "36"  !CDS_PN = "36";
"COMP":   PN = "3"  !CDS_PN = "3";
"EN":   PN = "40"  !CDS_PN = "40";
"FB":   PN = "2"  !CDS_PN = "2";
"GND":   PN = "41"  !CDS_PN = "41";
"ISET":   PN = "4"  !CDS_PN = "4";
"OTS":   PN = "6"  !CDS_PN = "6";
"PG":   PN = "7"  !CDS_PN = "7";
"PGND<0>":   PN = "16"  !CDS_PN = "16";
"PGND<1>":   PN = "17"  !CDS_PN = "17";
"PGND<2>":   PN = "18"  !CDS_PN = "18";
"PGND<3>":   PN = "19"  !CDS_PN = "19";
"PGND<4>":   PN = "20"  !CDS_PN = "20";
"PGND<5>":   PN = "21"  !CDS_PN = "21";
"PGND<6>":   PN = "22"  !CDS_PN = "22";
"PGND<7>":   PN = "23"  !CDS_PN = "23";
"PGND<8>":   PN = "24"  !CDS_PN = "24";
"PGND<9>":   PN = "25"  !CDS_PN = "25";
"PGND<10>":   PN = "26"  !CDS_PN = "26";
"PGND<11>":   PN = "27"  !CDS_PN = "27";
"PGND<12>":   PN = "28"  !CDS_PN = "28";
"PGND<13>":   PN = "37"  !CDS_PN = "37";
"SS":   PN = "1"  !CDS_PN = "1";
"VB":   PN = "38"  !CDS_PN = "38";
"VCC":   PN = "39"  !CDS_PN = "39";
"VIN<0>":   PN = "8"  !CDS_PN = "8";
"VIN<1>":   PN = "9"  !CDS_PN = "9";
"VIN<2>":   PN = "10"  !CDS_PN = "10";
"VIN<3>":   PN = "11"  !CDS_PN = "11";
"VIN<4>":   PN = "12"  !CDS_PN = "12";
"VIN<5>":   PN = "13"  !CDS_PN = "13";
"VIN<6>":   PN = "14"  !CDS_PN = "14";
"VIN<7>":   PN = "42"  !CDS_PN = "42";
"VSW":   PN = "35"  !CDS_PN = "35";
"VSWH<0>":   PN = "15"  !CDS_PN = "15";
"VSWH<1>":   PN = "29"  !CDS_PN = "29";
"VSWH<2>":   PN = "30"  !CDS_PN = "30";
"VSWH<3>":   PN = "31"  !CDS_PN = "31";
"VSWH<4>":   PN = "32"  !CDS_PN = "32";
"VSWH<5>":   PN = "33"  !CDS_PN = "33";
"VSWH<6>":   PN = "34"  !CDS_PN = "34";
"VSWH<7>":   PN = "43"  !CDS_PN = "43";
BODY = "CAP","I194": #LOCATION = "C7F10" !CDS_LOCATION = "C7F10" #SEC = "1" !CDS_SEC = "1";
"A":   PN = "1"  !CDS_PN = "1";
"B":   PN = "2"  !CDS_PN = "2";
BODY = "CAP","I199": #LOCATION = "C7F9" !CDS_LOCATION = "C7F9" #SEC = "1" !CDS_SEC = "1";
"A":   PN = "1"  !CDS_PN = "1";
"B":   PN = "2"  !CDS_PN = "2";
BODY = "CAP","I200": #LOCATION = "C7F12" !CDS_LOCATION = "C7F12" #SEC = "1" !CDS_SEC = "1";
"A":   PN = "1"  !CDS_PN = "1";
"B":   PN = "2"  !CDS_PN = "2";
BODY = "RES","I201": #LOCATION = "R7F18" !CDS_LOCATION = "R7F18" #SEC = "1" !CDS_SEC = "1";
"A":   PN = "1"  !CDS_PN = "1";
"B":   PN = "2"  !CDS_PN = "2";
BODY = "CAP","I202": #LOCATION = "C3T11" !CDS_LOCATION = "C3T11" #SEC = "1" !CDS_SEC = "1";
"A":   PN = "1"  !CDS_PN = "1";
"B":   PN = "2"  !CDS_PN = "2";
BODY = "CAP_A","I205": #LOCATION = "C7F6" !CDS_LOCATION = "C7F6" #SEC = "1" !CDS_SEC = "1";
"A":   PN = "1"  !CDS_PN = "1";
"B":   PN = "2"  !CDS_PN = "2";
BODY = "RES","I208": #LOCATION = "R7F16" !CDS_LOCATION = "R7F16" #SEC = "1" !CDS_SEC = "1";
"A":   PN = "1"  !CDS_PN = "1";
"B":   PN = "2"  !CDS_PN = "2";
BODY = "CAP","I209": #LOCATION = "C7F5" !CDS_LOCATION = "C7F5" #SEC = "1" !CDS_SEC = "1";
"A":   PN = "1"  !CDS_PN = "1";
"B":   PN = "2"  !CDS_PN = "2";
BODY = "CAP","I210": #LOCATION = "C3T8" !CDS_LOCATION = "C3T8" #SEC = "1" !CDS_SEC = "1";
"A":   PN = "1"  !CDS_PN = "1";
"B":   PN = "2"  !CDS_PN = "2";
BODY = "CAP","I211": #LOCATION = "C3T14" !CDS_LOCATION = "C3T14" #SEC = "1" !CDS_SEC = "1";
"A":   PN = "1"  !CDS_PN = "1";
"B":   PN = "2"  !CDS_PN = "2";
BODY = "CAP","I215": #LOCATION = "C3T12" !CDS_LOCATION = "C3T12" #SEC = "1" !CDS_SEC = "1";
"A":   PN = "1"  !CDS_PN = "1";
"B":   PN = "2"  !CDS_PN = "2";
BODY = "CAPP","I217": #LOCATION = "C4T3" !CDS_LOCATION = "C4T3" #SEC = "1" !CDS_SEC = "1";
"A":   PN = "1"  !CDS_PN = "1";
"B":   PN = "2"  !CDS_PN = "2";
BODY = "RES","I218": #LOCATION = "R7F17" !CDS_LOCATION = "R7F17" #SEC = "1" !CDS_SEC = "1";
"A":   PN = "1"  !CDS_PN = "1";
"B":   PN = "2"  !CDS_PN = "2";
BODY = "CAP","I219": #LOCATION = "C7F13" !CDS_LOCATION = "C7F13" #SEC = "1" !CDS_SEC = "1";
"A":   PN = "1"  !CDS_PN = "1";
"B":   PN = "2"  !CDS_PN = "2";
BODY = "RES","I220": #LOCATION = "R7F9" !CDS_LOCATION = "R7F9" #SEC = "1" !CDS_SEC = "1";
"A":   PN = "1"  !CDS_PN = "1";
"B":   PN = "2"  !CDS_PN = "2";
DRAWING = "@baseboard_fab2_lib.baseboard_fab2(sch_1):page232";
BODY = "CAP","I102": #LOCATION = "C4L2" !CDS_LOCATION = "C4L2" &SEC = "1" #&CDS_SEC = "1";
"A":   PN = "1"  !CDS_PN = "1";
"B":   PN = "2"  !CDS_PN = "2";
BODY = "CAP","I104": #LOCATION = "C6A3" !CDS_LOCATION = "C6A3" &SEC = "1" #&CDS_SEC = "1";
"A":   PN = "1"  !CDS_PN = "1";
"B":   PN = "2"  !CDS_PN = "2";
BODY = "CAP","I105": #LOCATION = "C6A2" !CDS_LOCATION = "C6A2" &SEC = "1" #&CDS_SEC = "1";
"A":   PN = "1"  !CDS_PN = "1";
"B":   PN = "2"  !CDS_PN = "2";
BODY = "CAP","I106": #LOCATION = "C4L3" !CDS_LOCATION = "C4L3" &SEC = "1" #&CDS_SEC = "1";
"A":   PN = "1"  !CDS_PN = "1";
"B":   PN = "2"  !CDS_PN = "2";
BODY = "CAP","I108": #LOCATION = "C4L4" !CDS_LOCATION = "C4L4" &SEC = "1" #&CDS_SEC = "1";
"A":   PN = "1"  !CDS_PN = "1";
"B":   PN = "2"  !CDS_PN = "2";
BODY = "CAP","I109": #LOCATION = "C6A7" !CDS_LOCATION = "C6A7" &SEC = "1" #&CDS_SEC = "1";
"A":   PN = "1"  !CDS_PN = "1";
"B":   PN = "2"  !CDS_PN = "2";
BODY = "CAP","I110": #LOCATION = "C6A6" !CDS_LOCATION = "C6A6" &SEC = "1" #&CDS_SEC = "1";
"A":   PN = "1"  !CDS_PN = "1";
"B":   PN = "2"  !CDS_PN = "2";
BODY = "CAP","I111": #LOCATION = "C4M3" !CDS_LOCATION = "C4M3" &SEC = "1" #&CDS_SEC = "1";
"A":   PN = "1"  !CDS_PN = "1";
"B":   PN = "2"  !CDS_PN = "2";
BODY = "CAP","I125": #LOCATION = "C4M4" !CDS_LOCATION = "C4M4" &SEC = "1" #&CDS_SEC = "1";
"A":   PN = "1"  !CDS_PN = "1";
"B":   PN = "2"  !CDS_PN = "2";
BODY = "CAP","I126": #LOCATION = "C6B2" !CDS_LOCATION = "C6B2" &SEC = "1" #&CDS_SEC = "1";
"A":   PN = "1"  !CDS_PN = "1";
"B":   PN = "2"  !CDS_PN = "2";
BODY = "CAP","I128": #LOCATION = "C6B1" !CDS_LOCATION = "C6B1" &SEC = "1" #&CDS_SEC = "1";
"A":   PN = "1"  !CDS_PN = "1";
"B":   PN = "2"  !CDS_PN = "2";
BODY = "CAP","I129": #LOCATION = "C4L1" !CDS_LOCATION = "C4L1" #SEC = "1" !CDS_SEC = "1";
"A":   PN = "1"  !CDS_PN = "1";
"B":   PN = "2"  !CDS_PN = "2";
BODY = "RES","I150": #LOCATION = "R7B20" !CDS_LOCATION = "R7B20" &SEC = "1" #&CDS_SEC = "1";
"A":   PN = "1"  !CDS_PN = "1";
"B":   PN = "2"  !CDS_PN = "2";
BODY = "CAP","I185": #LOCATION = "C7B9" !CDS_LOCATION = "C7B9" &SEC = "1" #&CDS_SEC = "1";
"A":   PN = "1"  !CDS_PN = "1";
"B":   PN = "2"  !CDS_PN = "2";
BODY = "RES","I193": #LOCATION = "R7B14" !CDS_LOCATION = "R7B14" &SEC = "1" #&CDS_SEC = "1";
"A":   PN = "1"  !CDS_PN = "1";
"B":   PN = "2"  !CDS_PN = "2";
BODY = "CAP","I197": #LOCATION = "C7B11" !CDS_LOCATION = "C7B11" #SEC = "1" !CDS_SEC = "1";
"A":   PN = "1"  !CDS_PN = "1";
"B":   PN = "2"  !CDS_PN = "2";
BODY = "FERRITE","I200": #LOCATION = "FB7B1" !CDS_LOCATION = "FB7B1" #SEC = "1" !CDS_SEC = "1";
"A":   PN = "1"  !CDS_PN = "1";
"B":   PN = "2"  !CDS_PN = "2";
BODY = "CAP","I202": #LOCATION = "C7B8" !CDS_LOCATION = "C7B8" &SEC = "1" #&CDS_SEC = "1";
"A":   PN = "1"  !CDS_PN = "1";
"B":   PN = "2"  !CDS_PN = "2";
BODY = "CAP","I207": #LOCATION = "C3M9" !CDS_LOCATION = "C3M9" &SEC = "1" #&CDS_SEC = "1";
"A":   PN = "1"  !CDS_PN = "1";
"B":   PN = "2"  !CDS_PN = "2";
BODY = "CAP","I209": #LOCATION = "C7B12" !CDS_LOCATION = "C7B12" &SEC = "1" #&CDS_SEC = "1";
"A":   PN = "1"  !CDS_PN = "1";
"B":   PN = "2"  !CDS_PN = "2";
BODY = "RES","I210": #LOCATION = "R7B17" !CDS_LOCATION = "R7B17" #SEC = "1" !CDS_SEC = "1";
"A":   PN = "1"  !CDS_PN = "1";
"B":   PN = "2"  !CDS_PN = "2";
BODY = "NCP3232L","I214": #LOCATION = "EU7B1" !CDS_LOCATION = "EU7B1" #SEC = "1" !CDS_SEC = "1";
"AGND":   PN = "5"  !CDS_PN = "5";
"BST":   PN = "36"  !CDS_PN = "36";
"COMP":   PN = "3"  !CDS_PN = "3";
"EN":   PN = "40"  !CDS_PN = "40";
"FB":   PN = "2"  !CDS_PN = "2";
"GND":   PN = "41"  !CDS_PN = "41";
"ISET":   PN = "4"  !CDS_PN = "4";
"OTS":   PN = "6"  !CDS_PN = "6";
"PG":   PN = "7"  !CDS_PN = "7";
"PGND<0>":   PN = "16"  !CDS_PN = "16";
"PGND<1>":   PN = "17"  !CDS_PN = "17";
"PGND<2>":   PN = "18"  !CDS_PN = "18";
"PGND<3>":   PN = "19"  !CDS_PN = "19";
"PGND<4>":   PN = "20"  !CDS_PN = "20";
"PGND<5>":   PN = "21"  !CDS_PN = "21";
"PGND<6>":   PN = "22"  !CDS_PN = "22";
"PGND<7>":   PN = "23"  !CDS_PN = "23";
"PGND<8>":   PN = "24"  !CDS_PN = "24";
"PGND<9>":   PN = "25"  !CDS_PN = "25";
"PGND<10>":   PN = "26"  !CDS_PN = "26";
"PGND<11>":   PN = "27"  !CDS_PN = "27";
"PGND<12>":   PN = "28"  !CDS_PN = "28";
"PGND<13>":   PN = "37"  !CDS_PN = "37";
"SS":   PN = "1"  !CDS_PN = "1";
"VB":   PN = "38"  !CDS_PN = "38";
"VCC":   PN = "39"  !CDS_PN = "39";
"VIN<0>":   PN = "8"  !CDS_PN = "8";
"VIN<1>":   PN = "9"  !CDS_PN = "9";
"VIN<2>":   PN = "10"  !CDS_PN = "10";
"VIN<3>":   PN = "11"  !CDS_PN = "11";
"VIN<4>":   PN = "12"  !CDS_PN = "12";
"VIN<5>":   PN = "13"  !CDS_PN = "13";
"VIN<6>":   PN = "14"  !CDS_PN = "14";
"VIN<7>":   PN = "42"  !CDS_PN = "42";
"VSW":   PN = "35"  !CDS_PN = "35";
"VSWH<0>":   PN = "15"  !CDS_PN = "15";
"VSWH<1>":   PN = "29"  !CDS_PN = "29";
"VSWH<2>":   PN = "30"  !CDS_PN = "30";
"VSWH<3>":   PN = "31"  !CDS_PN = "31";
"VSWH<4>":   PN = "32"  !CDS_PN = "32";
"VSWH<5>":   PN = "33"  !CDS_PN = "33";
"VSWH<6>":   PN = "34"  !CDS_PN = "34";
"VSWH<7>":   PN = "43"  !CDS_PN = "43";
BODY = "RES","I218": #LOCATION = "R7A15" !CDS_LOCATION = "R7A15" #SEC = "1" !CDS_SEC = "1";
"A":   PN = "1"  !CDS_PN = "1";
"B":   PN = "2"  !CDS_PN = "2";
BODY = "CAP","I220": #LOCATION = "C7A34" !CDS_LOCATION = "C7A34" #SEC = "1" !CDS_SEC = "1";
"A":   PN = "1"  !CDS_PN = "1";
"B":   PN = "2"  !CDS_PN = "2";
BODY = "RES","I227": #LOCATION = "R7B10" !CDS_LOCATION = "R7B10" #SEC = "1" !CDS_SEC = "1";
"A":   PN = "1"  !CDS_PN = "1";
"B":   PN = "2"  !CDS_PN = "2";
BODY = "CAPP","I229": #LOCATION = "C6B7" !CDS_LOCATION = "C6B7" &SEC = "1" #&CDS_SEC = "1";
"A":   PN = "1"  !CDS_PN = "1";
"B":   PN = "2"  !CDS_PN = "2";
BODY = "CAP","I236": #LOCATION = "C6B3" !CDS_LOCATION = "C6B3" &SEC = "1" #&CDS_SEC = "1";
"A":   PN = "1"  !CDS_PN = "1";
"B":   PN = "2"  !CDS_PN = "2";
BODY = "CAP","I238": #LOCATION = "C7B7" !CDS_LOCATION = "C7B7" &SEC = "1" #&CDS_SEC = "1";
"A":   PN = "1"  !CDS_PN = "1";
"B":   PN = "2"  !CDS_PN = "2";
BODY = "INDUCTOR","I239": #LOCATION = "L7B1" !CDS_LOCATION = "L7B1" &SEC = "1" #&CDS_SEC = "1";
"INA":   PN = "1"  !CDS_PN = "1";
"INB":   PN = "2"  !CDS_PN = "2";
BODY = "RES","I240": #LOCATION = "R7B19" !CDS_LOCATION = "R7B19" &SEC = "1" #&CDS_SEC = "1";
"A":   PN = "1"  !CDS_PN = "1";
"B":   PN = "2"  !CDS_PN = "2";
BODY = "CAP","I241": #LOCATION = "C7B30" !CDS_LOCATION = "C7B30" &SEC = "1" #&CDS_SEC = "1";
"A":   PN = "1"  !CDS_PN = "1";
"B":   PN = "2"  !CDS_PN = "2";
BODY = "CAP_A","I252": #LOCATION = "C7B6" !CDS_LOCATION = "C7B6" #SEC = "1" !CDS_SEC = "1";
"A":   PN = "1"  !CDS_PN = "1";
"B":   PN = "2"  !CDS_PN = "2";
BODY = "CAP","I253": #LOCATION = "C3M10" !CDS_LOCATION = "C3M10" #SEC = "1" !CDS_SEC = "1";
"A":   PN = "1"  !CDS_PN = "1";
"B":   PN = "2"  !CDS_PN = "2";
BODY = "RES","I257": #LOCATION = "R7B12" !CDS_LOCATION = "R7B12" #SEC = "1" !CDS_SEC = "1";
"A":   PN = "1"  !CDS_PN = "1";
"B":   PN = "2"  !CDS_PN = "2";
BODY = "CAP","I259": #LOCATION = "C3M8" !CDS_LOCATION = "C3M8" #SEC = "1" !CDS_SEC = "1";
"A":   PN = "1"  !CDS_PN = "1";
"B":   PN = "2"  !CDS_PN = "2";
BODY = "CAP","I260": #LOCATION = "C3M15" !CDS_LOCATION = "C3M15" #SEC = "1" !CDS_SEC = "1";
"A":   PN = "1"  !CDS_PN = "1";
"B":   PN = "2"  !CDS_PN = "2";
BODY = "CAP","I261": #LOCATION = "C3M16" !CDS_LOCATION = "C3M16" #SEC = "1" !CDS_SEC = "1";
"A":   PN = "1"  !CDS_PN = "1";
"B":   PN = "2"  !CDS_PN = "2";
BODY = "CAP","I262": #LOCATION = "C7B5" !CDS_LOCATION = "C7B5" #SEC = "1" !CDS_SEC = "1";
"A":   PN = "1"  !CDS_PN = "1";
"B":   PN = "2"  !CDS_PN = "2";
BODY = "CAPP","I267": #LOCATION = "C4M1" !CDS_LOCATION = "C4M1" #SEC = "1" !CDS_SEC = "1";
"A":   PN = "1"  !CDS_PN = "1";
"B":   PN = "2"  !CDS_PN = "2";
BODY = "RES","I298": #LOCATION = "R7B18" !CDS_LOCATION = "R7B18" #SEC = "1" !CDS_SEC = "1";
"A":   PN = "1"  !CDS_PN = "1";
"B":   PN = "2"  !CDS_PN = "2";
BODY = "RES","I299": #LOCATION = "R7B11" !CDS_LOCATION = "R7B11" #SEC = "1" !CDS_SEC = "1";
"A":   PN = "1"  !CDS_PN = "1";
"B":   PN = "2"  !CDS_PN = "2";
BODY = "RES","I300": #LOCATION = "R7B16" !CDS_LOCATION = "R7B16" #SEC = "1" !CDS_SEC = "1";
"A":   PN = "1"  !CDS_PN = "1";
"B":   PN = "2"  !CDS_PN = "2";
BODY = "CAP","I301": #LOCATION = "C7B10" !CDS_LOCATION = "C7B10" #SEC = "1" !CDS_SEC = "1";
"A":   PN = "1"  !CDS_PN = "1";
"B":   PN = "2"  !CDS_PN = "2";
BODY = "CAP","I302": #LOCATION = "C7B13" !CDS_LOCATION = "C7B13" #SEC = "1" !CDS_SEC = "1";
"A":   PN = "1"  !CDS_PN = "1";
"B":   PN = "2"  !CDS_PN = "2";
BODY = "RES","I303": #LOCATION = "R7B15" !CDS_LOCATION = "R7B15" &SEC = "1" #&CDS_SEC = "1";
"A":   PN = "1"  !CDS_PN = "1";
"B":   PN = "2"  !CDS_PN = "2";
BODY = "RES","I304": #LOCATION = "R7B13" !CDS_LOCATION = "R7B13" &SEC = "1" #&CDS_SEC = "1";
"A":   PN = "1"  !CDS_PN = "1";
"B":   PN = "2"  !CDS_PN = "2";
BODY = "CAP","I306": #LOCATION = "C7B14" !CDS_LOCATION = "C7B14" #SEC = "1" !CDS_SEC = "1";
"A":   PN = "1"  !CDS_PN = "1";
"B":   PN = "2"  !CDS_PN = "2";
BODY = "RES","I307": #LOCATION = "R7B9" !CDS_LOCATION = "R7B9" #SEC = "1" !CDS_SEC = "1";
"A":   PN = "1"  !CDS_PN = "1";
"B":   PN = "2"  !CDS_PN = "2";
DRAWING = "@baseboard_fab2_lib.baseboard_fab2(sch_1):page233";
BODY = "CAP","I109": #LOCATION = "C7U4" !CDS_LOCATION = "C7U4" &SEC = "1" #&CDS_SEC = "1";
"A":   PN = "1"  !CDS_PN = "1";
"B":   PN = "2"  !CDS_PN = "2";
BODY = "CAP","I111": #LOCATION = "C7U5" !CDS_LOCATION = "C7U5" &SEC = "1" #&CDS_SEC = "1";
"A":   PN = "1"  !CDS_PN = "1";
"B":   PN = "2"  !CDS_PN = "2";
BODY = "CAP","I112": #LOCATION = "C7T2" !CDS_LOCATION = "C7T2" &SEC = "1" #&CDS_SEC = "1";
"A":   PN = "1"  !CDS_PN = "1";
"B":   PN = "2"  !CDS_PN = "2";
BODY = "CAP","I113": #LOCATION = "C7T3" !CDS_LOCATION = "C7T3" &SEC = "1" #&CDS_SEC = "1";
"A":   PN = "1"  !CDS_PN = "1";
"B":   PN = "2"  !CDS_PN = "2";
BODY = "CAP","I115": #LOCATION = "C7U6" !CDS_LOCATION = "C7U6" &SEC = "1" #&CDS_SEC = "1";
"A":   PN = "1"  !CDS_PN = "1";
"B":   PN = "2"  !CDS_PN = "2";
BODY = "CAP","I116": #LOCATION = "C3F3" !CDS_LOCATION = "C3F3" &SEC = "1" #&CDS_SEC = "1";
"A":   PN = "1"  !CDS_PN = "1";
"B":   PN = "2"  !CDS_PN = "2";
BODY = "CAP","I117": #LOCATION = "C3F4" !CDS_LOCATION = "C3F4" &SEC = "1" #&CDS_SEC = "1";
"A":   PN = "1"  !CDS_PN = "1";
"B":   PN = "2"  !CDS_PN = "2";
BODY = "CAP","I118": #LOCATION = "C3G3" !CDS_LOCATION = "C3G3" &SEC = "1" #&CDS_SEC = "1";
"A":   PN = "1"  !CDS_PN = "1";
"B":   PN = "2"  !CDS_PN = "2";
BODY = "CAP","I132": #LOCATION = "C3G7" !CDS_LOCATION = "C3G7" &SEC = "1" #&CDS_SEC = "1";
"A":   PN = "1"  !CDS_PN = "1";
"B":   PN = "2"  !CDS_PN = "2";
BODY = "CAP","I133": #LOCATION = "C3G4" !CDS_LOCATION = "C3G4" &SEC = "1" #&CDS_SEC = "1";
"A":   PN = "1"  !CDS_PN = "1";
"B":   PN = "2"  !CDS_PN = "2";
BODY = "CAP","I135": #LOCATION = "C3G8" !CDS_LOCATION = "C3G8" &SEC = "1" #&CDS_SEC = "1";
"A":   PN = "1"  !CDS_PN = "1";
"B":   PN = "2"  !CDS_PN = "2";
BODY = "CAP","I136": #LOCATION = "C7U3" !CDS_LOCATION = "C7U3" #SEC = "1" !CDS_SEC = "1";
"A":   PN = "1"  !CDS_PN = "1";
"B":   PN = "2"  !CDS_PN = "2";
BODY = "RES","I157": #LOCATION = "R4G25" !CDS_LOCATION = "R4G25" &SEC = "1" #&CDS_SEC = "1";
"A":   PN = "1"  !CDS_PN = "1";
"B":   PN = "2"  !CDS_PN = "2";
BODY = "RES","I182": #LOCATION = "R4G5" !CDS_LOCATION = "R4G5" &SEC = "1" #&CDS_SEC = "1";
"A":   PN = "1"  !CDS_PN = "1";
"B":   PN = "2"  !CDS_PN = "2";
BODY = "CAP","I183": #LOCATION = "C4G7" !CDS_LOCATION = "C4G7" &SEC = "1" #&CDS_SEC = "1";
"A":   PN = "1"  !CDS_PN = "1";
"B":   PN = "2"  !CDS_PN = "2";
BODY = "RES","I184": #LOCATION = "R4G11" !CDS_LOCATION = "R4G11" #SEC = "1" !CDS_SEC = "1";
"A":   PN = "1"  !CDS_PN = "1";
"B":   PN = "2"  !CDS_PN = "2";
BODY = "RES","I185": #LOCATION = "R4G14" !CDS_LOCATION = "R4G14" #SEC = "1" !CDS_SEC = "1";
"A":   PN = "1"  !CDS_PN = "1";
"B":   PN = "2"  !CDS_PN = "2";
BODY = "CAP","I187": #LOCATION = "C6U6" !CDS_LOCATION = "C6U6" #SEC = "1" !CDS_SEC = "1";
"A":   PN = "1"  !CDS_PN = "1";
"B":   PN = "2"  !CDS_PN = "2";
BODY = "CAP","I189": #LOCATION = "C4G5" !CDS_LOCATION = "C4G5" &SEC = "1" #&CDS_SEC = "1";
"A":   PN = "1"  !CDS_PN = "1";
"B":   PN = "2"  !CDS_PN = "2";
BODY = "CAP","I194": #LOCATION = "C4G8" !CDS_LOCATION = "C4G8" #SEC = "1" !CDS_SEC = "1";
"A":   PN = "1"  !CDS_PN = "1";
"B":   PN = "2"  !CDS_PN = "2";
BODY = "CAP","I196": #LOCATION = "C4G4" !CDS_LOCATION = "C4G4" &SEC = "1" #&CDS_SEC = "1";
"A":   PN = "1"  !CDS_PN = "1";
"B":   PN = "2"  !CDS_PN = "2";
BODY = "FERRITE","I198": #LOCATION = "FB4G1" !CDS_LOCATION = "FB4G1" #SEC = "1" !CDS_SEC = "1";
"A":   PN = "1"  !CDS_PN = "1";
"B":   PN = "2"  !CDS_PN = "2";
BODY = "RES","I199": #LOCATION = "R4G24" !CDS_LOCATION = "R4G24" &SEC = "1" #&CDS_SEC = "1";
"A":   PN = "1"  !CDS_PN = "1";
"B":   PN = "2"  !CDS_PN = "2";
BODY = "CAP","I201": #LOCATION = "C4G9" !CDS_LOCATION = "C4G9" &SEC = "1" #&CDS_SEC = "1";
"A":   PN = "1"  !CDS_PN = "1";
"B":   PN = "2"  !CDS_PN = "2";
BODY = "RES","I208": #LOCATION = "R4F6" !CDS_LOCATION = "R4F6" &SEC = "1" #&CDS_SEC = "1";
"A":   PN = "1"  !CDS_PN = "1";
"B":   PN = "2"  !CDS_PN = "2";
BODY = "CAP","I209": #LOCATION = "C4F12" !CDS_LOCATION = "C4F12" &SEC = "1" #&CDS_SEC = "1";
"A":   PN = "1"  !CDS_PN = "1";
"B":   PN = "2"  !CDS_PN = "2";
BODY = "RES","I211": #LOCATION = "R4G6" !CDS_LOCATION = "R4G6" &SEC = "1" #&CDS_SEC = "1";
"A":   PN = "1"  !CDS_PN = "1";
"B":   PN = "2"  !CDS_PN = "2";
BODY = "CAPP","I217": #LOCATION = "C4F7" !CDS_LOCATION = "C4F7" &SEC = "1" #&CDS_SEC = "1";
"A":   PN = "1"  !CDS_PN = "1";
"B":   PN = "2"  !CDS_PN = "2";
BODY = "CAP","I221": #LOCATION = "C6U3" !CDS_LOCATION = "C6U3" &SEC = "1" #&CDS_SEC = "1";
"A":   PN = "1"  !CDS_PN = "1";
"B":   PN = "2"  !CDS_PN = "2";
BODY = "CAP","I223": #LOCATION = "C6U2" !CDS_LOCATION = "C6U2" &SEC = "1" #&CDS_SEC = "1";
"A":   PN = "1"  !CDS_PN = "1";
"B":   PN = "2"  !CDS_PN = "2";
BODY = "CAP","I224": #LOCATION = "C4G26" !CDS_LOCATION = "C4G26" &SEC = "1" #&CDS_SEC = "1";
"A":   PN = "1"  !CDS_PN = "1";
"B":   PN = "2"  !CDS_PN = "2";
BODY = "NCP3232L","I225": #LOCATION = "EU4G1" !CDS_LOCATION = "EU4G1" #SEC = "1" !CDS_SEC = "1";
"AGND":   PN = "5"  !CDS_PN = "5";
"BST":   PN = "36"  !CDS_PN = "36";
"COMP":   PN = "3"  !CDS_PN = "3";
"EN":   PN = "40"  !CDS_PN = "40";
"FB":   PN = "2"  !CDS_PN = "2";
"GND":   PN = "41"  !CDS_PN = "41";
"ISET":   PN = "4"  !CDS_PN = "4";
"OTS":   PN = "6"  !CDS_PN = "6";
"PG":   PN = "7"  !CDS_PN = "7";
"PGND<0>":   PN = "16"  !CDS_PN = "16";
"PGND<1>":   PN = "17"  !CDS_PN = "17";
"PGND<2>":   PN = "18"  !CDS_PN = "18";
"PGND<3>":   PN = "19"  !CDS_PN = "19";
"PGND<4>":   PN = "20"  !CDS_PN = "20";
"PGND<5>":   PN = "21"  !CDS_PN = "21";
"PGND<6>":   PN = "22"  !CDS_PN = "22";
"PGND<7>":   PN = "23"  !CDS_PN = "23";
"PGND<8>":   PN = "24"  !CDS_PN = "24";
"PGND<9>":   PN = "25"  !CDS_PN = "25";
"PGND<10>":   PN = "26"  !CDS_PN = "26";
"PGND<11>":   PN = "27"  !CDS_PN = "27";
"PGND<12>":   PN = "28"  !CDS_PN = "28";
"PGND<13>":   PN = "37"  !CDS_PN = "37";
"SS":   PN = "1"  !CDS_PN = "1";
"VB":   PN = "38"  !CDS_PN = "38";
"VCC":   PN = "39"  !CDS_PN = "39";
"VIN<0>":   PN = "8"  !CDS_PN = "8";
"VIN<1>":   PN = "9"  !CDS_PN = "9";
"VIN<2>":   PN = "10"  !CDS_PN = "10";
"VIN<3>":   PN = "11"  !CDS_PN = "11";
"VIN<4>":   PN = "12"  !CDS_PN = "12";
"VIN<5>":   PN = "13"  !CDS_PN = "13";
"VIN<6>":   PN = "14"  !CDS_PN = "14";
"VIN<7>":   PN = "42"  !CDS_PN = "42";
"VSW":   PN = "35"  !CDS_PN = "35";
"VSWH<0>":   PN = "15"  !CDS_PN = "15";
"VSWH<1>":   PN = "29"  !CDS_PN = "29";
"VSWH<2>":   PN = "30"  !CDS_PN = "30";
"VSWH<3>":   PN = "31"  !CDS_PN = "31";
"VSWH<4>":   PN = "32"  !CDS_PN = "32";
"VSWH<5>":   PN = "33"  !CDS_PN = "33";
"VSWH<6>":   PN = "34"  !CDS_PN = "34";
"VSWH<7>":   PN = "43"  !CDS_PN = "43";
BODY = "CAP_A","I242": #LOCATION = "C6U5" !CDS_LOCATION = "C6U5" #SEC = "1" !CDS_SEC = "1";
"A":   PN = "1"  !CDS_PN = "1";
"B":   PN = "2"  !CDS_PN = "2";
BODY = "RES","I247": #LOCATION = "R4G12" !CDS_LOCATION = "R4G12" #SEC = "1" !CDS_SEC = "1";
"A":   PN = "1"  !CDS_PN = "1";
"B":   PN = "2"  !CDS_PN = "2";
BODY = "CAP","I248": #LOCATION = "C6U4" !CDS_LOCATION = "C6U4" #SEC = "1" !CDS_SEC = "1";
"A":   PN = "1"  !CDS_PN = "1";
"B":   PN = "2"  !CDS_PN = "2";
BODY = "CAP","I253": #LOCATION = "C4G2" !CDS_LOCATION = "C4G2" #SEC = "1" !CDS_SEC = "1";
"A":   PN = "1"  !CDS_PN = "1";
"B":   PN = "2"  !CDS_PN = "2";
BODY = "CAP","I254": #LOCATION = "C6U7" !CDS_LOCATION = "C6U7" #SEC = "1" !CDS_SEC = "1";
"A":   PN = "1"  !CDS_PN = "1";
"B":   PN = "2"  !CDS_PN = "2";
BODY = "CAP","I255": #LOCATION = "C6U8" !CDS_LOCATION = "C6U8" #SEC = "1" !CDS_SEC = "1";
"A":   PN = "1"  !CDS_PN = "1";
"B":   PN = "2"  !CDS_PN = "2";
BODY = "CAPP","I256": #LOCATION = "C4F11" !CDS_LOCATION = "C4F11" #SEC = "1" !CDS_SEC = "1";
"A":   PN = "1"  !CDS_PN = "1";
"B":   PN = "2"  !CDS_PN = "2";
BODY = "RES","I266": #LOCATION = "R4G10" !CDS_LOCATION = "R4G10" #SEC = "1" !CDS_SEC = "1";
"A":   PN = "1"  !CDS_PN = "1";
"B":   PN = "2"  !CDS_PN = "2";
BODY = "CAP","I267": #LOCATION = "C4G11" !CDS_LOCATION = "C4G11" #SEC = "1" !CDS_SEC = "1";
"A":   PN = "1"  !CDS_PN = "1";
"B":   PN = "2"  !CDS_PN = "2";
BODY = "RES","I269": #LOCATION = "R4G9" !CDS_LOCATION = "R4G9" &SEC = "1" #&CDS_SEC = "1";
"A":   PN = "1"  !CDS_PN = "1";
"B":   PN = "2"  !CDS_PN = "2";
BODY = "RES","I270": #LOCATION = "R4G7" !CDS_LOCATION = "R4G7" &SEC = "1" #&CDS_SEC = "1";
"A":   PN = "1"  !CDS_PN = "1";
"B":   PN = "2"  !CDS_PN = "2";
BODY = "RES","I271": #LOCATION = "R4G8" !CDS_LOCATION = "R4G8" #SEC = "1" !CDS_SEC = "1";
"A":   PN = "1"  !CDS_PN = "1";
"B":   PN = "2"  !CDS_PN = "2";
BODY = "RES","I272": #LOCATION = "R4G13" !CDS_LOCATION = "R4G13" #SEC = "1" !CDS_SEC = "1";
"A":   PN = "1"  !CDS_PN = "1";
"B":   PN = "2"  !CDS_PN = "2";
BODY = "CAP","I273": #LOCATION = "C4G6" !CDS_LOCATION = "C4G6" #SEC = "1" !CDS_SEC = "1";
"A":   PN = "1"  !CDS_PN = "1";
"B":   PN = "2"  !CDS_PN = "2";
BODY = "CAP","I274": #LOCATION = "C4G10" !CDS_LOCATION = "C4G10" #SEC = "1" !CDS_SEC = "1";
"A":   PN = "1"  !CDS_PN = "1";
"B":   PN = "2"  !CDS_PN = "2";
BODY = "RES","I275": #LOCATION = "R4G4" !CDS_LOCATION = "R4G4" #SEC = "1" !CDS_SEC = "1";
"A":   PN = "1"  !CDS_PN = "1";
"B":   PN = "2"  !CDS_PN = "2";
BODY = "INDUCTOR","I277": #LOCATION = "L4G1" !CDS_LOCATION = "L4G1" #SEC = "1" !CDS_SEC = "1";
"INA":   PN = "1"  !CDS_PN = "1";
"INB":   PN = "2"  !CDS_PN = "2";
DRAWING = "@baseboard_fab2_lib.baseboard_fab2(sch_1):page234";
BODY = "RES","I29": #LOCATION = "R4B14" !CDS_LOCATION = "R4B14" &SEC = "1" #&CDS_SEC = "1";
"A":   PN = "1"  !CDS_PN = "1";
"B":   PN = "2"  !CDS_PN = "2";
BODY = "CAP","I84": #LOCATION = "C3B2" !CDS_LOCATION = "C3B2" #SEC = "1" !CDS_SEC = "1";
"A":   PN = "1"  !CDS_PN = "1";
"B":   PN = "2"  !CDS_PN = "2";
BODY = "CAP","I86": #LOCATION = "C3A8" !CDS_LOCATION = "C3A8" &SEC = "1" #&CDS_SEC = "1";
"A":   PN = "1"  !CDS_PN = "1";
"B":   PN = "2"  !CDS_PN = "2";
BODY = "CAP","I87": #LOCATION = "C7L3" !CDS_LOCATION = "C7L3" &SEC = "1" #&CDS_SEC = "1";
"A":   PN = "1"  !CDS_PN = "1";
"B":   PN = "2"  !CDS_PN = "2";
BODY = "CAP","I88": #LOCATION = "C7L2" !CDS_LOCATION = "C7L2" &SEC = "1" #&CDS_SEC = "1";
"A":   PN = "1"  !CDS_PN = "1";
"B":   PN = "2"  !CDS_PN = "2";
BODY = "CAP","I89": #LOCATION = "C7L7" !CDS_LOCATION = "C7L7" &SEC = "1" #&CDS_SEC = "1";
"A":   PN = "1"  !CDS_PN = "1";
"B":   PN = "2"  !CDS_PN = "2";
BODY = "CAP","I90": #LOCATION = "C7L6" !CDS_LOCATION = "C7L6" &SEC = "1" #&CDS_SEC = "1";
"A":   PN = "1"  !CDS_PN = "1";
"B":   PN = "2"  !CDS_PN = "2";
BODY = "CAP","I91": #LOCATION = "C7M4" !CDS_LOCATION = "C7M4" &SEC = "1" #&CDS_SEC = "1";
"A":   PN = "1"  !CDS_PN = "1";
"B":   PN = "2"  !CDS_PN = "2";
BODY = "CAP","I92": #LOCATION = "C7M3" !CDS_LOCATION = "C7M3" &SEC = "1" #&CDS_SEC = "1";
"A":   PN = "1"  !CDS_PN = "1";
"B":   PN = "2"  !CDS_PN = "2";
BODY = "CAP","I93": #LOCATION = "C3A4" !CDS_LOCATION = "C3A4" &SEC = "1" #&CDS_SEC = "1";
"A":   PN = "1"  !CDS_PN = "1";
"B":   PN = "2"  !CDS_PN = "2";
BODY = "CAP","I94": #LOCATION = "C3B1" !CDS_LOCATION = "C3B1" &SEC = "1" #&CDS_SEC = "1";
"A":   PN = "1"  !CDS_PN = "1";
"B":   PN = "2"  !CDS_PN = "2";
BODY = "CAP","I95": #LOCATION = "C3A7" !CDS_LOCATION = "C3A7" &SEC = "1" #&CDS_SEC = "1";
"A":   PN = "1"  !CDS_PN = "1";
"B":   PN = "2"  !CDS_PN = "2";
BODY = "CAP","I97": #LOCATION = "C3A3" !CDS_LOCATION = "C3A3" &SEC = "1" #&CDS_SEC = "1";
"A":   PN = "1"  !CDS_PN = "1";
"B":   PN = "2"  !CDS_PN = "2";
BODY = "CAP","I129": #LOCATION = "C4B5" !CDS_LOCATION = "C4B5" &SEC = "1" #&CDS_SEC = "1";
"A":   PN = "1"  !CDS_PN = "1";
"B":   PN = "2"  !CDS_PN = "2";
BODY = "CAP","I130": #LOCATION = "C4B1" !CDS_LOCATION = "C4B1" &SEC = "1" #&CDS_SEC = "1";
"A":   PN = "1"  !CDS_PN = "1";
"B":   PN = "2"  !CDS_PN = "2";
BODY = "CAP","I139": #LOCATION = "C4B8" !CDS_LOCATION = "C4B8" &SEC = "1" #&CDS_SEC = "1";
"A":   PN = "1"  !CDS_PN = "1";
"B":   PN = "2"  !CDS_PN = "2";
BODY = "RES","I140": #LOCATION = "R4B6" !CDS_LOCATION = "R4B6" #SEC = "1" !CDS_SEC = "1";
"A":   PN = "1"  !CDS_PN = "1";
"B":   PN = "2"  !CDS_PN = "2";
BODY = "RES","I143": #LOCATION = "R4B10" !CDS_LOCATION = "R4B10" #SEC = "1" !CDS_SEC = "1";
"A":   PN = "1"  !CDS_PN = "1";
"B":   PN = "2"  !CDS_PN = "2";
BODY = "CAP","I144": #LOCATION = "C6L12" !CDS_LOCATION = "C6L12" #SEC = "1" !CDS_SEC = "1";
"A":   PN = "1"  !CDS_PN = "1";
"B":   PN = "2"  !CDS_PN = "2";
BODY = "CAP","I146": #LOCATION = "C4B6" !CDS_LOCATION = "C4B6" #SEC = "1" !CDS_SEC = "1";
"A":   PN = "1"  !CDS_PN = "1";
"B":   PN = "2"  !CDS_PN = "2";
BODY = "CAP","I152": #LOCATION = "C6L11" !CDS_LOCATION = "C6L11" &SEC = "1" #&CDS_SEC = "1";
"A":   PN = "1"  !CDS_PN = "1";
"B":   PN = "2"  !CDS_PN = "2";
BODY = "FERRITE","I154": #LOCATION = "FB4A1" !CDS_LOCATION = "FB4A1" #SEC = "1" !CDS_SEC = "1";
"A":   PN = "1"  !CDS_PN = "1";
"B":   PN = "2"  !CDS_PN = "2";
BODY = "RES","I155": #LOCATION = "R4B13" !CDS_LOCATION = "R4B13" &SEC = "1" #&CDS_SEC = "1";
"A":   PN = "1"  !CDS_PN = "1";
"B":   PN = "2"  !CDS_PN = "2";
BODY = "RES","I162": #LOCATION = "R4A7" !CDS_LOCATION = "R4A7" &SEC = "1" #&CDS_SEC = "1";
"A":   PN = "1"  !CDS_PN = "1";
"B":   PN = "2"  !CDS_PN = "2";
BODY = "CAP","I163": #LOCATION = "C4A16" !CDS_LOCATION = "C4A16" &SEC = "1" #&CDS_SEC = "1";
"A":   PN = "1"  !CDS_PN = "1";
"B":   PN = "2"  !CDS_PN = "2";
BODY = "INDUCTOR","I164": #LOCATION = "L4A1" !CDS_LOCATION = "L4A1" &SEC = "1" #&CDS_SEC = "1";
"INA":   PN = "1"  !CDS_PN = "1";
"INB":   PN = "2"  !CDS_PN = "2";
BODY = "CAPP","I167": #LOCATION = "C3B3" !CDS_LOCATION = "C3B3" &SEC = "1" #&CDS_SEC = "1";
"A":   PN = "1"  !CDS_PN = "1";
"B":   PN = "2"  !CDS_PN = "2";
BODY = "CAP","I177": #LOCATION = "C4B3" !CDS_LOCATION = "C4B3" &SEC = "1" #&CDS_SEC = "1";
"A":   PN = "1"  !CDS_PN = "1";
"B":   PN = "2"  !CDS_PN = "2";
BODY = "CAP","I180": #LOCATION = "C4B2" !CDS_LOCATION = "C4B2" &SEC = "1" #&CDS_SEC = "1";
"A":   PN = "1"  !CDS_PN = "1";
"B":   PN = "2"  !CDS_PN = "2";
BODY = "CAP","I182": #LOCATION = "C4B15" !CDS_LOCATION = "C4B15" &SEC = "1" #&CDS_SEC = "1";
"A":   PN = "1"  !CDS_PN = "1";
"B":   PN = "2"  !CDS_PN = "2";
BODY = "RES","I183": #LOCATION = "R4B2" !CDS_LOCATION = "R4B2" &SEC = "1" #&CDS_SEC = "1";
"A":   PN = "1"  !CDS_PN = "1";
"B":   PN = "2"  !CDS_PN = "2";
BODY = "NCP3232L","I184": #LOCATION = "EU4A3" !CDS_LOCATION = "EU4A3" #SEC = "1" !CDS_SEC = "1";
"AGND":   PN = "5"  !CDS_PN = "5";
"BST":   PN = "36"  !CDS_PN = "36";
"COMP":   PN = "3"  !CDS_PN = "3";
"EN":   PN = "40"  !CDS_PN = "40";
"FB":   PN = "2"  !CDS_PN = "2";
"GND":   PN = "41"  !CDS_PN = "41";
"ISET":   PN = "4"  !CDS_PN = "4";
"OTS":   PN = "6"  !CDS_PN = "6";
"PG":   PN = "7"  !CDS_PN = "7";
"PGND<0>":   PN = "16"  !CDS_PN = "16";
"PGND<1>":   PN = "17"  !CDS_PN = "17";
"PGND<2>":   PN = "18"  !CDS_PN = "18";
"PGND<3>":   PN = "19"  !CDS_PN = "19";
"PGND<4>":   PN = "20"  !CDS_PN = "20";
"PGND<5>":   PN = "21"  !CDS_PN = "21";
"PGND<6>":   PN = "22"  !CDS_PN = "22";
"PGND<7>":   PN = "23"  !CDS_PN = "23";
"PGND<8>":   PN = "24"  !CDS_PN = "24";
"PGND<9>":   PN = "25"  !CDS_PN = "25";
"PGND<10>":   PN = "26"  !CDS_PN = "26";
"PGND<11>":   PN = "27"  !CDS_PN = "27";
"PGND<12>":   PN = "28"  !CDS_PN = "28";
"PGND<13>":   PN = "37"  !CDS_PN = "37";
"SS":   PN = "1"  !CDS_PN = "1";
"VB":   PN = "38"  !CDS_PN = "38";
"VCC":   PN = "39"  !CDS_PN = "39";
"VIN<0>":   PN = "8"  !CDS_PN = "8";
"VIN<1>":   PN = "9"  !CDS_PN = "9";
"VIN<2>":   PN = "10"  !CDS_PN = "10";
"VIN<3>":   PN = "11"  !CDS_PN = "11";
"VIN<4>":   PN = "12"  !CDS_PN = "12";
"VIN<5>":   PN = "13"  !CDS_PN = "13";
"VIN<6>":   PN = "14"  !CDS_PN = "14";
"VIN<7>":   PN = "42"  !CDS_PN = "42";
"VSW":   PN = "35"  !CDS_PN = "35";
"VSWH<0>":   PN = "15"  !CDS_PN = "15";
"VSWH<1>":   PN = "29"  !CDS_PN = "29";
"VSWH<2>":   PN = "30"  !CDS_PN = "30";
"VSWH<3>":   PN = "31"  !CDS_PN = "31";
"VSWH<4>":   PN = "32"  !CDS_PN = "32";
"VSWH<5>":   PN = "33"  !CDS_PN = "33";
"VSWH<6>":   PN = "34"  !CDS_PN = "34";
"VSWH<7>":   PN = "43"  !CDS_PN = "43";
BODY = "CAP_A","I199": #LOCATION = "C4A20" !CDS_LOCATION = "C4A20" #SEC = "1" !CDS_SEC = "1";
"A":   PN = "1"  !CDS_PN = "1";
"B":   PN = "2"  !CDS_PN = "2";
BODY = "RES","I201": #LOCATION = "R4B7" !CDS_LOCATION = "R4B7" #SEC = "1" !CDS_SEC = "1";
"A":   PN = "1"  !CDS_PN = "1";
"B":   PN = "2"  !CDS_PN = "2";
BODY = "CAP","I202": #LOCATION = "C6L10" !CDS_LOCATION = "C6L10" #SEC = "1" !CDS_SEC = "1";
"A":   PN = "1"  !CDS_PN = "1";
"B":   PN = "2"  !CDS_PN = "2";
BODY = "CAP","I203": #LOCATION = "C6M3" !CDS_LOCATION = "C6M3" #SEC = "1" !CDS_SEC = "1";
"A":   PN = "1"  !CDS_PN = "1";
"B":   PN = "2"  !CDS_PN = "2";
BODY = "CAP","I204": #LOCATION = "C6M5" !CDS_LOCATION = "C6M5" #SEC = "1" !CDS_SEC = "1";
"A":   PN = "1"  !CDS_PN = "1";
"B":   PN = "2"  !CDS_PN = "2";
BODY = "CAP","I205": #LOCATION = "C4A19" !CDS_LOCATION = "C4A19" #SEC = "1" !CDS_SEC = "1";
"A":   PN = "1"  !CDS_PN = "1";
"B":   PN = "2"  !CDS_PN = "2";
BODY = "CAPP","I210": #LOCATION = "C6L8" !CDS_LOCATION = "C6L8" #SEC = "1" !CDS_SEC = "1";
"A":   PN = "1"  !CDS_PN = "1";
"B":   PN = "2"  !CDS_PN = "2";
BODY = "CAP","I211": #LOCATION = "C4B9" !CDS_LOCATION = "C4B9" #SEC = "1" !CDS_SEC = "1";
"A":   PN = "1"  !CDS_PN = "1";
"B":   PN = "2"  !CDS_PN = "2";
BODY = "CAP","I212": #LOCATION = "C4B4" !CDS_LOCATION = "C4B4" #SEC = "1" !CDS_SEC = "1";
"A":   PN = "1"  !CDS_PN = "1";
"B":   PN = "2"  !CDS_PN = "2";
BODY = "RES","I213": #LOCATION = "R4B8" !CDS_LOCATION = "R4B8" #SEC = "1" !CDS_SEC = "1";
"A":   PN = "1"  !CDS_PN = "1";
"B":   PN = "2"  !CDS_PN = "2";
BODY = "RES","I214": #LOCATION = "R4B3" !CDS_LOCATION = "R4B3" #SEC = "1" !CDS_SEC = "1";
"A":   PN = "1"  !CDS_PN = "1";
"B":   PN = "2"  !CDS_PN = "2";
BODY = "RES","I215": #LOCATION = "R4B5" !CDS_LOCATION = "R4B5" &SEC = "1" #&CDS_SEC = "1";
"A":   PN = "1"  !CDS_PN = "1";
"B":   PN = "2"  !CDS_PN = "2";
BODY = "RES","I216": #LOCATION = "R4B4" !CDS_LOCATION = "R4B4" &SEC = "1" #&CDS_SEC = "1";
"A":   PN = "1"  !CDS_PN = "1";
"B":   PN = "2"  !CDS_PN = "2";
BODY = "CAP","I218": #LOCATION = "C4B7" !CDS_LOCATION = "C4B7" #SEC = "1" !CDS_SEC = "1";
"A":   PN = "1"  !CDS_PN = "1";
"B":   PN = "2"  !CDS_PN = "2";
BODY = "RES","I219": #LOCATION = "R4B9" !CDS_LOCATION = "R4B9" #SEC = "1" !CDS_SEC = "1";
"A":   PN = "1"  !CDS_PN = "1";
"B":   PN = "2"  !CDS_PN = "2";
BODY = "RES","I220": #LOCATION = "R4B1" !CDS_LOCATION = "R4B1" &SEC = "1" #&CDS_SEC = "1";
"A":   PN = "1"  !CDS_PN = "1";
"B":   PN = "2"  !CDS_PN = "2";
DRAWING = "@baseboard_fab2_lib.baseboard_fab2(sch_1):page235";
BODY = "CAP_A","I143": #LOCATION = "C8A7" !CDS_LOCATION = "C8A7" #SEC = "1" !CDS_SEC = "1";
"A":   PN = "1"  !CDS_PN = "1";
"B":   PN = "2"  !CDS_PN = "2";
BODY = "CAP_A","I145": #LOCATION = "C8A8" !CDS_LOCATION = "C8A8" #SEC = "1" !CDS_SEC = "1";
"A":   PN = "1"  !CDS_PN = "1";
"B":   PN = "2"  !CDS_PN = "2";
BODY = "RES","I147": #LOCATION = "R2L16" !CDS_LOCATION = "R2L16" #SEC = "1" !CDS_SEC = "1";
"A":   PN = "1"  !CDS_PN = "1";
"B":   PN = "2"  !CDS_PN = "2";
BODY = "RES","I148": #LOCATION = "R2L24" !CDS_LOCATION = "R2L24" #SEC = "1" !CDS_SEC = "1";
"A":   PN = "1"  !CDS_PN = "1";
"B":   PN = "2"  !CDS_PN = "2";
BODY = "RES","I149": #LOCATION = "R8A6" !CDS_LOCATION = "R8A6" #SEC = "1" !CDS_SEC = "1";
"A":   PN = "1"  !CDS_PN = "1";
"B":   PN = "2"  !CDS_PN = "2";
BODY = "CAP_A","I151": #LOCATION = "C2L8" !CDS_LOCATION = "C2L8" #SEC = "1" !CDS_SEC = "1";
"A":   PN = "1"  !CDS_PN = "1";
"B":   PN = "2"  !CDS_PN = "2";
BODY = "CAP","I153": #LOCATION = "C2L2" !CDS_LOCATION = "C2L2" #SEC = "1" !CDS_SEC = "1";
"A":   PN = "1"  !CDS_PN = "1";
"B":   PN = "2"  !CDS_PN = "2";
BODY = "RES","I154": #LOCATION = "R2L8" !CDS_LOCATION = "R2L8" #SEC = "1" !CDS_SEC = "1";
"A":   PN = "1"  !CDS_PN = "1";
"B":   PN = "2"  !CDS_PN = "2";
BODY = "RES","I159": #LOCATION = "R2L14" !CDS_LOCATION = "R2L14" #SEC = "1" !CDS_SEC = "1";
"A":   PN = "1"  !CDS_PN = "1";
"B":   PN = "2"  !CDS_PN = "2";
BODY = "RES","I165": #LOCATION = "R8A4" !CDS_LOCATION = "R8A4" #SEC = "1" !CDS_SEC = "1";
"A":   PN = "1"  !CDS_PN = "1";
"B":   PN = "2"  !CDS_PN = "2";
BODY = "RES","I166": #LOCATION = "R2L10" !CDS_LOCATION = "R2L10" #SEC = "1" !CDS_SEC = "1";
"A":   PN = "1"  !CDS_PN = "1";
"B":   PN = "2"  !CDS_PN = "2";
BODY = "CAP","I167": #LOCATION = "C8A3" !CDS_LOCATION = "C8A3" #SEC = "1" !CDS_SEC = "1";
"A":   PN = "1"  !CDS_PN = "1";
"B":   PN = "2"  !CDS_PN = "2";
BODY = "CAP_A","I169": #LOCATION = "C2L11" !CDS_LOCATION = "C2L11" #SEC = "1" !CDS_SEC = "1";
"A":   PN = "1"  !CDS_PN = "1";
"B":   PN = "2"  !CDS_PN = "2";
BODY = "RES","I172": #LOCATION = "R8A8" !CDS_LOCATION = "R8A8" &SEC = "1" #&CDS_SEC = "1";
"A":   PN = "1"  !CDS_PN = "1";
"B":   PN = "2"  !CDS_PN = "2";
BODY = "RES","I173": #LOCATION = "R8A9" !CDS_LOCATION = "R8A9" &SEC = "1" #&CDS_SEC = "1";
"A":   PN = "1"  !CDS_PN = "1";
"B":   PN = "2"  !CDS_PN = "2";
BODY = "RES","I176": #LOCATION = "R2L9" !CDS_LOCATION = "R2L9" #SEC = "1" !CDS_SEC = "1";
"A":   PN = "1"  !CDS_PN = "1";
"B":   PN = "2"  !CDS_PN = "2";
BODY = "CAP","I209": #LOCATION = "C8A2" !CDS_LOCATION = "C8A2" #SEC = "1" !CDS_SEC = "1";
"A":   PN = "1"  !CDS_PN = "1";
"B":   PN = "2"  !CDS_PN = "2";
BODY = "RES","I210": #LOCATION = "R8A1" !CDS_LOCATION = "R8A1" #SEC = "1" !CDS_SEC = "1";
"A":   PN = "1"  !CDS_PN = "1";
"B":   PN = "2"  !CDS_PN = "2";
BODY = "RES","I216": #LOCATION = "R8A5" !CDS_LOCATION = "R8A5" &SEC = "1" #&CDS_SEC = "1";
"A":   PN = "1"  !CDS_PN = "1";
"B":   PN = "2"  !CDS_PN = "2";
BODY = "RES","I217": #LOCATION = "R8A2" !CDS_LOCATION = "R8A2" &SEC = "1" #&CDS_SEC = "1";
"A":   PN = "1"  !CDS_PN = "1";
"B":   PN = "2"  !CDS_PN = "2";
BODY = "CAP","I218": #LOCATION = "C8A9" !CDS_LOCATION = "C8A9" #SEC = "1" !CDS_SEC = "1";
"A":   PN = "1"  !CDS_PN = "1";
"B":   PN = "2"  !CDS_PN = "2";
BODY = "RES","I221": #LOCATION = "R2L17" !CDS_LOCATION = "R2L17" #SEC = "1" !CDS_SEC = "1";
"A":   PN = "1"  !CDS_PN = "1";
"B":   PN = "2"  !CDS_PN = "2";
BODY = "RES","I222": #LOCATION = "R8A7" !CDS_LOCATION = "R8A7" #SEC = "1" !CDS_SEC = "1";
"A":   PN = "1"  !CDS_PN = "1";
"B":   PN = "2"  !CDS_PN = "2";
BODY = "RES","I224": #LOCATION = "R2L1" !CDS_LOCATION = "R2L1" #SEC = "1" !CDS_SEC = "1";
"A":   PN = "1"  !CDS_PN = "1";
"B":   PN = "2"  !CDS_PN = "2";
BODY = "RES","I225": #LOCATION = "R2L7" !CDS_LOCATION = "R2L7" &SEC = "1" #&CDS_SEC = "1";
"A":   PN = "1"  !CDS_PN = "1";
"B":   PN = "2"  !CDS_PN = "2";
BODY = "PXE1110B","I229": #LOCATION = "EU8A1" !CDS_LOCATION = "EU8A1" #SEC = "1" !CDS_SEC = "1";
"AIREF1":   PN = "21"  !CDS_PN = "21";
"AISEN1":   PN = "22"  !CDS_PN = "22";
"APWM1":   PN = "5"  !CDS_PN = "5";
"ATSEN":   PN = "35"  !CDS_PN = "35";
"AVREF":   PN = "20"  !CDS_PN = "20";
"AVREN":   PN = "10"  !CDS_PN = "10";
"AVRRDY":   PN = "9"  !CDS_PN = "9";
"AVSEN":   PN = "19"  !CDS_PN = "19";
"BIREF1":   PN = "25"  !CDS_PN = "25";
"BISEN1":   PN = "26"  !CDS_PN = "26";
"BPWM1":   PN = "3"  !CDS_PN = "3";
"BTSEN":   PN = "34"  !CDS_PN = "34";
"BVREF":   PN = "30"  !CDS_PN = "30";
"BVSEN":   PN = "29"  !CDS_PN = "29";
"DNC<0>":   PN = "1"  !CDS_PN = "1";
"DNC<1>":   PN = "2"  !CDS_PN = "2";
"DNC<2>":   PN = "4"  !CDS_PN = "4";
"DNC<3>":   PN = "24"  !CDS_PN = "24";
"DNC<4>":   PN = "28"  !CDS_PN = "28";
"GND<0>":   PN = "27"  !CDS_PN = "27";
"GND<1>":   PN = "23"  !CDS_PN = "23";
"IINSEN":   PN = "38"  !CDS_PN = "38";
"MP0":   PN = "13"  !CDS_PN = "13";
"MP1":   PN = "14"  !CDS_PN = "14";
"MP2":   PN = "18"  !CDS_PN = "18";
"MP3":   PN = "31"  !CDS_PN = "31";
"MP4":   PN = "32"  !CDS_PN = "32";
"PINALRT_N":   PN = "12"  !CDS_PN = "12";
"RESET_N":   PN = "8"  !CDS_PN = "8";
"SCL":   PN = "7"  !CDS_PN = "7";
"SDA":   PN = "6"  !CDS_PN = "6";
"THPAD":   PN = "41"  !CDS_PN = "41";
"VALRT_N":   PN = "17"  !CDS_PN = "17";
"VCLK":   PN = "15"  !CDS_PN = "15";
"VD12":   PN = "40"  !CDS_PN = "40";
"VDD":   PN = "39"  !CDS_PN = "39";
"VDIO":   PN = "16"  !CDS_PN = "16";
"VINSEN":   PN = "37"  !CDS_PN = "37";
"VRHOT_N":   PN = "11"  !CDS_PN = "11";
"XADDR1":   PN = "36"  !CDS_PN = "36";
"XADDR2":   PN = "33"  !CDS_PN = "33";
BODY = "RES","I235": #LOCATION = "R2L25" !CDS_LOCATION = "R2L25" &SEC = "1" #&CDS_SEC = "1";
"A":   PN = "1"  !CDS_PN = "1";
"B":   PN = "2"  !CDS_PN = "2";
BODY = "RES","I236": #LOCATION = "R2L26" !CDS_LOCATION = "R2L26" &SEC = "1" #&CDS_SEC = "1";
"A":   PN = "1"  !CDS_PN = "1";
"B":   PN = "2"  !CDS_PN = "2";
DRAWING = "@baseboard_fab2_lib.baseboard_fab2(sch_1):page237";
BODY = "RES","I3": #LOCATION = "R8A10" !CDS_LOCATION = "R8A10" &SEC = "1" #&CDS_SEC = "1";
"A":   PN = "1"  !CDS_PN = "1";
"B":   PN = "2"  !CDS_PN = "2";
BODY = "CAP","I5": #LOCATION = "C8A11" !CDS_LOCATION = "C8A11" &SEC = "1" #&CDS_SEC = "1";
"A":   PN = "1"  !CDS_PN = "1";
"B":   PN = "2"  !CDS_PN = "2";
BODY = "CAP","I12": #LOCATION = "C2L45" !CDS_LOCATION = "C2L45" &SEC = "1" #&CDS_SEC = "1";
"A":   PN = "1"  !CDS_PN = "1";
"B":   PN = "2"  !CDS_PN = "2";
BODY = "CAP","I13": #LOCATION = "C8A14" !CDS_LOCATION = "C8A14" #SEC = "1" !CDS_SEC = "1";
"A":   PN = "1"  !CDS_PN = "1";
"B":   PN = "2"  !CDS_PN = "2";
BODY = "RES","I15": #LOCATION = "R8A12" !CDS_LOCATION = "R8A12" #SEC = "1" !CDS_SEC = "1";
"A":   PN = "1"  !CDS_PN = "1";
"B":   PN = "2"  !CDS_PN = "2";
BODY = "CAP","I29": #LOCATION = "C8A6" !CDS_LOCATION = "C8A6" #SEC = "1" !CDS_SEC = "1";
"A":   PN = "1"  !CDS_PN = "1";
"B":   PN = "2"  !CDS_PN = "2";
BODY = "CAP","I31": #LOCATION = "C8A4" !CDS_LOCATION = "C8A4" #SEC = "1" !CDS_SEC = "1";
"A":   PN = "1"  !CDS_PN = "1";
"B":   PN = "2"  !CDS_PN = "2";
BODY = "CAP","I55": #LOCATION = "C8A10" !CDS_LOCATION = "C8A10" &SEC = "1" #&CDS_SEC = "1";
"A":   PN = "1"  !CDS_PN = "1";
"B":   PN = "2"  !CDS_PN = "2";
BODY = "CAP","I77": #LOCATION = "C8A12" !CDS_LOCATION = "C8A12" #SEC = "1" !CDS_SEC = "1";
"A":   PN = "1"  !CDS_PN = "1";
"B":   PN = "2"  !CDS_PN = "2";
BODY = "CAP","I79": #LOCATION = "C2L32" !CDS_LOCATION = "C2L32" #SEC = "1" !CDS_SEC = "1";
"A":   PN = "1"  !CDS_PN = "1";
"B":   PN = "2"  !CDS_PN = "2";
BODY = "RES","I80": #LOCATION = "R2L19" !CDS_LOCATION = "R2L19" #SEC = "1" !CDS_SEC = "1";
"A":   PN = "1"  !CDS_PN = "1";
"B":   PN = "2"  !CDS_PN = "2";
BODY = "RES","I81": #LOCATION = "R2L20" !CDS_LOCATION = "R2L20" #SEC = "1" !CDS_SEC = "1";
"A":   PN = "1"  !CDS_PN = "1";
"B":   PN = "2"  !CDS_PN = "2";
BODY = "RT9059","I86": #LOCATION = "EU8A2" !CDS_LOCATION = "EU8A2" #SEC = "1" !CDS_SEC = "1";
"ADJ_NC":   PN = "4"  !CDS_PN = "4";
"EN":   PN = "6"  !CDS_PN = "6";
"GND":   PN = "11"  !CDS_PN = "11";
"PGOOD":   PN = "5"  !CDS_PN = "5";
"VDD":   PN = "10"  !CDS_PN = "10";
"VIN<0>":   PN = "7"  !CDS_PN = "7";
"VIN<1>":   PN = "8"  !CDS_PN = "8";
"VIN<2>":   PN = "9"  !CDS_PN = "9";
"VOUT<0>":   PN = "1"  !CDS_PN = "1";
"VOUT<1>":   PN = "2"  !CDS_PN = "2";
"VOUT<2>":   PN = "3"  !CDS_PN = "3";
BODY = "RES","I90": #LOCATION = "R8A11" !CDS_LOCATION = "R8A11" #SEC = "1" !CDS_SEC = "1";
"A":   PN = "1"  !CDS_PN = "1";
"B":   PN = "2"  !CDS_PN = "2";
DRAWING = "@baseboard_fab2_lib.baseboard_fab2(sch_1):page238";
BODY = "CAP","I5": #LOCATION = "C9F9" !CDS_LOCATION = "C9F9" &SEC = "1" #&CDS_SEC = "1";
"A":   PN = "1"  !CDS_PN = "1";
"B":   PN = "2"  !CDS_PN = "2";
BODY = "CAP","I7": #LOCATION = "C9F3" !CDS_LOCATION = "C9F3" #SEC = "1" !CDS_SEC = "1";
"A":   PN = "1"  !CDS_PN = "1";
"B":   PN = "2"  !CDS_PN = "2";
BODY = "RES","I14": #LOCATION = "R9F8" !CDS_LOCATION = "R9F8" #SEC = "1" !CDS_SEC = "1";
"A":   PN = "1"  !CDS_PN = "1";
"B":   PN = "2"  !CDS_PN = "2";
BODY = "CAP","I19": #LOCATION = "C9F8" !CDS_LOCATION = "C9F8" &SEC = "1" #&CDS_SEC = "1";
"A":   PN = "1"  !CDS_PN = "1";
"B":   PN = "2"  !CDS_PN = "2";
BODY = "RES","I21": #LOCATION = "R9F13" !CDS_LOCATION = "R9F13" #SEC = "1" !CDS_SEC = "1";
"A":   PN = "1"  !CDS_PN = "1";
"B":   PN = "2"  !CDS_PN = "2";
BODY = "CAP","I23": #LOCATION = "C9E10" !CDS_LOCATION = "C9E10" #SEC = "1" !CDS_SEC = "1";
"A":   PN = "1"  !CDS_PN = "1";
"B":   PN = "2"  !CDS_PN = "2";
BODY = "CAP","I30": #LOCATION = "C9F4" !CDS_LOCATION = "C9F4" #SEC = "1" !CDS_SEC = "1";
"A":   PN = "1"  !CDS_PN = "1";
"B":   PN = "2"  !CDS_PN = "2";
BODY = "CAP","I39": #LOCATION = "C9E11" !CDS_LOCATION = "C9E11" #SEC = "1" !CDS_SEC = "1";
"A":   PN = "1"  !CDS_PN = "1";
"B":   PN = "2"  !CDS_PN = "2";
BODY = "RT9059","I40": #LOCATION = "EU9F1" !CDS_LOCATION = "EU9F1" #SEC = "1" !CDS_SEC = "1";
"ADJ_NC":   PN = "4"  !CDS_PN = "4";
"EN":   PN = "6"  !CDS_PN = "6";
"GND":   PN = "11"  !CDS_PN = "11";
"PGOOD":   PN = "5"  !CDS_PN = "5";
"VDD":   PN = "10"  !CDS_PN = "10";
"VIN<0>":   PN = "7"  !CDS_PN = "7";
"VIN<1>":   PN = "8"  !CDS_PN = "8";
"VIN<2>":   PN = "9"  !CDS_PN = "9";
"VOUT<0>":   PN = "1"  !CDS_PN = "1";
"VOUT<1>":   PN = "2"  !CDS_PN = "2";
"VOUT<2>":   PN = "3"  !CDS_PN = "3";
BODY = "RES","I41": #LOCATION = "R9F11" !CDS_LOCATION = "R9F11" #SEC = "1" !CDS_SEC = "1";
"A":   PN = "1"  !CDS_PN = "1";
"B":   PN = "2"  !CDS_PN = "2";
BODY = "4K42R2F-GP","I45": #LOCATION = "R9F6" !CDS_LOCATION = "R9F6" &SEC = "1" #&CDS_SEC = "1";
"1":   PN = "1"  !CDS_PN = "1";
"2":   PN = "2"  !CDS_PN = "2";
DRAWING = "@baseboard_fab2_lib.baseboard_fab2(sch_1):page240";
BODY = "RES","I106": #LOCATION = "R8F9" !CDS_LOCATION = "R8F9" #SEC = "1" !CDS_SEC = "1";
"A":   PN = "1"  !CDS_PN = "1";
"B":   PN = "2"  !CDS_PN = "2";
BODY = "CAP","I109": #LOCATION = "C2R11" !CDS_LOCATION = "C2R11" #SEC = "1" !CDS_SEC = "1";
"A":   PN = "1"  !CDS_PN = "1";
"B":   PN = "2"  !CDS_PN = "2";
BODY = "RES","I111": #LOCATION = "R8F1" !CDS_LOCATION = "R8F1" &SEC = "1" #&CDS_SEC = "1";
"A":   PN = "1"  !CDS_PN = "1";
"B":   PN = "2"  !CDS_PN = "2";
BODY = "CAP","I113": #LOCATION = "C8E17" !CDS_LOCATION = "C8E17" &SEC = "1" #&CDS_SEC = "1";
"A":   PN = "1"  !CDS_PN = "1";
"B":   PN = "2"  !CDS_PN = "2";
BODY = "CAP","I116": #LOCATION = "C8F2" !CDS_LOCATION = "C8F2" &SEC = "1" #&CDS_SEC = "1";
"A":   PN = "1"  !CDS_PN = "1";
"B":   PN = "2"  !CDS_PN = "2";
BODY = "RES","I117": #LOCATION = "R8F5" !CDS_LOCATION = "R8F5" #SEC = "1" !CDS_SEC = "1";
"A":   PN = "1"  !CDS_PN = "1";
"B":   PN = "2"  !CDS_PN = "2";
BODY = "RT8240","I125": #LOCATION = "EU8F1" !CDS_LOCATION = "EU8F1" #SEC = "1" !CDS_SEC = "1";
"BOOT":   PN = "4"  !CDS_PN = "4";
"CS":   PN = "10"  !CDS_PN = "10";
"EN":   PN = "8"  !CDS_PN = "8";
"G0":   PN = "11"  !CDS_PN = "11";
"GND<0>":   PN = "12"  !CDS_PN = "12";
"GND<1>":   PN = "13"  !CDS_PN = "13";
"LGATE":   PN = "1"  !CDS_PN = "1";
"PGOOD":   PN = "9"  !CDS_PN = "9";
"PHASE":   PN = "2"  !CDS_PN = "2";
"RGND":   PN = "7"  !CDS_PN = "7";
"UGATE":   PN = "3"  !CDS_PN = "3";
"VCC":   PN = "5"  !CDS_PN = "5";
"VOUT":   PN = "6"  !CDS_PN = "6";
BODY = "RES","I127": #LOCATION = "R8E35" !CDS_LOCATION = "R8E35" &SEC = "1" #&CDS_SEC = "1";
"A":   PN = "1"  !CDS_PN = "1";
"B":   PN = "2"  !CDS_PN = "2";
BODY = "CAP","I129": #LOCATION = "C8E12" !CDS_LOCATION = "C8E12" &SEC = "1" #&CDS_SEC = "1";
"A":   PN = "1"  !CDS_PN = "1";
"B":   PN = "2"  !CDS_PN = "2";
BODY = "FERRITE","I132": #LOCATION = "FB9E1" !CDS_LOCATION = "FB9E1" #SEC = "1" !CDS_SEC = "1";
"A":   PN = "1"  !CDS_PN = "1";
"B":   PN = "2"  !CDS_PN = "2";
BODY = "CAP","I134": #LOCATION = "C9F1" !CDS_LOCATION = "C9F1" &SEC = "1" #&CDS_SEC = "1";
"A":   PN = "1"  !CDS_PN = "1";
"B":   PN = "2"  !CDS_PN = "2";
BODY = "CAP","I135": #LOCATION = "C8E11" !CDS_LOCATION = "C8E11" &SEC = "1" #&CDS_SEC = "1";
"A":   PN = "1"  !CDS_PN = "1";
"B":   PN = "2"  !CDS_PN = "2";
BODY = "CAP","I137": #LOCATION = "C8E10" !CDS_LOCATION = "C8E10" &SEC = "1" #&CDS_SEC = "1";
"A":   PN = "1"  !CDS_PN = "1";
"B":   PN = "2"  !CDS_PN = "2";
BODY = "CAP","I139": #LOCATION = "C8E14" !CDS_LOCATION = "C8E14" &SEC = "1" #&CDS_SEC = "1";
"A":   PN = "1"  !CDS_PN = "1";
"B":   PN = "2"  !CDS_PN = "2";
BODY = "RES","I140": #LOCATION = "R8E38" !CDS_LOCATION = "R8E38" &SEC = "1" #&CDS_SEC = "1";
"A":   PN = "1"  !CDS_PN = "1";
"B":   PN = "2"  !CDS_PN = "2";
BODY = "RES","I142": #LOCATION = "R8E34" !CDS_LOCATION = "R8E34" &SEC = "1" #&CDS_SEC = "1";
"A":   PN = "1"  !CDS_PN = "1";
"B":   PN = "2"  !CDS_PN = "2";
BODY = "RES","I143": #LOCATION = "R8E31" !CDS_LOCATION = "R8E31" &SEC = "1" #&CDS_SEC = "1";
"A":   PN = "1"  !CDS_PN = "1";
"B":   PN = "2"  !CDS_PN = "2";
BODY = "RES","I144": #LOCATION = "R8E25" !CDS_LOCATION = "R8E25" #SEC = "1" !CDS_SEC = "1";
"A":   PN = "1"  !CDS_PN = "1";
"B":   PN = "2"  !CDS_PN = "2";
BODY = "RES","I146": #LOCATION = "R8F11" !CDS_LOCATION = "R8F11" &SEC = "1" #&CDS_SEC = "1";
"A":   PN = "1"  !CDS_PN = "1";
"B":   PN = "2"  !CDS_PN = "2";
BODY = "RES","I148": #LOCATION = "R8F3" !CDS_LOCATION = "R8F3" &SEC = "1" #&CDS_SEC = "1";
"A":   PN = "1"  !CDS_PN = "1";
"B":   PN = "2"  !CDS_PN = "2";
BODY = "RES","I152": #LOCATION = "R2T4" !CDS_LOCATION = "R2T4" &SEC = "1" #&CDS_SEC = "1";
"A":   PN = "1"  !CDS_PN = "1";
"B":   PN = "2"  !CDS_PN = "2";
BODY = "CAPP","I154": #LOCATION = "C8F14" !CDS_LOCATION = "C8F14" &SEC = "1" #&CDS_SEC = "1";
"A":   PN = "1"  !CDS_PN = "1";
"B":   PN = "2"  !CDS_PN = "2";
BODY = "CAPP","I155": #LOCATION = "C8F8" !CDS_LOCATION = "C8F8" &SEC = "1" #&CDS_SEC = "1";
"A":   PN = "1"  !CDS_PN = "1";
"B":   PN = "2"  !CDS_PN = "2";
BODY = "CAP","I158": #LOCATION = "C2T7" !CDS_LOCATION = "C2T7" &SEC = "1" #&CDS_SEC = "1";
"A":   PN = "1"  !CDS_PN = "1";
"B":   PN = "2"  !CDS_PN = "2";
BODY = "CAP","I160": #LOCATION = "C2T6" !CDS_LOCATION = "C2T6" &SEC = "1" #&CDS_SEC = "1";
"A":   PN = "1"  !CDS_PN = "1";
"B":   PN = "2"  !CDS_PN = "2";
BODY = "CAP","I163": #LOCATION = "C8F3" !CDS_LOCATION = "C8F3" &SEC = "1" #&CDS_SEC = "1";
"A":   PN = "1"  !CDS_PN = "1";
"B":   PN = "2"  !CDS_PN = "2";
BODY = "CSD87384M","I170": #LOCATION = "EU8E1" !CDS_LOCATION = "EU8E1" #SEC = "1" !CDS_SEC = "1";
"BG":   PN = "4"  !CDS_PN = "4";
"PGND":   PN = "3"  !CDS_PN = "3";
"TG":   PN = "1"  !CDS_PN = "1";
"VIN":   PN = "2"  !CDS_PN = "2";
"VSW":   PN = "5"  !CDS_PN = "5";
BODY = "RES","I171": #LOCATION = "R8F10" !CDS_LOCATION = "R8F10" #SEC = "1" !CDS_SEC = "1";
"A":   PN = "1"  !CDS_PN = "1";
"B":   PN = "2"  !CDS_PN = "2";
BODY = "INDUCTOR","I173": #LOCATION = "L8F1" !CDS_LOCATION = "L8F1" &SEC = "1" #&CDS_SEC = "1";
"INA":   PN = "1"  !CDS_PN = "1";
"INB":   PN = "2"  !CDS_PN = "2";
BODY = "CAP","I174": #LOCATION = "C2T9" !CDS_LOCATION = "C2T9" &SEC = "1" #&CDS_SEC = "1";
"A":   PN = "1"  !CDS_PN = "1";
"B":   PN = "2"  !CDS_PN = "2";
BODY = "RES","I176": #LOCATION = "R8F2" !CDS_LOCATION = "R8F2" &SEC = "1" #&CDS_SEC = "1";
"A":   PN = "1"  !CDS_PN = "1";
"B":   PN = "2"  !CDS_PN = "2";
BODY = "RES","I177": #LOCATION = "R8E40" !CDS_LOCATION = "R8E40" &SEC = "1" #&CDS_SEC = "1";
"A":   PN = "1"  !CDS_PN = "1";
"B":   PN = "2"  !CDS_PN = "2";
DRAWING = "@baseboard_fab2_lib.baseboard_fab2(sch_1):page241";
BODY = "CAP","I2": #LOCATION = "C8E9" !CDS_LOCATION = "C8E9" #SEC = "1" !CDS_SEC = "1";
"A":   PN = "1"  !CDS_PN = "1";
"B":   PN = "2"  !CDS_PN = "2";
BODY = "CAP","I3": #LOCATION = "C8E7" !CDS_LOCATION = "C8E7" #SEC = "1" !CDS_SEC = "1";
"A":   PN = "1"  !CDS_PN = "1";
"B":   PN = "2"  !CDS_PN = "2";
BODY = "CAPP","I8": #LOCATION = "C8E4" !CDS_LOCATION = "C8E4" #SEC = "1" !CDS_SEC = "1";
"A":   PN = "1"  !CDS_PN = "1";
"B":   PN = "2"  !CDS_PN = "2";
BODY = "RES","I9": #LOCATION = "R8E18" !CDS_LOCATION = "R8E18" #SEC = "1" !CDS_SEC = "1";
"A":   PN = "1"  !CDS_PN = "1";
"B":   PN = "2"  !CDS_PN = "2";
BODY = "RES","I11": #LOCATION = "R7E12" !CDS_LOCATION = "R7E12" #SEC = "1" !CDS_SEC = "1";
"A":   PN = "1"  !CDS_PN = "1";
"B":   PN = "2"  !CDS_PN = "2";
BODY = "CAP","I12": #LOCATION = "C8E6" !CDS_LOCATION = "C8E6" #SEC = "1" !CDS_SEC = "1";
"A":   PN = "1"  !CDS_PN = "1";
"B":   PN = "2"  !CDS_PN = "2";
BODY = "CAP","I14": #LOCATION = "C7E10" !CDS_LOCATION = "C7E10" #SEC = "1" !CDS_SEC = "1";
"A":   PN = "1"  !CDS_PN = "1";
"B":   PN = "2"  !CDS_PN = "2";
BODY = "RES","I18": #LOCATION = "R7E14" !CDS_LOCATION = "R7E14" #SEC = "1" !CDS_SEC = "1";
"A":   PN = "1"  !CDS_PN = "1";
"B":   PN = "2"  !CDS_PN = "2";
BODY = "CAP","I30": #LOCATION = "C7E14" !CDS_LOCATION = "C7E14" #SEC = "1" !CDS_SEC = "1";
"A":   PN = "1"  !CDS_PN = "1";
"B":   PN = "2"  !CDS_PN = "2";
BODY = "RES","I37": #LOCATION = "R7E17" !CDS_LOCATION = "R7E17" #SEC = "1" !CDS_SEC = "1";
"A":   PN = "1"  !CDS_PN = "1";
"B":   PN = "2"  !CDS_PN = "2";
BODY = "CAP","I39": #LOCATION = "C7E11" !CDS_LOCATION = "C7E11" #SEC = "1" !CDS_SEC = "1";
"A":   PN = "1"  !CDS_PN = "1";
"B":   PN = "2"  !CDS_PN = "2";
BODY = "CAP","I41": #LOCATION = "C8E13" !CDS_LOCATION = "C8E13" #SEC = "1" !CDS_SEC = "1";
"A":   PN = "1"  !CDS_PN = "1";
"B":   PN = "2"  !CDS_PN = "2";
BODY = "CAP","I45": #LOCATION = "C7E13" !CDS_LOCATION = "C7E13" #SEC = "1" !CDS_SEC = "1";
"A":   PN = "1"  !CDS_PN = "1";
"B":   PN = "2"  !CDS_PN = "2";
BODY = "CAP","I47": #LOCATION = "C7E12" !CDS_LOCATION = "C7E12" #SEC = "1" !CDS_SEC = "1";
"A":   PN = "1"  !CDS_PN = "1";
"B":   PN = "2"  !CDS_PN = "2";
BODY = "RES","I50": #LOCATION = "R7F1" !CDS_LOCATION = "R7F1" #SEC = "1" !CDS_SEC = "1";
"A":   PN = "1"  !CDS_PN = "1";
"B":   PN = "2"  !CDS_PN = "2";
BODY = "RES","I51": #LOCATION = "R7E16" !CDS_LOCATION = "R7E16" #SEC = "1" !CDS_SEC = "1";
"A":   PN = "1"  !CDS_PN = "1";
"B":   PN = "2"  !CDS_PN = "2";
BODY = "CAP","I53": #LOCATION = "C8E16" !CDS_LOCATION = "C8E16" #SEC = "1" !CDS_SEC = "1";
"A":   PN = "1"  !CDS_PN = "1";
"B":   PN = "2"  !CDS_PN = "2";
BODY = "RES","I54": #LOCATION = "R8E39" !CDS_LOCATION = "R8E39" #SEC = "1" !CDS_SEC = "1";
"A":   PN = "1"  !CDS_PN = "1";
"B":   PN = "2"  !CDS_PN = "2";
BODY = "CAP","I57": #LOCATION = "C8F1" !CDS_LOCATION = "C8F1" #SEC = "1" !CDS_SEC = "1";
"A":   PN = "1"  !CDS_PN = "1";
"B":   PN = "2"  !CDS_PN = "2";
BODY = "RES","I58": #LOCATION = "R7E13" !CDS_LOCATION = "R7E13" #SEC = "1" !CDS_SEC = "1";
"A":   PN = "1"  !CDS_PN = "1";
"B":   PN = "2"  !CDS_PN = "2";
BODY = "CAP","I63": #LOCATION = "C8E15" !CDS_LOCATION = "C8E15" #SEC = "1" !CDS_SEC = "1";
"A":   PN = "1"  !CDS_PN = "1";
"B":   PN = "2"  !CDS_PN = "2";
BODY = "RES","I78": #LOCATION = "R8E37" !CDS_LOCATION = "R8E37" #SEC = "1" !CDS_SEC = "1";
"A":   PN = "1"  !CDS_PN = "1";
"B":   PN = "2"  !CDS_PN = "2";
BODY = "FERRITE","I82": #LOCATION = "FB7E1" !CDS_LOCATION = "FB7E1" &SEC = "1" #&CDS_SEC = "1";
"A":   PN = "1"  !CDS_PN = "1";
"B":   PN = "2"  !CDS_PN = "2";
BODY = "TPS54821","I83": #LOCATION = "EU7E2" !CDS_LOCATION = "EU7E2" #SEC = "1" !CDS_SEC = "1";
"BOOT":   PN = "13"  !CDS_PN = "13";
"COMP":   PN = "8"  !CDS_PN = "8";
"EN":   PN = "10"  !CDS_PN = "10";
"GND<0>":   PN = "2"  !CDS_PN = "2";
"GND<1>":   PN = "3"  !CDS_PN = "3";
"PH<0>":   PN = "11"  !CDS_PN = "11";
"PH<1>":   PN = "12"  !CDS_PN = "12";
"PVIN<0>":   PN = "4"  !CDS_PN = "4";
"PVIN<1>":   PN = "5"  !CDS_PN = "5";
"PWRGD":   PN = "14"  !CDS_PN = "14";
"RT_CLK":   PN = "1"  !CDS_PN = "1";
"SS_TR":   PN = "9"  !CDS_PN = "9";
"THPAD":   PN = "15"  !CDS_PN = "15";
"VIN":   PN = "6"  !CDS_PN = "6";
"VSENSE":   PN = "7"  !CDS_PN = "7";
BODY = "RES","I89": #LOCATION = "R7E15" !CDS_LOCATION = "R7E15" #SEC = "1" !CDS_SEC = "1";
"A":   PN = "1"  !CDS_PN = "1";
"B":   PN = "2"  !CDS_PN = "2";
BODY = "INDUCTOR","I90": #LOCATION = "L8E1" !CDS_LOCATION = "L8E1" &SEC = "1" #&CDS_SEC = "1";
"INA":   PN = "1"  !CDS_PN = "1";
"INB":   PN = "2"  !CDS_PN = "2";
BODY = "RES","I91": #LOCATION = "R8E33" !CDS_LOCATION = "R8E33" #SEC = "1" !CDS_SEC = "1";
"A":   PN = "1"  !CDS_PN = "1";
"B":   PN = "2"  !CDS_PN = "2";
DRAWING = "@baseboard_fab2_lib.baseboard_fab2(sch_1):page242";
BODY = "CAP","I11": #LOCATION = "C5G21" !CDS_LOCATION = "C5G21" &SEC = "1" #&CDS_SEC = "1";
"A":   PN = "1"  !CDS_PN = "1";
"B":   PN = "2"  !CDS_PN = "2";
BODY = "CAP","I15": #LOCATION = "C5G22" !CDS_LOCATION = "C5G22" &SEC = "1" #&CDS_SEC = "1";
"A":   PN = "1"  !CDS_PN = "1";
"B":   PN = "2"  !CDS_PN = "2";
BODY = "CAP","I37": #LOCATION = "C5G77" !CDS_LOCATION = "C5G77" &SEC = "1" #&CDS_SEC = "1";
"A":   PN = "1"  !CDS_PN = "1";
"B":   PN = "2"  !CDS_PN = "2";
BODY = "CAP","I41": #LOCATION = "C5G78" !CDS_LOCATION = "C5G78" &SEC = "1" #&CDS_SEC = "1";
"A":   PN = "1"  !CDS_PN = "1";
"B":   PN = "2"  !CDS_PN = "2";
BODY = "CAP_A","I53": #LOCATION = "C5G41" !CDS_LOCATION = "C5G41" &SEC = "1" #&CDS_SEC = "1";
"A":   PN = "1"  !CDS_PN = "1";
"B":   PN = "2"  !CDS_PN = "2";
BODY = "CAP_A","I54": #LOCATION = "C5G42" !CDS_LOCATION = "C5G42" &SEC = "1" #&CDS_SEC = "1";
"A":   PN = "1"  !CDS_PN = "1";
"B":   PN = "2"  !CDS_PN = "2";
BODY = "CAP_A","I55": #LOCATION = "C5G44" !CDS_LOCATION = "C5G44" &SEC = "1" #&CDS_SEC = "1";
"A":   PN = "1"  !CDS_PN = "1";
"B":   PN = "2"  !CDS_PN = "2";
BODY = "CAP_A","I56": #LOCATION = "C5G43" !CDS_LOCATION = "C5G43" &SEC = "1" #&CDS_SEC = "1";
"A":   PN = "1"  !CDS_PN = "1";
"B":   PN = "2"  !CDS_PN = "2";
BODY = "CAP_A","I57": #LOCATION = "C5G48" !CDS_LOCATION = "C5G48" &SEC = "1" #&CDS_SEC = "1";
"A":   PN = "1"  !CDS_PN = "1";
"B":   PN = "2"  !CDS_PN = "2";
BODY = "CAP_A","I58": #LOCATION = "C5G47" !CDS_LOCATION = "C5G47" &SEC = "1" #&CDS_SEC = "1";
"A":   PN = "1"  !CDS_PN = "1";
"B":   PN = "2"  !CDS_PN = "2";
BODY = "CAP_A","I59": #LOCATION = "C5G46" !CDS_LOCATION = "C5G46" &SEC = "1" #&CDS_SEC = "1";
"A":   PN = "1"  !CDS_PN = "1";
"B":   PN = "2"  !CDS_PN = "2";
BODY = "CAP_A","I60": #LOCATION = "C5G45" !CDS_LOCATION = "C5G45" &SEC = "1" #&CDS_SEC = "1";
"A":   PN = "1"  !CDS_PN = "1";
"B":   PN = "2"  !CDS_PN = "2";
BODY = "CAP_A","I61": #LOCATION = "C5G49" !CDS_LOCATION = "C5G49" &SEC = "1" #&CDS_SEC = "1";
"A":   PN = "1"  !CDS_PN = "1";
"B":   PN = "2"  !CDS_PN = "2";
BODY = "CAP_A","I62": #LOCATION = "C5G54" !CDS_LOCATION = "C5G54" &SEC = "1" #&CDS_SEC = "1";
"A":   PN = "1"  !CDS_PN = "1";
"B":   PN = "2"  !CDS_PN = "2";
BODY = "CAP_A","I63": #LOCATION = "C5G58" !CDS_LOCATION = "C5G58" &SEC = "1" #&CDS_SEC = "1";
"A":   PN = "1"  !CDS_PN = "1";
"B":   PN = "2"  !CDS_PN = "2";
BODY = "CAP_A","I64": #LOCATION = "C5G57" !CDS_LOCATION = "C5G57" &SEC = "1" #&CDS_SEC = "1";
"A":   PN = "1"  !CDS_PN = "1";
"B":   PN = "2"  !CDS_PN = "2";
BODY = "CAP_A","I65": #LOCATION = "C5G56" !CDS_LOCATION = "C5G56" &SEC = "1" #&CDS_SEC = "1";
"A":   PN = "1"  !CDS_PN = "1";
"B":   PN = "2"  !CDS_PN = "2";
BODY = "CAP_A","I66": #LOCATION = "C5G55" !CDS_LOCATION = "C5G55" &SEC = "1" #&CDS_SEC = "1";
"A":   PN = "1"  !CDS_PN = "1";
"B":   PN = "2"  !CDS_PN = "2";
BODY = "CAP_A","I67": #LOCATION = "C5G53" !CDS_LOCATION = "C5G53" &SEC = "1" #&CDS_SEC = "1";
"A":   PN = "1"  !CDS_PN = "1";
"B":   PN = "2"  !CDS_PN = "2";
BODY = "CAP_A","I68": #LOCATION = "C5G52" !CDS_LOCATION = "C5G52" &SEC = "1" #&CDS_SEC = "1";
"A":   PN = "1"  !CDS_PN = "1";
"B":   PN = "2"  !CDS_PN = "2";
BODY = "CAP_A","I69": #LOCATION = "C5G51" !CDS_LOCATION = "C5G51" &SEC = "1" #&CDS_SEC = "1";
"A":   PN = "1"  !CDS_PN = "1";
"B":   PN = "2"  !CDS_PN = "2";
BODY = "CAP_A","I70": #LOCATION = "C5G50" !CDS_LOCATION = "C5G50" &SEC = "1" #&CDS_SEC = "1";
"A":   PN = "1"  !CDS_PN = "1";
"B":   PN = "2"  !CDS_PN = "2";
BODY = "CAP_A","I71": #LOCATION = "C5G67" !CDS_LOCATION = "C5G67" &SEC = "1" #&CDS_SEC = "1";
"A":   PN = "1"  !CDS_PN = "1";
"B":   PN = "2"  !CDS_PN = "2";
BODY = "CAP_A","I72": #LOCATION = "C5G66" !CDS_LOCATION = "C5G66" &SEC = "1" #&CDS_SEC = "1";
"A":   PN = "1"  !CDS_PN = "1";
"B":   PN = "2"  !CDS_PN = "2";
BODY = "CAP_A","I73": #LOCATION = "C5G65" !CDS_LOCATION = "C5G65" &SEC = "1" #&CDS_SEC = "1";
"A":   PN = "1"  !CDS_PN = "1";
"B":   PN = "2"  !CDS_PN = "2";
BODY = "CAP_A","I74": #LOCATION = "C5G64" !CDS_LOCATION = "C5G64" &SEC = "1" #&CDS_SEC = "1";
"A":   PN = "1"  !CDS_PN = "1";
"B":   PN = "2"  !CDS_PN = "2";
BODY = "CAP_A","I75": #LOCATION = "C5G63" !CDS_LOCATION = "C5G63" &SEC = "1" #&CDS_SEC = "1";
"A":   PN = "1"  !CDS_PN = "1";
"B":   PN = "2"  !CDS_PN = "2";
BODY = "CAP_A","I76": #LOCATION = "C5G62" !CDS_LOCATION = "C5G62" &SEC = "1" #&CDS_SEC = "1";
"A":   PN = "1"  !CDS_PN = "1";
"B":   PN = "2"  !CDS_PN = "2";
BODY = "CAP_A","I77": #LOCATION = "C5G61" !CDS_LOCATION = "C5G61" &SEC = "1" #&CDS_SEC = "1";
"A":   PN = "1"  !CDS_PN = "1";
"B":   PN = "2"  !CDS_PN = "2";
BODY = "CAP_A","I78": #LOCATION = "C5G60" !CDS_LOCATION = "C5G60" &SEC = "1" #&CDS_SEC = "1";
"A":   PN = "1"  !CDS_PN = "1";
"B":   PN = "2"  !CDS_PN = "2";
BODY = "CAP_A","I79": #LOCATION = "C5G59" !CDS_LOCATION = "C5G59" &SEC = "1" #&CDS_SEC = "1";
"A":   PN = "1"  !CDS_PN = "1";
"B":   PN = "2"  !CDS_PN = "2";
BODY = "CAP_A","I80": #LOCATION = "C5G76" !CDS_LOCATION = "C5G76" &SEC = "1" #&CDS_SEC = "1";
"A":   PN = "1"  !CDS_PN = "1";
"B":   PN = "2"  !CDS_PN = "2";
BODY = "CAP_A","I81": #LOCATION = "C5G75" !CDS_LOCATION = "C5G75" &SEC = "1" #&CDS_SEC = "1";
"A":   PN = "1"  !CDS_PN = "1";
"B":   PN = "2"  !CDS_PN = "2";
BODY = "CAP_A","I82": #LOCATION = "C5G74" !CDS_LOCATION = "C5G74" &SEC = "1" #&CDS_SEC = "1";
"A":   PN = "1"  !CDS_PN = "1";
"B":   PN = "2"  !CDS_PN = "2";
BODY = "CAP_A","I83": #LOCATION = "C5G73" !CDS_LOCATION = "C5G73" &SEC = "1" #&CDS_SEC = "1";
"A":   PN = "1"  !CDS_PN = "1";
"B":   PN = "2"  !CDS_PN = "2";
BODY = "CAP_A","I84": #LOCATION = "C5G72" !CDS_LOCATION = "C5G72" &SEC = "1" #&CDS_SEC = "1";
"A":   PN = "1"  !CDS_PN = "1";
"B":   PN = "2"  !CDS_PN = "2";
BODY = "CAP_A","I85": #LOCATION = "C5G71" !CDS_LOCATION = "C5G71" &SEC = "1" #&CDS_SEC = "1";
"A":   PN = "1"  !CDS_PN = "1";
"B":   PN = "2"  !CDS_PN = "2";
BODY = "CAP_A","I86": #LOCATION = "C5G70" !CDS_LOCATION = "C5G70" &SEC = "1" #&CDS_SEC = "1";
"A":   PN = "1"  !CDS_PN = "1";
"B":   PN = "2"  !CDS_PN = "2";
BODY = "CAP_A","I87": #LOCATION = "C5G69" !CDS_LOCATION = "C5G69" &SEC = "1" #&CDS_SEC = "1";
"A":   PN = "1"  !CDS_PN = "1";
"B":   PN = "2"  !CDS_PN = "2";
BODY = "CAP_A","I88": #LOCATION = "C5G68" !CDS_LOCATION = "C5G68" &SEC = "1" #&CDS_SEC = "1";
"A":   PN = "1"  !CDS_PN = "1";
"B":   PN = "2"  !CDS_PN = "2";
DRAWING = "@baseboard_fab2_lib.baseboard_fab2(sch_1):page243";
BODY = "CAP","I12": #LOCATION = "C5G117" !CDS_LOCATION = "C5G117" &SEC = "1" #&CDS_SEC = "1";
"A":   PN = "1"  !CDS_PN = "1";
"B":   PN = "2"  !CDS_PN = "2";
BODY = "CAP","I13": #LOCATION = "C5G118" !CDS_LOCATION = "C5G118" &SEC = "1" #&CDS_SEC = "1";
"A":   PN = "1"  !CDS_PN = "1";
"B":   PN = "2"  !CDS_PN = "2";
BODY = "CAP","I39": #LOCATION = "C5G115" !CDS_LOCATION = "C5G115" &SEC = "1" #&CDS_SEC = "1";
"A":   PN = "1"  !CDS_PN = "1";
"B":   PN = "2"  !CDS_PN = "2";
BODY = "CAP","I43": #LOCATION = "C5G116" !CDS_LOCATION = "C5G116" &SEC = "1" #&CDS_SEC = "1";
"A":   PN = "1"  !CDS_PN = "1";
"B":   PN = "2"  !CDS_PN = "2";
BODY = "CAP_A","I53": #LOCATION = "C5G79" !CDS_LOCATION = "C5G79" &SEC = "1" #&CDS_SEC = "1";
"A":   PN = "1"  !CDS_PN = "1";
"B":   PN = "2"  !CDS_PN = "2";
BODY = "CAP_A","I54": #LOCATION = "C5G87" !CDS_LOCATION = "C5G87" &SEC = "1" #&CDS_SEC = "1";
"A":   PN = "1"  !CDS_PN = "1";
"B":   PN = "2"  !CDS_PN = "2";
BODY = "CAP_A","I55": #LOCATION = "C5G86" !CDS_LOCATION = "C5G86" &SEC = "1" #&CDS_SEC = "1";
"A":   PN = "1"  !CDS_PN = "1";
"B":   PN = "2"  !CDS_PN = "2";
BODY = "CAP_A","I56": #LOCATION = "C5G85" !CDS_LOCATION = "C5G85" &SEC = "1" #&CDS_SEC = "1";
"A":   PN = "1"  !CDS_PN = "1";
"B":   PN = "2"  !CDS_PN = "2";
BODY = "CAP_A","I57": #LOCATION = "C5G84" !CDS_LOCATION = "C5G84" &SEC = "1" #&CDS_SEC = "1";
"A":   PN = "1"  !CDS_PN = "1";
"B":   PN = "2"  !CDS_PN = "2";
BODY = "CAP_A","I58": #LOCATION = "C5G83" !CDS_LOCATION = "C5G83" &SEC = "1" #&CDS_SEC = "1";
"A":   PN = "1"  !CDS_PN = "1";
"B":   PN = "2"  !CDS_PN = "2";
BODY = "CAP_A","I59": #LOCATION = "C5G82" !CDS_LOCATION = "C5G82" &SEC = "1" #&CDS_SEC = "1";
"A":   PN = "1"  !CDS_PN = "1";
"B":   PN = "2"  !CDS_PN = "2";
BODY = "CAP_A","I60": #LOCATION = "C5G81" !CDS_LOCATION = "C5G81" &SEC = "1" #&CDS_SEC = "1";
"A":   PN = "1"  !CDS_PN = "1";
"B":   PN = "2"  !CDS_PN = "2";
BODY = "CAP_A","I61": #LOCATION = "C5G80" !CDS_LOCATION = "C5G80" &SEC = "1" #&CDS_SEC = "1";
"A":   PN = "1"  !CDS_PN = "1";
"B":   PN = "2"  !CDS_PN = "2";
BODY = "CAP_A","I62": #LOCATION = "C5G96" !CDS_LOCATION = "C5G96" &SEC = "1" #&CDS_SEC = "1";
"A":   PN = "1"  !CDS_PN = "1";
"B":   PN = "2"  !CDS_PN = "2";
BODY = "CAP_A","I63": #LOCATION = "C5G95" !CDS_LOCATION = "C5G95" &SEC = "1" #&CDS_SEC = "1";
"A":   PN = "1"  !CDS_PN = "1";
"B":   PN = "2"  !CDS_PN = "2";
BODY = "CAP_A","I64": #LOCATION = "C5G94" !CDS_LOCATION = "C5G94" &SEC = "1" #&CDS_SEC = "1";
"A":   PN = "1"  !CDS_PN = "1";
"B":   PN = "2"  !CDS_PN = "2";
BODY = "CAP_A","I65": #LOCATION = "C5G93" !CDS_LOCATION = "C5G93" &SEC = "1" #&CDS_SEC = "1";
"A":   PN = "1"  !CDS_PN = "1";
"B":   PN = "2"  !CDS_PN = "2";
BODY = "CAP_A","I66": #LOCATION = "C5G92" !CDS_LOCATION = "C5G92" &SEC = "1" #&CDS_SEC = "1";
"A":   PN = "1"  !CDS_PN = "1";
"B":   PN = "2"  !CDS_PN = "2";
BODY = "CAP_A","I67": #LOCATION = "C5G91" !CDS_LOCATION = "C5G91" &SEC = "1" #&CDS_SEC = "1";
"A":   PN = "1"  !CDS_PN = "1";
"B":   PN = "2"  !CDS_PN = "2";
BODY = "CAP_A","I68": #LOCATION = "C5G90" !CDS_LOCATION = "C5G90" &SEC = "1" #&CDS_SEC = "1";
"A":   PN = "1"  !CDS_PN = "1";
"B":   PN = "2"  !CDS_PN = "2";
BODY = "CAP_A","I69": #LOCATION = "C5G89" !CDS_LOCATION = "C5G89" &SEC = "1" #&CDS_SEC = "1";
"A":   PN = "1"  !CDS_PN = "1";
"B":   PN = "2"  !CDS_PN = "2";
BODY = "CAP_A","I70": #LOCATION = "C5G88" !CDS_LOCATION = "C5G88" &SEC = "1" #&CDS_SEC = "1";
"A":   PN = "1"  !CDS_PN = "1";
"B":   PN = "2"  !CDS_PN = "2";
BODY = "CAP_A","I71": #LOCATION = "C5G103" !CDS_LOCATION = "C5G103" &SEC = "1" #&CDS_SEC = "1";
"A":   PN = "1"  !CDS_PN = "1";
"B":   PN = "2"  !CDS_PN = "2";
BODY = "CAP_A","I72": #LOCATION = "C5G104" !CDS_LOCATION = "C5G104" &SEC = "1" #&CDS_SEC = "1";
"A":   PN = "1"  !CDS_PN = "1";
"B":   PN = "2"  !CDS_PN = "2";
BODY = "CAP_A","I73": #LOCATION = "C5G105" !CDS_LOCATION = "C5G105" &SEC = "1" #&CDS_SEC = "1";
"A":   PN = "1"  !CDS_PN = "1";
"B":   PN = "2"  !CDS_PN = "2";
BODY = "CAP_A","I74": #LOCATION = "C5G102" !CDS_LOCATION = "C5G102" &SEC = "1" #&CDS_SEC = "1";
"A":   PN = "1"  !CDS_PN = "1";
"B":   PN = "2"  !CDS_PN = "2";
BODY = "CAP_A","I75": #LOCATION = "C5G101" !CDS_LOCATION = "C5G101" &SEC = "1" #&CDS_SEC = "1";
"A":   PN = "1"  !CDS_PN = "1";
"B":   PN = "2"  !CDS_PN = "2";
BODY = "CAP_A","I76": #LOCATION = "C5G100" !CDS_LOCATION = "C5G100" &SEC = "1" #&CDS_SEC = "1";
"A":   PN = "1"  !CDS_PN = "1";
"B":   PN = "2"  !CDS_PN = "2";
BODY = "CAP_A","I77": #LOCATION = "C5G99" !CDS_LOCATION = "C5G99" &SEC = "1" #&CDS_SEC = "1";
"A":   PN = "1"  !CDS_PN = "1";
"B":   PN = "2"  !CDS_PN = "2";
BODY = "CAP_A","I78": #LOCATION = "C5G98" !CDS_LOCATION = "C5G98" &SEC = "1" #&CDS_SEC = "1";
"A":   PN = "1"  !CDS_PN = "1";
"B":   PN = "2"  !CDS_PN = "2";
BODY = "CAP_A","I79": #LOCATION = "C5G97" !CDS_LOCATION = "C5G97" &SEC = "1" #&CDS_SEC = "1";
"A":   PN = "1"  !CDS_PN = "1";
"B":   PN = "2"  !CDS_PN = "2";
BODY = "CAP_A","I80": #LOCATION = "C5G114" !CDS_LOCATION = "C5G114" &SEC = "1" #&CDS_SEC = "1";
"A":   PN = "1"  !CDS_PN = "1";
"B":   PN = "2"  !CDS_PN = "2";
BODY = "CAP_A","I81": #LOCATION = "C5G113" !CDS_LOCATION = "C5G113" &SEC = "1" #&CDS_SEC = "1";
"A":   PN = "1"  !CDS_PN = "1";
"B":   PN = "2"  !CDS_PN = "2";
BODY = "CAP_A","I82": #LOCATION = "C5G112" !CDS_LOCATION = "C5G112" &SEC = "1" #&CDS_SEC = "1";
"A":   PN = "1"  !CDS_PN = "1";
"B":   PN = "2"  !CDS_PN = "2";
BODY = "CAP_A","I83": #LOCATION = "C5G111" !CDS_LOCATION = "C5G111" &SEC = "1" #&CDS_SEC = "1";
"A":   PN = "1"  !CDS_PN = "1";
"B":   PN = "2"  !CDS_PN = "2";
BODY = "CAP_A","I84": #LOCATION = "C5G110" !CDS_LOCATION = "C5G110" &SEC = "1" #&CDS_SEC = "1";
"A":   PN = "1"  !CDS_PN = "1";
"B":   PN = "2"  !CDS_PN = "2";
BODY = "CAP_A","I85": #LOCATION = "C5G109" !CDS_LOCATION = "C5G109" &SEC = "1" #&CDS_SEC = "1";
"A":   PN = "1"  !CDS_PN = "1";
"B":   PN = "2"  !CDS_PN = "2";
BODY = "CAP_A","I86": #LOCATION = "C5G108" !CDS_LOCATION = "C5G108" &SEC = "1" #&CDS_SEC = "1";
"A":   PN = "1"  !CDS_PN = "1";
"B":   PN = "2"  !CDS_PN = "2";
BODY = "CAP_A","I87": #LOCATION = "C5G107" !CDS_LOCATION = "C5G107" &SEC = "1" #&CDS_SEC = "1";
"A":   PN = "1"  !CDS_PN = "1";
"B":   PN = "2"  !CDS_PN = "2";
BODY = "CAP_A","I88": #LOCATION = "C5G106" !CDS_LOCATION = "C5G106" &SEC = "1" #&CDS_SEC = "1";
"A":   PN = "1"  !CDS_PN = "1";
"B":   PN = "2"  !CDS_PN = "2";
DRAWING = "@baseboard_fab2_lib.baseboard_fab2(sch_1):page244";
BODY = "CAP","I2": LOCATION = "C831" #&CDS_LOCATION = "C831" &SEC = "1" #&CDS_SEC = "1";
"A":   PN = "1"  !CDS_PN = "1";
"B":   PN = "2"  !CDS_PN = "2";
BODY = "CAP","I5": LOCATION = "C829" #&CDS_LOCATION = "C829" &SEC = "1" #&CDS_SEC = "1";
"A":   PN = "1"  !CDS_PN = "1";
"B":   PN = "2"  !CDS_PN = "2";
BODY = "CAP","I8": LOCATION = "C833" #&CDS_LOCATION = "C833" &SEC = "1" #&CDS_SEC = "1";
"A":   PN = "1"  !CDS_PN = "1";
"B":   PN = "2"  !CDS_PN = "2";
BODY = "CAP","I12": LOCATION = "C827" #&CDS_LOCATION = "C827" &SEC = "1" #&CDS_SEC = "1";
"A":   PN = "1"  !CDS_PN = "1";
"B":   PN = "2"  !CDS_PN = "2";
BODY = "CAP","I17": LOCATION = "C841" #&CDS_LOCATION = "C841" &SEC = "1" #&CDS_SEC = "1";
"A":   PN = "1"  !CDS_PN = "1";
"B":   PN = "2"  !CDS_PN = "2";
BODY = "CAP","I23": LOCATION = "C830" #&CDS_LOCATION = "C830" &SEC = "1" #&CDS_SEC = "1";
"A":   PN = "1"  !CDS_PN = "1";
"B":   PN = "2"  !CDS_PN = "2";
BODY = "CAP","I24": LOCATION = "C826" #&CDS_LOCATION = "C826" &SEC = "1" #&CDS_SEC = "1";
"A":   PN = "1"  !CDS_PN = "1";
"B":   PN = "2"  !CDS_PN = "2";
BODY = "CAP","I28": LOCATION = "C828" #&CDS_LOCATION = "C828" &SEC = "1" #&CDS_SEC = "1";
"A":   PN = "1"  !CDS_PN = "1";
"B":   PN = "2"  !CDS_PN = "2";
BODY = "CAP","I29": LOCATION = "C840" #&CDS_LOCATION = "C840" &SEC = "1" #&CDS_SEC = "1";
"A":   PN = "1"  !CDS_PN = "1";
"B":   PN = "2"  !CDS_PN = "2";
BODY = "CAP","I30": LOCATION = "C832" #&CDS_LOCATION = "C832" &SEC = "1" #&CDS_SEC = "1";
"A":   PN = "1"  !CDS_PN = "1";
"B":   PN = "2"  !CDS_PN = "2";
BODY = "CAP","I35": LOCATION = "C845" #&CDS_LOCATION = "C845" &SEC = "1" #&CDS_SEC = "1";
"A":   PN = "1"  !CDS_PN = "1";
"B":   PN = "2"  !CDS_PN = "2";
BODY = "RES","I39": LOCATION = "R767" #&CDS_LOCATION = "R767" &SEC = "1" #&CDS_SEC = "1";
"A":   PN = "1"  !CDS_PN = "1";
"B":   PN = "2"  !CDS_PN = "2";
BODY = "CAP","I41": LOCATION = "C835" #&CDS_LOCATION = "C835" &SEC = "1" #&CDS_SEC = "1";
"A":   PN = "1"  !CDS_PN = "1";
"B":   PN = "2"  !CDS_PN = "2";
BODY = "CAP","I47": LOCATION = "C843" #&CDS_LOCATION = "C843" &SEC = "1" #&CDS_SEC = "1";
"A":   PN = "1"  !CDS_PN = "1";
"B":   PN = "2"  !CDS_PN = "2";
BODY = "CAP","I50": LOCATION = "C834" #&CDS_LOCATION = "C834" &SEC = "1" #&CDS_SEC = "1";
"A":   PN = "1"  !CDS_PN = "1";
"B":   PN = "2"  !CDS_PN = "2";
BODY = "CAP","I51": LOCATION = "C844" #&CDS_LOCATION = "C844" &SEC = "1" #&CDS_SEC = "1";
"A":   PN = "1"  !CDS_PN = "1";
"B":   PN = "2"  !CDS_PN = "2";
BODY = "CAP","I52": LOCATION = "C842" #&CDS_LOCATION = "C842" &SEC = "1" #&CDS_SEC = "1";
"A":   PN = "1"  !CDS_PN = "1";
"B":   PN = "2"  !CDS_PN = "2";
BODY = "RES","I58": LOCATION = "R769" #&CDS_LOCATION = "R769" &SEC = "1" #&CDS_SEC = "1";
"A":   PN = "1"  !CDS_PN = "1";
"B":   PN = "2"  !CDS_PN = "2";
BODY = "RES","I64": LOCATION = "R760" #&CDS_LOCATION = "R760" &SEC = "1" #&CDS_SEC = "1";
"A":   PN = "1"  !CDS_PN = "1";
"B":   PN = "2"  !CDS_PN = "2";
BODY = "RES","I65": LOCATION = "R771" #&CDS_LOCATION = "R771" &SEC = "1" #&CDS_SEC = "1";
"A":   PN = "1"  !CDS_PN = "1";
"B":   PN = "2"  !CDS_PN = "2";
BODY = "RES","I66": LOCATION = "R768" #&CDS_LOCATION = "R768" &SEC = "1" #&CDS_SEC = "1";
"A":   PN = "1"  !CDS_PN = "1";
"B":   PN = "2"  !CDS_PN = "2";
BODY = "RES","I72": LOCATION = "R774" #&CDS_LOCATION = "R774" &SEC = "1" #&CDS_SEC = "1";
"A":   PN = "1"  !CDS_PN = "1";
"B":   PN = "2"  !CDS_PN = "2";
BODY = "RES","I74": LOCATION = "R779" #&CDS_LOCATION = "R779" &SEC = "1" #&CDS_SEC = "1";
"A":   PN = "1"  !CDS_PN = "1";
"B":   PN = "2"  !CDS_PN = "2";
BODY = "RES","I77": LOCATION = "R783" #&CDS_LOCATION = "R783" &SEC = "1" #&CDS_SEC = "1";
"A":   PN = "1"  !CDS_PN = "1";
"B":   PN = "2"  !CDS_PN = "2";
BODY = "RES","I80": LOCATION = "R777" #&CDS_LOCATION = "R777" &SEC = "1" #&CDS_SEC = "1";
"A":   PN = "1"  !CDS_PN = "1";
"B":   PN = "2"  !CDS_PN = "2";
BODY = "RES","I86": LOCATION = "R781" #&CDS_LOCATION = "R781" &SEC = "1" #&CDS_SEC = "1";
"A":   PN = "1"  !CDS_PN = "1";
"B":   PN = "2"  !CDS_PN = "2";
BODY = "RES","I93": LOCATION = "R775" #&CDS_LOCATION = "R775" &SEC = "1" #&CDS_SEC = "1";
"A":   PN = "1"  !CDS_PN = "1";
"B":   PN = "2"  !CDS_PN = "2";
BODY = "RES","I94": LOCATION = "R778" #&CDS_LOCATION = "R778" &SEC = "1" #&CDS_SEC = "1";
"A":   PN = "1"  !CDS_PN = "1";
"B":   PN = "2"  !CDS_PN = "2";
BODY = "RES","I97": LOCATION = "R780" #&CDS_LOCATION = "R780" &SEC = "1" #&CDS_SEC = "1";
"A":   PN = "1"  !CDS_PN = "1";
"B":   PN = "2"  !CDS_PN = "2";
BODY = "RES","I98": LOCATION = "R782" #&CDS_LOCATION = "R782" &SEC = "1" #&CDS_SEC = "1";
"A":   PN = "1"  !CDS_PN = "1";
"B":   PN = "2"  !CDS_PN = "2";
BODY = "RES","I99": LOCATION = "R784" #&CDS_LOCATION = "R784" &SEC = "1" #&CDS_SEC = "1";
"A":   PN = "1"  !CDS_PN = "1";
"B":   PN = "2"  !CDS_PN = "2";
BODY = "RES","I103": LOCATION = "R785" #&CDS_LOCATION = "R785" &SEC = "1" #&CDS_SEC = "1";
"A":   PN = "1"  !CDS_PN = "1";
"B":   PN = "2"  !CDS_PN = "2";
DRAWING = "@baseboard_fab2_lib.baseboard_fab2(sch_1):page245";
BODY = "SMC-CONN60A-22-GP","I48": #LOCATION = "CONX8" !CDS_LOCATION = "CONX8" &SEC = "1" #&CDS_SEC = "1";
"1":   PN = "1"  !CDS_PN = "1";
"2":   PN = "2"  !CDS_PN = "2";
"3":   PN = "3"  !CDS_PN = "3";
"4":   PN = "4"  !CDS_PN = "4";
"5":   PN = "5"  !CDS_PN = "5";
"6":   PN = "6"  !CDS_PN = "6";
"7":   PN = "7"  !CDS_PN = "7";
"8":   PN = "8"  !CDS_PN = "8";
"9":   PN = "9"  !CDS_PN = "9";
"10":   PN = "10"  !CDS_PN = "10";
"11":   PN = "11"  !CDS_PN = "11";
"12":   PN = "12"  !CDS_PN = "12";
"13":   PN = "13"  !CDS_PN = "13";
"14":   PN = "14"  !CDS_PN = "14";
"15":   PN = "15"  !CDS_PN = "15";
"16":   PN = "16"  !CDS_PN = "16";
"17":   PN = "17"  !CDS_PN = "17";
"18":   PN = "18"  !CDS_PN = "18";
"19":   PN = "19"  !CDS_PN = "19";
"20":   PN = "20"  !CDS_PN = "20";
"21":   PN = "21"  !CDS_PN = "21";
"22":   PN = "22"  !CDS_PN = "22";
"23":   PN = "23"  !CDS_PN = "23";
"24":   PN = "24"  !CDS_PN = "24";
"25":   PN = "25"  !CDS_PN = "25";
"26":   PN = "26"  !CDS_PN = "26";
"27":   PN = "27"  !CDS_PN = "27";
"28":   PN = "28"  !CDS_PN = "28";
"29":   PN = "29"  !CDS_PN = "29";
"30":   PN = "30"  !CDS_PN = "30";
"31":   PN = "31"  !CDS_PN = "31";
"32":   PN = "32"  !CDS_PN = "32";
"33":   PN = "33"  !CDS_PN = "33";
"34":   PN = "34"  !CDS_PN = "34";
"35":   PN = "35"  !CDS_PN = "35";
"36":   PN = "36"  !CDS_PN = "36";
"37":   PN = "37"  !CDS_PN = "37";
"38":   PN = "38"  !CDS_PN = "38";
"39":   PN = "39"  !CDS_PN = "39";
"40":   PN = "40"  !CDS_PN = "40";
"41":   PN = "41"  !CDS_PN = "41";
"42":   PN = "42"  !CDS_PN = "42";
"43":   PN = "43"  !CDS_PN = "43";
"44":   PN = "44"  !CDS_PN = "44";
"45":   PN = "45"  !CDS_PN = "45";
"46":   PN = "46"  !CDS_PN = "46";
"47":   PN = "47"  !CDS_PN = "47";
"48":   PN = "48"  !CDS_PN = "48";
"49":   PN = "49"  !CDS_PN = "49";
"50":   PN = "50"  !CDS_PN = "50";
"51":   PN = "51"  !CDS_PN = "51";
"52":   PN = "52"  !CDS_PN = "52";
"53":   PN = "53"  !CDS_PN = "53";
"54":   PN = "54"  !CDS_PN = "54";
"55":   PN = "55"  !CDS_PN = "55";
"56":   PN = "56"  !CDS_PN = "56";
"57":   PN = "57"  !CDS_PN = "57";
"58":   PN = "58"  !CDS_PN = "58";
"59":   PN = "59"  !CDS_PN = "59";
"60":   PN = "60"  !CDS_PN = "60";
"NP1":   PN = "NP1"  !CDS_PN = "NP1";
"NP2":   PN = "NP2"  !CDS_PN = "NP2";
"PTH1":   PN = "PTH1"  !CDS_PN = "PTH1";
"PTH2":   PN = "PTH2"  !CDS_PN = "PTH2";
DRAWING = "@baseboard_fab2_lib.baseboard_fab2(sch_1):page109";
BODY = "SCONN200_H68296001","I78": #LOCATION = "J8G1" !CDS_LOCATION = "J8G1" #SEC = "2" !CDS_SEC = "2";
"IO101":   PN = "101"  !CDS_PN = "101";
"IO102":   PN = "102"  !CDS_PN = "102";
"IO103":   PN = "103"  !CDS_PN = "103";
"IO104":   PN = "104"  !CDS_PN = "104";
"IO105":   PN = "105"  !CDS_PN = "105";
"IO106":   PN = "106"  !CDS_PN = "106";
"IO107":   PN = "107"  !CDS_PN = "107";
"IO108":   PN = "108"  !CDS_PN = "108";
"IO109":   PN = "109"  !CDS_PN = "109";
"IO110":   PN = "110"  !CDS_PN = "110";
"IO111":   PN = "111"  !CDS_PN = "111";
"IO112":   PN = "112"  !CDS_PN = "112";
"IO113":   PN = "113"  !CDS_PN = "113";
"IO114":   PN = "114"  !CDS_PN = "114";
"IO115":   PN = "115"  !CDS_PN = "115";
"IO116":   PN = "116"  !CDS_PN = "116";
"IO117":   PN = "117"  !CDS_PN = "117";
"IO118":   PN = "118"  !CDS_PN = "118";
"IO119":   PN = "119"  !CDS_PN = "119";
"IO120":   PN = "120"  !CDS_PN = "120";
"IO121":   PN = "121"  !CDS_PN = "121";
"IO122":   PN = "122"  !CDS_PN = "122";
"IO123":   PN = "123"  !CDS_PN = "123";
"IO124":   PN = "124"  !CDS_PN = "124";
"IO125":   PN = "125"  !CDS_PN = "125";
"IO126":   PN = "126"  !CDS_PN = "126";
"IO127":   PN = "127"  !CDS_PN = "127";
"IO128":   PN = "128"  !CDS_PN = "128";
"IO129":   PN = "129"  !CDS_PN = "129";
"IO130":   PN = "130"  !CDS_PN = "130";
"IO131":   PN = "131"  !CDS_PN = "131";
"IO132":   PN = "132"  !CDS_PN = "132";
"IO133":   PN = "133"  !CDS_PN = "133";
"IO134":   PN = "134"  !CDS_PN = "134";
"IO135":   PN = "135"  !CDS_PN = "135";
"IO136":   PN = "136"  !CDS_PN = "136";
"IO137":   PN = "137"  !CDS_PN = "137";
"IO138":   PN = "138"  !CDS_PN = "138";
"IO139":   PN = "139"  !CDS_PN = "139";
"IO140":   PN = "140"  !CDS_PN = "140";
"IO141":   PN = "141"  !CDS_PN = "141";
"IO142":   PN = "142"  !CDS_PN = "142";
"IO143":   PN = "143"  !CDS_PN = "143";
"IO144":   PN = "144"  !CDS_PN = "144";
"IO145":   PN = "145"  !CDS_PN = "145";
"IO146":   PN = "146"  !CDS_PN = "146";
"IO147":   PN = "147"  !CDS_PN = "147";
"IO148":   PN = "148"  !CDS_PN = "148";
"IO149":   PN = "149"  !CDS_PN = "149";
"IO150":   PN = "150"  !CDS_PN = "150";
"IO151":   PN = "151"  !CDS_PN = "151";
"IO152":   PN = "152"  !CDS_PN = "152";
"IO153":   PN = "153"  !CDS_PN = "153";
"IO154":   PN = "154"  !CDS_PN = "154";
"IO155":   PN = "155"  !CDS_PN = "155";
"IO156":   PN = "156"  !CDS_PN = "156";
"IO157":   PN = "157"  !CDS_PN = "157";
"IO158":   PN = "158"  !CDS_PN = "158";
"IO159":   PN = "159"  !CDS_PN = "159";
"IO160":   PN = "160"  !CDS_PN = "160";
"IO161":   PN = "161"  !CDS_PN = "161";
"IO162":   PN = "162"  !CDS_PN = "162";
"IO163":   PN = "163"  !CDS_PN = "163";
"IO164":   PN = "164"  !CDS_PN = "164";
"IO165":   PN = "165"  !CDS_PN = "165";
"IO166":   PN = "166"  !CDS_PN = "166";
"IO167":   PN = "167"  !CDS_PN = "167";
"IO168":   PN = "168"  !CDS_PN = "168";
"IO169":   PN = "169"  !CDS_PN = "169";
"IO170":   PN = "170"  !CDS_PN = "170";
"IO171":   PN = "171"  !CDS_PN = "171";
"IO172":   PN = "172"  !CDS_PN = "172";
"IO173":   PN = "173"  !CDS_PN = "173";
"IO174":   PN = "174"  !CDS_PN = "174";
"IO175":   PN = "175"  !CDS_PN = "175";
"IO176":   PN = "176"  !CDS_PN = "176";
"IO177":   PN = "177"  !CDS_PN = "177";
"IO178":   PN = "178"  !CDS_PN = "178";
"IO179":   PN = "179"  !CDS_PN = "179";
"IO180":   PN = "180"  !CDS_PN = "180";
"IO181":   PN = "181"  !CDS_PN = "181";
"IO182":   PN = "182"  !CDS_PN = "182";
"IO183":   PN = "183"  !CDS_PN = "183";
"IO184":   PN = "184"  !CDS_PN = "184";
"IO185":   PN = "185"  !CDS_PN = "185";
"IO186":   PN = "186"  !CDS_PN = "186";
"IO187":   PN = "187"  !CDS_PN = "187";
"IO188":   PN = "188"  !CDS_PN = "188";
"IO189":   PN = "189"  !CDS_PN = "189";
"IO190":   PN = "190"  !CDS_PN = "190";
"IO191":   PN = "191"  !CDS_PN = "191";
"IO192":   PN = "192"  !CDS_PN = "192";
"IO193":   PN = "193"  !CDS_PN = "193";
"IO194":   PN = "194"  !CDS_PN = "194";
"IO195":   PN = "195"  !CDS_PN = "195";
"IO196":   PN = "196"  !CDS_PN = "196";
"IO197":   PN = "197"  !CDS_PN = "197";
"IO198":   PN = "198"  !CDS_PN = "198";
"IO199":   PN = "199"  !CDS_PN = "199";
"IO200":   PN = "200"  !CDS_PN = "200";
DRAWING = "@baseboard_fab2_lib.baseboard_fab2(sch_1):page246";
BODY = "RES","I5": #LOCATION = "RN8F1" !CDS_LOCATION = "RN8F1" &SEC = "1" #&CDS_SEC = "1";
"A":   PN = "1"  !CDS_PN = "1";
"B":   PN = "2"  !CDS_PN = "2";
BODY = "RES","I8": #LOCATION = "RN8F6" !CDS_LOCATION = "RN8F6" &SEC = "1" #&CDS_SEC = "1";
"A":   PN = "1"  !CDS_PN = "1";
"B":   PN = "2"  !CDS_PN = "2";
BODY = "RES","I9": #LOCATION = "RN8F5" !CDS_LOCATION = "RN8F5" #SEC = "1" !CDS_SEC = "1";
"A":   PN = "1"  !CDS_PN = "1";
"B":   PN = "2"  !CDS_PN = "2";
BODY = "RES","I10": #LOCATION = "RN8F2" !CDS_LOCATION = "RN8F2" &SEC = "1" #&CDS_SEC = "1";
"A":   PN = "1"  !CDS_PN = "1";
"B":   PN = "2"  !CDS_PN = "2";
BODY = "RES","I11": #LOCATION = "RN8F3" !CDS_LOCATION = "RN8F3" #SEC = "1" !CDS_SEC = "1";
"A":   PN = "1"  !CDS_PN = "1";
"B":   PN = "2"  !CDS_PN = "2";
BODY = "RES","I12": #LOCATION = "RN8F4" !CDS_LOCATION = "RN8F4" #SEC = "1" !CDS_SEC = "1";
"A":   PN = "1"  !CDS_PN = "1";
"B":   PN = "2"  !CDS_PN = "2";
BODY = "CAP","I15": #LOCATION = "CN8F1" !CDS_LOCATION = "CN8F1" &SEC = "1" #&CDS_SEC = "1";
"A":   PN = "1"  !CDS_PN = "1";
"B":   PN = "2"  !CDS_PN = "2";
BODY = "CAP","I16": #LOCATION = "CN8F2" !CDS_LOCATION = "CN8F2" &SEC = "1" #&CDS_SEC = "1";
"A":   PN = "1"  !CDS_PN = "1";
"B":   PN = "2"  !CDS_PN = "2";
BODY = "W25Q256","I17": #LOCATION = "UN8F2" !CDS_LOCATION = "UN8F2" #SEC = "1" !CDS_SEC = "1";
"CLK":   PN = "16"  !CDS_PN = "16";
"CS_N":   PN = "7"  !CDS_PN = "7";
"DI_IO<0>":   PN = "15"  !CDS_PN = "15";
"DO_IO<1>":   PN = "8"  !CDS_PN = "8";
"GND":   PN = "10"  !CDS_PN = "10";
"HOLD_N_IO<3>":   PN = "1"  !CDS_PN = "1";
"NC<0>":   PN = "14"  !CDS_PN = "14";
"NC<1>":   PN = "13"  !CDS_PN = "13";
"NC<2>":   PN = "12"  !CDS_PN = "12";
"NC<3>":   PN = "11"  !CDS_PN = "11";
"NC<4>":   PN = "6"  !CDS_PN = "6";
"NC<5>":   PN = "5"  !CDS_PN = "5";
"NC<6>":   PN = "4"  !CDS_PN = "4";
"RESET_N":   PN = "3"  !CDS_PN = "3";
"VCC":   PN = "2"  !CDS_PN = "2";
"WP_N_IO<2>":   PN = "9"  !CDS_PN = "9";
DRAWING = "@baseboard_fab2_lib.baseboard_fab2(sch_1):page247";
BODY = "RES","I1": #LOCATION = "R6W10" !CDS_LOCATION = "R6W10" &SEC = "1" #&CDS_SEC = "1";
"A":   PN = "1"  !CDS_PN = "1";
"B":   PN = "2"  !CDS_PN = "2";
BODY = "RES","I3": #LOCATION = "R6W7" !CDS_LOCATION = "R6W7" &SEC = "1" #&CDS_SEC = "1";
"A":   PN = "1"  !CDS_PN = "1";
"B":   PN = "2"  !CDS_PN = "2";
BODY = "RES","I5": #LOCATION = "R6W4" !CDS_LOCATION = "R6W4" &SEC = "1" #&CDS_SEC = "1";
"A":   PN = "1"  !CDS_PN = "1";
"B":   PN = "2"  !CDS_PN = "2";
BODY = "RES","I8": #LOCATION = "R6W8" !CDS_LOCATION = "R6W8" &SEC = "1" #&CDS_SEC = "1";
"A":   PN = "1"  !CDS_PN = "1";
"B":   PN = "2"  !CDS_PN = "2";
BODY = "RES","I9": #LOCATION = "R6W9" !CDS_LOCATION = "R6W9" &SEC = "1" #&CDS_SEC = "1";
"A":   PN = "1"  !CDS_PN = "1";
"B":   PN = "2"  !CDS_PN = "2";
BODY = "RES","I10": #LOCATION = "R6W5" !CDS_LOCATION = "R6W5" &SEC = "1" #&CDS_SEC = "1";
"A":   PN = "1"  !CDS_PN = "1";
"B":   PN = "2"  !CDS_PN = "2";
BODY = "RES","I11": #LOCATION = "R6W6" !CDS_LOCATION = "R6W6" &SEC = "1" #&CDS_SEC = "1";
"A":   PN = "1"  !CDS_PN = "1";
"B":   PN = "2"  !CDS_PN = "2";
BODY = "CAP","I18": #LOCATION = "C6W1" !CDS_LOCATION = "C6W1" &SEC = "1" #&CDS_SEC = "1";
"A":   PN = "1"  !CDS_PN = "1";
"B":   PN = "2"  !CDS_PN = "2";
BODY = "RES","I67": #LOCATION = "R6W11" !CDS_LOCATION = "R6W11" &SEC = "1" #&CDS_SEC = "1";
"A":   PN = "1"  !CDS_PN = "1";
"B":   PN = "2"  !CDS_PN = "2";
BODY = "RES","I68": #LOCATION = "R6W12" !CDS_LOCATION = "R6W12" &SEC = "1" #&CDS_SEC = "1";
"A":   PN = "1"  !CDS_PN = "1";
"B":   PN = "2"  !CDS_PN = "2";
BODY = "PCA9515ADGKR-1-GP","I77": #LOCATION = "U6W2" !CDS_LOCATION = "U6W2" &SEC = "1" #&CDS_SEC = "1";
"EN":   PN = "5"  !CDS_PN = "5";
"GND":   PN = "4"  !CDS_PN = "4";
"NC#1":   PN = "1"  !CDS_PN = "1";
"SCL0":   PN = "2"  !CDS_PN = "2";
"SCL1":   PN = "7"  !CDS_PN = "7";
"SDA0":   PN = "3"  !CDS_PN = "3";
"SDA1":   PN = "6"  !CDS_PN = "6";
"VCC":   PN = "8"  !CDS_PN = "8";
BODY = "CAP","I81": #LOCATION = "C6W2" !CDS_LOCATION = "C6W2" &SEC = "1" #&CDS_SEC = "1";
"A":   PN = "1"  !CDS_PN = "1";
"B":   PN = "2"  !CDS_PN = "2";
BODY = "CAP_A","I85": #LOCATION = "C6W3" !CDS_LOCATION = "C6W3" #SEC = "1" !CDS_SEC = "1";
"A":   PN = "1"  !CDS_PN = "1";
"B":   PN = "2"  !CDS_PN = "2";
BODY = "RES","I87": #LOCATION = "R6W20" !CDS_LOCATION = "R6W20" &SEC = "1" #&CDS_SEC = "1";
"A":   PN = "1"  !CDS_PN = "1";
"B":   PN = "2"  !CDS_PN = "2";
BODY = "AT24C64","I89": #LOCATION = "U6W3" !CDS_LOCATION = "U6W3" #SEC = "1" !CDS_SEC = "1";
"A0":   PN = "1"  !CDS_PN = "1";
"A1":   PN = "2"  !CDS_PN = "2";
"A2":   PN = "3"  !CDS_PN = "3";
"SCL":   PN = "6"  !CDS_PN = "6";
"SDA":   PN = "5"  !CDS_PN = "5";
"WP":   PN = "7"  !CDS_PN = "7";
BODY = "RES","I90": #LOCATION = "R6W21" !CDS_LOCATION = "R6W21" #SEC = "1" !CDS_SEC = "1";
"A":   PN = "1"  !CDS_PN = "1";
"B":   PN = "2"  !CDS_PN = "2";
BODY = "RES","I92": #LOCATION = "R6W23" !CDS_LOCATION = "R6W23" #SEC = "1" !CDS_SEC = "1";
"A":   PN = "1"  !CDS_PN = "1";
"B":   PN = "2"  !CDS_PN = "2";
BODY = "RES","I94": #LOCATION = "R6W22" !CDS_LOCATION = "R6W22" #SEC = "1" !CDS_SEC = "1";
"A":   PN = "1"  !CDS_PN = "1";
"B":   PN = "2"  !CDS_PN = "2";
BODY = "PCA9555PWRG4-GP","I97": #LOCATION = "U6W1" !CDS_LOCATION = "U6W1" &SEC = "1" #&CDS_SEC = "1";
"A0":   PN = "21"  !CDS_PN = "21";
"A1":   PN = "2"  !CDS_PN = "2";
"A2":   PN = "3"  !CDS_PN = "3";
"GND":   PN = "12"  !CDS_PN = "12";
"INT#":   PN = "1"  !CDS_PN = "1";
"P0":   PN = "4"  !CDS_PN = "4";
"P1":   PN = "5"  !CDS_PN = "5";
"P2":   PN = "6"  !CDS_PN = "6";
"P3":   PN = "7"  !CDS_PN = "7";
"P4":   PN = "8"  !CDS_PN = "8";
"P5":   PN = "9"  !CDS_PN = "9";
"P6":   PN = "10"  !CDS_PN = "10";
"P7":   PN = "11"  !CDS_PN = "11";
"P10":   PN = "13"  !CDS_PN = "13";
"P11":   PN = "14"  !CDS_PN = "14";
"P12":   PN = "15"  !CDS_PN = "15";
"P13":   PN = "16"  !CDS_PN = "16";
"P14":   PN = "17"  !CDS_PN = "17";
"P15":   PN = "18"  !CDS_PN = "18";
"P16":   PN = "19"  !CDS_PN = "19";
"P17":   PN = "20"  !CDS_PN = "20";
"SCL":   PN = "22"  !CDS_PN = "22";
"SDA":   PN = "23"  !CDS_PN = "23";
"VCC":   PN = "24"  !CDS_PN = "24";
DRAWING = "@baseboard_fab2_lib.baseboard_fab2(sch_1):page249";
BODY = "RES","I2": #LOCATION = "R3W1" !CDS_LOCATION = "R3W1" &SEC = "1" #&CDS_SEC = "1";
"A":   PN = "1"  !CDS_PN = "1";
"B":   PN = "2"  !CDS_PN = "2";
BODY = "RES","I7": #LOCATION = "R3W9" !CDS_LOCATION = "R3W9" &SEC = "1" #&CDS_SEC = "1";
"A":   PN = "1"  !CDS_PN = "1";
"B":   PN = "2"  !CDS_PN = "2";
BODY = "RES","I8": #LOCATION = "R3W7" !CDS_LOCATION = "R3W7" &SEC = "1" #&CDS_SEC = "1";
"A":   PN = "1"  !CDS_PN = "1";
"B":   PN = "2"  !CDS_PN = "2";
BODY = "RES","I12": #LOCATION = "R3W2" !CDS_LOCATION = "R3W2" &SEC = "1" #&CDS_SEC = "1";
"A":   PN = "1"  !CDS_PN = "1";
"B":   PN = "2"  !CDS_PN = "2";
BODY = "LMV331IDCKRG4-GP","I15": #LOCATION = "Q9W4" !CDS_LOCATION = "Q9W4" &SEC = "1" #&CDS_SEC = "1";
"+IN":   PN = "1"  !CDS_PN = "1";
"-IN":   PN = "3"  !CDS_PN = "3";
"GND":   PN = "2"  !CDS_PN = "2";
"OUT":   PN = "4"  !CDS_PN = "4";
"VCC":   PN = "5"  !CDS_PN = "5";
BODY = "RES","I17": #LOCATION = "R3W3" !CDS_LOCATION = "R3W3" &SEC = "1" #&CDS_SEC = "1";
"A":   PN = "1"  !CDS_PN = "1";
"B":   PN = "2"  !CDS_PN = "2";
BODY = "CAP","I21": #LOCATION = "C8W2" !CDS_LOCATION = "C8W2" &SEC = "1" #&CDS_SEC = "1";
"A":   PN = "1"  !CDS_PN = "1";
"B":   PN = "2"  !CDS_PN = "2";
BODY = "NPN","I26": #LOCATION = "Q9W3" !CDS_LOCATION = "Q9W3" &SEC = "1" #&CDS_SEC = "1";
"B":   PN = "1"  !CDS_PN = "1";
"C":   PN = "3"  !CDS_PN = "3";
"E":   PN = "2"  !CDS_PN = "2";
BODY = "RES","I27": #LOCATION = "R3W6" !CDS_LOCATION = "R3W6" &SEC = "1" #&CDS_SEC = "1";
"A":   PN = "1"  !CDS_PN = "1";
"B":   PN = "2"  !CDS_PN = "2";
BODY = "NPN","I29": #LOCATION = "Q9W2" !CDS_LOCATION = "Q9W2" &SEC = "1" #&CDS_SEC = "1";
"B":   PN = "1"  !CDS_PN = "1";
"C":   PN = "3"  !CDS_PN = "3";
"E":   PN = "2"  !CDS_PN = "2";
BODY = "FET_N","I30": #LOCATION = "Q9W1" !CDS_LOCATION = "Q9W1" &SEC = "1" #&CDS_SEC = "1";
"DRN":   PN = "3"  !CDS_PN = "3";
"GATE":   PN = "1"  !CDS_PN = "1";
"SRC":   PN = "2"  !CDS_PN = "2";
BODY = "47KR2F-GP","I31": #LOCATION = "R3W4" !CDS_LOCATION = "R3W4" &SEC = "1" #&CDS_SEC = "1";
"1":   PN = "1"  !CDS_PN = "1";
"2":   PN = "2"  !CDS_PN = "2";
BODY = "CAP","I32": #LOCATION = "C8W1" !CDS_LOCATION = "C8W1" &SEC = "1" #&CDS_SEC = "1";
"A":   PN = "1"  !CDS_PN = "1";
"B":   PN = "2"  !CDS_PN = "2";
BODY = "82K5R2F-GP","I33": #LOCATION = "R3W5" !CDS_LOCATION = "R3W5" &SEC = "1" #&CDS_SEC = "1";
"1":   PN = "1"  !CDS_PN = "1";
"2":   PN = "2"  !CDS_PN = "2";
DRAWING = "@baseboard_fab2_lib.baseboard_fab2(sch_1):page143";
BODY = "CAP","I55": #LOCATION = "C25W22" !CDS_LOCATION = "C25W22" &SEC = "1" #&CDS_SEC = "1";
"A":   PN = "1"  !CDS_PN = "1";
"B":   PN = "2"  !CDS_PN = "2";
BODY = "RES","I58": #LOCATION = "R1T27" !CDS_LOCATION = "R1T27" &SEC = "1" #&CDS_SEC = "1";
"A":   PN = "1"  !CDS_PN = "1";
"B":   PN = "2"  !CDS_PN = "2";
BODY = "AST2520A1-GP-GP","I63": #LOCATION = "U25W4" !CDS_LOCATION = "U25W4" &SEC = "1" #&CDS_SEC = "1";
"MA0":   PN = "V13"  !CDS_PN = "V13";
"MA1":   PN = "AB14"  !CDS_PN = "AB14";
"MA2":   PN = "W14"  !CDS_PN = "W14";
"MA3":   PN = "U14"  !CDS_PN = "U14";
"MA4":   PN = "W15"  !CDS_PN = "W15";
"MA5":   PN = "V15"  !CDS_PN = "V15";
"MA6":   PN = "AB16"  !CDS_PN = "AB16";
"MA7":   PN = "AA16"  !CDS_PN = "AA16";
"MA8":   PN = "W16"  !CDS_PN = "W16";
"MA9":   PN = "Y16"  !CDS_PN = "Y16";
"MA10":   PN = "U13"  !CDS_PN = "U13";
"MA11":   PN = "AA14"  !CDS_PN = "AA14";
"MA12":   PN = "Y14"  !CDS_PN = "Y14";
"MA13":   PN = "AB15"  !CDS_PN = "AB15";
"MA14_MACT#":   PN = "Y15"  !CDS_PN = "Y15";
"MA15":   PN = "U15"  !CDS_PN = "U15";
"MBA0":   PN = "U12"  !CDS_PN = "U12";
"MBA1":   PN = "Y13"  !CDS_PN = "Y13";
"MBA2_MBG0":   PN = "W13"  !CDS_PN = "W13";
"MCAS#":   PN = "AB13"  !CDS_PN = "AB13";
"MCKE":   PN = "Y11"  !CDS_PN = "Y11";
"MCKN":   PN = "AB12"  !CDS_PN = "AB12";
"MCKP":   PN = "AB11"  !CDS_PN = "AB11";
"MCS#":   PN = "AA12"  !CDS_PN = "AA12";
"MDM0":   PN = "U8"  !CDS_PN = "U8";
"MDM1":   PN = "AB8"  !CDS_PN = "AB8";
"MDQ0":   PN = "U10"  !CDS_PN = "U10";
"MDQ1":   PN = "W10"  !CDS_PN = "W10";
"MDQ2":   PN = "Y10"  !CDS_PN = "Y10";
"MDQ3":   PN = "AA10"  !CDS_PN = "AA10";
"MDQ4":   PN = "U9"  !CDS_PN = "U9";
"MDQ5":   PN = "Y9"  !CDS_PN = "Y9";
"MDQ6":   PN = "W9"  !CDS_PN = "W9";
"MDQ7":   PN = "V9"  !CDS_PN = "V9";
"MDQ8":   PN = "AA8"  !CDS_PN = "AA8";
"MDQ9":   PN = "Y8"  !CDS_PN = "Y8";
"MDQ10":   PN = "Y7"  !CDS_PN = "Y7";
"MDQ11":   PN = "W8"  !CDS_PN = "W8";
"MDQ12":   PN = "AA6"  !CDS_PN = "AA6";
"MDQ13":   PN = "W7"  !CDS_PN = "W7";
"MDQ14":   PN = "V7"  !CDS_PN = "V7";
"MDQ15":   PN = "U7"  !CDS_PN = "U7";
"MDQS0N":   PN = "AB10"  !CDS_PN = "AB10";
"MDQS0P":   PN = "AB9"  !CDS_PN = "AB9";
"MDQS1N":   PN = "AB6"  !CDS_PN = "AB6";
"MDQS1P":   PN = "AB7"  !CDS_PN = "AB7";
"MIOZ":   PN = "W11"  !CDS_PN = "W11";
"MODT":   PN = "V11"  !CDS_PN = "V11";
"MRAS#":   PN = "W12"  !CDS_PN = "W12";
"MVREF":   PN = "T9"  !CDS_PN = "T9";
"MWE#":   PN = "Y12"  !CDS_PN = "Y12";
DRAWING = "@baseboard_fab2_lib.baseboard_fab2(sch_1):page144";
BODY = "RES","I57": #LOCATION = "R1U14" !CDS_LOCATION = "R1U14" &SEC = "1" #&CDS_SEC = "1";
"A":   PN = "1"  !CDS_PN = "1";
"B":   PN = "2"  !CDS_PN = "2";
BODY = "RES","I58": #LOCATION = "R1U13" !CDS_LOCATION = "R1U13" &SEC = "1" #&CDS_SEC = "1";
"A":   PN = "1"  !CDS_PN = "1";
"B":   PN = "2"  !CDS_PN = "2";
BODY = "RES","I59": #LOCATION = "R1U12" !CDS_LOCATION = "R1U12" &SEC = "1" #&CDS_SEC = "1";
"A":   PN = "1"  !CDS_PN = "1";
"B":   PN = "2"  !CDS_PN = "2";
BODY = "RES","I73": #LOCATION = "R25W58" !CDS_LOCATION = "R25W58" #SEC = "1" !CDS_SEC = "1";
"A":   PN = "1"  !CDS_PN = "1";
"B":   PN = "2"  !CDS_PN = "2";
BODY = "RES","I82": #LOCATION = "R1T24" !CDS_LOCATION = "R1T24" #SEC = "1" !CDS_SEC = "1";
"A":   PN = "1"  !CDS_PN = "1";
"B":   PN = "2"  !CDS_PN = "2";
BODY = "RES","I89": #LOCATION = "R6W17" !CDS_LOCATION = "R6W17" &SEC = "1" #&CDS_SEC = "1";
"A":   PN = "1"  !CDS_PN = "1";
"B":   PN = "2"  !CDS_PN = "2";
BODY = "RES","I90": #LOCATION = "R6W18" !CDS_LOCATION = "R6W18" &SEC = "1" #&CDS_SEC = "1";
"A":   PN = "1"  !CDS_PN = "1";
"B":   PN = "2"  !CDS_PN = "2";
BODY = "AST2520A1-GP-GP","I95": #LOCATION = "U25W4" !CDS_LOCATION = "U25W4" &SEC = "2" #&CDS_SEC = "2";
"DACB":   PN = "J2"  !CDS_PN = "J2";
"DACG":   PN = "J3"  !CDS_PN = "J3";
"DACR":   PN = "J4"  !CDS_PN = "J4";
"DACRSET":   PN = "K4"  !CDS_PN = "K4";
"GPIOA4_TIMER5_SCL9":   PN = "C14"  !CDS_PN = "C14";
"GPIOA5_TIMER6_SDA9":   PN = "A13"  !CDS_PN = "A13";
"GPIOB0":   PN = "K19"  !CDS_PN = "K19";
"GPIOB1":   PN = "L19"  !CDS_PN = "L19";
"GPIOB2":   PN = "L18"  !CDS_PN = "L18";
"GPIOB3":   PN = "K18"  !CDS_PN = "K18";
"GPIOB4_USBCKI":   PN = "J20"  !CDS_PN = "J20";
"GPIOB5_LPCPD#_LPCSMI#":   PN = "H21"  !CDS_PN = "H21";
"GPIOB6_LPCPME#":   PN = "H22"  !CDS_PN = "H22";
"GPIOB7":   PN = "H20"  !CDS_PN = "H20";
"GPIOG0_SGPS1CK":   PN = "A19"  !CDS_PN = "A19";
"GPIOG1_SGPS1LD":   PN = "E19"  !CDS_PN = "E19";
"GPIOG2_SGPS1I0":   PN = "C19"  !CDS_PN = "C19";
"GPIOG3_SGPS1I1":   PN = "E16"  !CDS_PN = "E16";
"GPIOI0_SYSCS#":   PN = "C18"  !CDS_PN = "C18";
"GPIOI1_SYSCK":   PN = "E15"  !CDS_PN = "E15";
"GPIOI2_SYSMOSI":   PN = "B16"  !CDS_PN = "B16";
"GPIOI3_SYSMISO":   PN = "C16"  !CDS_PN = "C16";
"GPIOI4_SPI1CS0#_VBCS#":   PN = "B15"  !CDS_PN = "B15";
"GPIOI5_SPI1CK_VBCK":   PN = "C15"  !CDS_PN = "C15";
"GPIOI6_SPI1MOSI_VBMOSI":   PN = "A14"  !CDS_PN = "A14";
"GPIOI7_SPI1MISO_VBMISO":   PN = "A15"  !CDS_PN = "A15";
"GPIOJ0_SGPMCK":   PN = "R2"  !CDS_PN = "R2";
"GPIOJ1_SGPMLD":   PN = "L2"  !CDS_PN = "L2";
"GPIOJ2_SGPMO":   PN = "N3"  !CDS_PN = "N3";
"GPIOJ3_SGPMI":   PN = "N4"  !CDS_PN = "N4";
"GPIOK0_SCL5":   PN = "L3"  !CDS_PN = "L3";
"GPIOK1_SDA5":   PN = "L4"  !CDS_PN = "L4";
"GPIOK2_SCL6":   PN = "L1"  !CDS_PN = "L1";
"GPIOK3_SDA6":   PN = "N2"  !CDS_PN = "N2";
"GPIOK4_SCL7":   PN = "N1"  !CDS_PN = "N1";
"GPIOK5_SDA7":   PN = "P1"  !CDS_PN = "P1";
"GPIOK6_SCL8":   PN = "P2"  !CDS_PN = "P2";
"GPIOK7_SDA8":   PN = "R1"  !CDS_PN = "R1";
"GPIOQ0_SCL3":   PN = "A11"  !CDS_PN = "A11";
"GPIOQ1_SDA3":   PN = "A10"  !CDS_PN = "A10";
"GPIOQ2_SCL4":   PN = "A9"  !CDS_PN = "A9";
"GPIOQ3_SDA4":   PN = "B9"  !CDS_PN = "B9";
"GPIOQ4_SCL14":   PN = "N21"  !CDS_PN = "N21";
"GPIOQ5_SDA14":   PN = "N22"  !CDS_PN = "N22";
"GPIOY4_SCL1":   PN = "M18"  !CDS_PN = "M18";
"GPIOY5_SDA1":   PN = "M19"  !CDS_PN = "M19";
"GPIOY6_SCL2":   PN = "M20"  !CDS_PN = "M20";
"GPIOY7_SDA2":   PN = "P20"  !CDS_PN = "P20";
"NTRST":   PN = "E11"  !CDS_PN = "E11";
"RTCK":   PN = "C9"  !CDS_PN = "C9";
"TCK":   PN = "C10"  !CDS_PN = "C10";
"TDI":   PN = "D12"  !CDS_PN = "D12";
"TDO":   PN = "D11"  !CDS_PN = "D11";
"TMS":   PN = "C8"  !CDS_PN = "C8";
DRAWING = "@baseboard_fab2_lib.baseboard_fab2(sch_1):page145";
BODY = "OSC_C","I8": #LOCATION = "Y9F2" !CDS_LOCATION = "Y9F2" #SEC = "1" !CDS_SEC = "1";
"ENABLE_CONTROL":   PN = "1"  !CDS_PN = "1";
"GND":   PN = "2"  !CDS_PN = "2";
"OUT":   PN = "3"  !CDS_PN = "3";
"VDD":   PN = "4"  !CDS_PN = "4";
BODY = "RES","I10": #LOCATION = "R9F60" !CDS_LOCATION = "R9F60" #SEC = "1" !CDS_SEC = "1";
"A":   PN = "1"  !CDS_PN = "1";
"B":   PN = "2"  !CDS_PN = "2";
BODY = "RES","I11": #LOCATION = "R9F62" !CDS_LOCATION = "R9F62" #SEC = "1" !CDS_SEC = "1";
"A":   PN = "1"  !CDS_PN = "1";
"B":   PN = "2"  !CDS_PN = "2";
BODY = "RES","I14": #LOCATION = "R9F61" !CDS_LOCATION = "R9F61" #SEC = "1" !CDS_SEC = "1";
"A":   PN = "1"  !CDS_PN = "1";
"B":   PN = "2"  !CDS_PN = "2";
BODY = "CAP_A","I15": #LOCATION = "C9F23" !CDS_LOCATION = "C9F23" #SEC = "1" !CDS_SEC = "1";
"A":   PN = "1"  !CDS_PN = "1";
"B":   PN = "2"  !CDS_PN = "2";
BODY = "RES","I20": #LOCATION = "R9F33" !CDS_LOCATION = "R9F33" #SEC = "1" !CDS_SEC = "1";
"A":   PN = "1"  !CDS_PN = "1";
"B":   PN = "2"  !CDS_PN = "2";
BODY = "RES","I22": #LOCATION = "R9F20" !CDS_LOCATION = "R9F20" #SEC = "1" !CDS_SEC = "1";
"A":   PN = "1"  !CDS_PN = "1";
"B":   PN = "2"  !CDS_PN = "2";
BODY = "RES","I30": #LOCATION = "R25W61" !CDS_LOCATION = "R25W61" #SEC = "1" !CDS_SEC = "1";
"A":   PN = "1"  !CDS_PN = "1";
"B":   PN = "2"  !CDS_PN = "2";
BODY = "RES","I31": #LOCATION = "R25W62" !CDS_LOCATION = "R25W62" #SEC = "1" !CDS_SEC = "1";
"A":   PN = "1"  !CDS_PN = "1";
"B":   PN = "2"  !CDS_PN = "2";
BODY = "RES","I34": #LOCATION = "R25W60" !CDS_LOCATION = "R25W60" #SEC = "1" !CDS_SEC = "1";
"A":   PN = "1"  !CDS_PN = "1";
"B":   PN = "2"  !CDS_PN = "2";
BODY = "RES","I36": #LOCATION = "R25W64" !CDS_LOCATION = "R25W64" #SEC = "1" !CDS_SEC = "1";
"A":   PN = "1"  !CDS_PN = "1";
"B":   PN = "2"  !CDS_PN = "2";
BODY = "RES","I38": #LOCATION = "R25W65" !CDS_LOCATION = "R25W65" #SEC = "1" !CDS_SEC = "1";
"A":   PN = "1"  !CDS_PN = "1";
"B":   PN = "2"  !CDS_PN = "2";
BODY = "CAP_A","I44": #LOCATION = "C25W21" !CDS_LOCATION = "C25W21" #SEC = "1" !CDS_SEC = "1";
"A":   PN = "1"  !CDS_PN = "1";
"B":   PN = "2"  !CDS_PN = "2";
BODY = "CAP_A","I45": #LOCATION = "C25W20" !CDS_LOCATION = "C25W20" #SEC = "1" !CDS_SEC = "1";
"A":   PN = "1"  !CDS_PN = "1";
"B":   PN = "2"  !CDS_PN = "2";
BODY = "RES","I46": #LOCATION = "R25W67" !CDS_LOCATION = "R25W67" #SEC = "1" !CDS_SEC = "1";
"A":   PN = "1"  !CDS_PN = "1";
"B":   PN = "2"  !CDS_PN = "2";
BODY = "RES","I100": #LOCATION = "R1T15" !CDS_LOCATION = "R1T15" &SEC = "1" #&CDS_SEC = "1";
"A":   PN = "1"  !CDS_PN = "1";
"B":   PN = "2"  !CDS_PN = "2";
BODY = "RES","I101": #LOCATION = "R1T23" !CDS_LOCATION = "R1T23" &SEC = "1" #&CDS_SEC = "1";
"A":   PN = "1"  !CDS_PN = "1";
"B":   PN = "2"  !CDS_PN = "2";
BODY = "AST2520A1-GP-GP","I117": #LOCATION = "U25W4" !CDS_LOCATION = "U25W4" &SEC = "3" #&CDS_SEC = "3";
"CLKIN":   PN = "W18"  !CDS_PN = "W18";
"GPIOA0_MAC1LINK":   PN = "B14"  !CDS_PN = "B14";
"GPIOA1_MAC2LINK":   PN = "D14"  !CDS_PN = "D14";
"GPIOA2_TIMER3_SPI1CS1#":   PN = "D13"  !CDS_PN = "D13";
"GPIOA3_TIMER4":   PN = "E13"  !CDS_PN = "E13";
"GPIOC0_SD1CLK_SCL10":   PN = "C12"  !CDS_PN = "C12";
"GPIOC1_SD1CMD_SDA10":   PN = "A12"  !CDS_PN = "A12";
"GPIOC2_SD1DAT0_SCL11":   PN = "B12"  !CDS_PN = "B12";
"GPIOC3_SD1DAT1_SDA11":   PN = "D9"  !CDS_PN = "D9";
"GPIOC4_SD1DAT2_SCL12":   PN = "D10"  !CDS_PN = "D10";
"GPIOC5_SD1DAT3_SDA12":   PN = "E12"  !CDS_PN = "E12";
"GPIOC6_SD1CD#_SCL13":   PN = "C11"  !CDS_PN = "C11";
"GPIOC7_SD1WP#_SDA13":   PN = "B11"  !CDS_PN = "B11";
"GPIOD0_SD2CLK":   PN = "F19"  !CDS_PN = "F19";
"GPIOD1_SD2CMD":   PN = "E21"  !CDS_PN = "E21";
"GPIOD2_SD2DAT0":   PN = "F20"  !CDS_PN = "F20";
"GPIOD3_SD2DAT1":   PN = "D20"  !CDS_PN = "D20";
"GPIOD4_SD2DAT2":   PN = "D21"  !CDS_PN = "D21";
"GPIOD5_SD2DAT3":   PN = "E20"  !CDS_PN = "E20";
"GPIOD6_SD2CD#":   PN = "G18"  !CDS_PN = "G18";
"GPIOD7_SD2WP#":   PN = "C21"  !CDS_PN = "C21";
"GPIOE0_NCTS3":   PN = "B20"  !CDS_PN = "B20";
"GPIOE1_NDCD3":   PN = "C20"  !CDS_PN = "C20";
"GPIOE2_NDSR3":   PN = "F18"  !CDS_PN = "F18";
"GPIOE3_NRI3":   PN = "F17"  !CDS_PN = "F17";
"GPIOE4_NDTR3":   PN = "E18"  !CDS_PN = "E18";
"GPIOE5_NRTS3":   PN = "D19"  !CDS_PN = "D19";
"GPIOE6_TXD3":   PN = "A20"  !CDS_PN = "A20";
"GPIOE7_RXD3":   PN = "B19"  !CDS_PN = "B19";
"GPIOF0_NCTS4_LHAD0":   PN = "J19"  !CDS_PN = "J19";
"GPIOF1_NDCD4_LHAD1":   PN = "J18"  !CDS_PN = "J18";
"GPIOF2_NDSR4_LHAD2":   PN = "B22"  !CDS_PN = "B22";
"GPIOF3_NRI4_LHAD3":   PN = "B21"  !CDS_PN = "B21";
"GPIOF4_NDTR4_LHCLK":   PN = "A21"  !CDS_PN = "A21";
"GPIOF5_NRTS4_LHFRAME#":   PN = "H19"  !CDS_PN = "H19";
"GPIOF6_TXD4_LHSIRQ#":   PN = "G17"  !CDS_PN = "G17";
"GPIOF7_RXD4_LHRST#":   PN = "H18"  !CDS_PN = "H18";
"GPIOG4_SGPS2CK_SALT1":   PN = "E17"  !CDS_PN = "E17";
"GPIOG5_SGPS2LD_SALT2":   PN = "D16"  !CDS_PN = "D16";
"GPIOG6_SGPS2I0_SALT3":   PN = "D15"  !CDS_PN = "D15";
"GPIOG7_SGPS2I1_SALT4":   PN = "E14"  !CDS_PN = "E14";
"GPIOL0_NCTS1":   PN = "T2"  !CDS_PN = "T2";
"GPIOL1_NDCD1_VPIDE":   PN = "T1"  !CDS_PN = "T1";
"GPIOL2_NDSR1":   PN = "U1"  !CDS_PN = "U1";
"GPIOL3_NRI1_VPIHS":   PN = "U2"  !CDS_PN = "U2";
"GPIOL4_NDTR1_VPIVS":   PN = "P4"  !CDS_PN = "P4";
"GPIOL5_NRTS1_VPICLK":   PN = "P3"  !CDS_PN = "P3";
"GPIOL6_TXD1":   PN = "V1"  !CDS_PN = "V1";
"GPIOL7_RXD1":   PN = "W1"  !CDS_PN = "W1";
"GPIOM0_NCTS2_VPIB2":   PN = "Y1"  !CDS_PN = "Y1";
"GPIOM1_NDCD2_VPIB3":   PN = "AB2"  !CDS_PN = "AB2";
"GPIOM2_NDSR2_VPIB4":   PN = "AA1"  !CDS_PN = "AA1";
"GPIOM3_NRI2_VPIB5":   PN = "Y2"  !CDS_PN = "Y2";
"GPIOM4_NDTR2_VPIB6":   PN = "AA2"  !CDS_PN = "AA2";
"GPIOM5_NRTS2_VPIB7":   PN = "P5"  !CDS_PN = "P5";
"GPIOM6_TXD2_VPIB8":   PN = "R5"  !CDS_PN = "R5";
"GPIOM7_RXD2_VPIB9":   PN = "T5"  !CDS_PN = "T5";
"GPIOY3_SIOONCTRL#":   PN = "P21"  !CDS_PN = "P21";
"PECI":   PN = "AB18"  !CDS_PN = "AB18";
"PEREFCLKN":   PN = "K22"  !CDS_PN = "K22";
"PEREFCLKP":   PN = "K21"  !CDS_PN = "K21";
"PEREXT":   PN = "K20"  !CDS_PN = "K20";
"PERST#":   PN = "L20"  !CDS_PN = "L20";
"PERXN":   PN = "M22"  !CDS_PN = "M22";
"PERXP":   PN = "M21"  !CDS_PN = "M21";
"PETXN":   PN = "L22"  !CDS_PN = "L22";
"PETXP":   PN = "L21"  !CDS_PN = "L21";
"RXD5":   PN = "K2"  !CDS_PN = "K2";
"SRST#":   PN = "U18"  !CDS_PN = "U18";
"TXD5":   PN = "K1"  !CDS_PN = "K1";
DRAWING = "@baseboard_fab2_lib.baseboard_fab2(sch_1):page146";
BODY = "RES","I26": #LOCATION = "R25W83" !CDS_LOCATION = "R25W83" &SEC = "1" #&CDS_SEC = "1";
"A":   PN = "1"  !CDS_PN = "1";
"B":   PN = "2"  !CDS_PN = "2";
BODY = "RES","I27": #LOCATION = "R25W84" !CDS_LOCATION = "R25W84" &SEC = "1" #&CDS_SEC = "1";
"A":   PN = "1"  !CDS_PN = "1";
"B":   PN = "2"  !CDS_PN = "2";
BODY = "RES","I35": #LOCATION = "R1T25" !CDS_LOCATION = "R1T25" &SEC = "1" #&CDS_SEC = "1";
"A":   PN = "1"  !CDS_PN = "1";
"B":   PN = "2"  !CDS_PN = "2";
BODY = "RES","I37": #LOCATION = "R1T26" !CDS_LOCATION = "R1T26" &SEC = "1" #&CDS_SEC = "1";
"A":   PN = "1"  !CDS_PN = "1";
"B":   PN = "2"  !CDS_PN = "2";
BODY = "RES","I51": #LOCATION = "R1U52" !CDS_LOCATION = "R1U52" &SEC = "1" #&CDS_SEC = "1";
"A":   PN = "1"  !CDS_PN = "1";
"B":   PN = "2"  !CDS_PN = "2";
BODY = "RES","I64": #LOCATION = "R25W70" !CDS_LOCATION = "R25W70" #SEC = "1" !CDS_SEC = "1";
"A":   PN = "1"  !CDS_PN = "1";
"B":   PN = "2"  !CDS_PN = "2";
BODY = "RES","I65": #LOCATION = "R25W63" !CDS_LOCATION = "R25W63" #SEC = "1" !CDS_SEC = "1";
"A":   PN = "1"  !CDS_PN = "1";
"B":   PN = "2"  !CDS_PN = "2";
BODY = "RES","I67": #LOCATION = "R25W81" !CDS_LOCATION = "R25W81" #SEC = "1" !CDS_SEC = "1";
"A":   PN = "1"  !CDS_PN = "1";
"B":   PN = "2"  !CDS_PN = "2";
BODY = "RES","I68": #LOCATION = "R25W82" !CDS_LOCATION = "R25W82" #SEC = "1" !CDS_SEC = "1";
"A":   PN = "1"  !CDS_PN = "1";
"B":   PN = "2"  !CDS_PN = "2";
BODY = "RES","I69": #LOCATION = "R25W78" !CDS_LOCATION = "R25W78" #SEC = "1" !CDS_SEC = "1";
"A":   PN = "1"  !CDS_PN = "1";
"B":   PN = "2"  !CDS_PN = "2";
BODY = "RES","I70": #LOCATION = "R25W74" !CDS_LOCATION = "R25W74" #SEC = "1" !CDS_SEC = "1";
"A":   PN = "1"  !CDS_PN = "1";
"B":   PN = "2"  !CDS_PN = "2";
BODY = "RES","I71": #LOCATION = "R25W72" !CDS_LOCATION = "R25W72" #SEC = "1" !CDS_SEC = "1";
"A":   PN = "1"  !CDS_PN = "1";
"B":   PN = "2"  !CDS_PN = "2";
BODY = "RES","I72": #LOCATION = "R25W71" !CDS_LOCATION = "R25W71" &SEC = "1" #&CDS_SEC = "1";
"A":   PN = "1"  !CDS_PN = "1";
"B":   PN = "2"  !CDS_PN = "2";
BODY = "RES","I73": #LOCATION = "R25W73" !CDS_LOCATION = "R25W73" #SEC = "1" !CDS_SEC = "1";
"A":   PN = "1"  !CDS_PN = "1";
"B":   PN = "2"  !CDS_PN = "2";
BODY = "RES","I74": #LOCATION = "R3N24" !CDS_LOCATION = "R3N24" &SEC = "1" #&CDS_SEC = "1";
"A":   PN = "1"  !CDS_PN = "1";
"B":   PN = "2"  !CDS_PN = "2";
BODY = "RES","I75": #LOCATION = "R3N26" !CDS_LOCATION = "R3N26" &SEC = "1" #&CDS_SEC = "1";
"A":   PN = "1"  !CDS_PN = "1";
"B":   PN = "2"  !CDS_PN = "2";
BODY = "RES","I76": #LOCATION = "R25W66" !CDS_LOCATION = "R25W66" &SEC = "1" #&CDS_SEC = "1";
"A":   PN = "1"  !CDS_PN = "1";
"B":   PN = "2"  !CDS_PN = "2";
BODY = "RES","I78": #LOCATION = "R1U7" !CDS_LOCATION = "R1U7" #SEC = "1" !CDS_SEC = "1";
"A":   PN = "1"  !CDS_PN = "1";
"B":   PN = "2"  !CDS_PN = "2";
BODY = "RES","I84": #LOCATION = "R25W68" !CDS_LOCATION = "R25W68" &SEC = "1" #&CDS_SEC = "1";
"A":   PN = "1"  !CDS_PN = "1";
"B":   PN = "2"  !CDS_PN = "2";
BODY = "RES","I85": #LOCATION = "R25W69" !CDS_LOCATION = "R25W69" &SEC = "1" #&CDS_SEC = "1";
"A":   PN = "1"  !CDS_PN = "1";
"B":   PN = "2"  !CDS_PN = "2";
BODY = "RES","I96": #LOCATION = "R2T41" !CDS_LOCATION = "R2T41" #SEC = "1" !CDS_SEC = "1";
"A":   PN = "1"  !CDS_PN = "1";
"B":   PN = "2"  !CDS_PN = "2";
BODY = "AST2520A1-GP-GP","I104": #LOCATION = "U25W4" !CDS_LOCATION = "U25W4" &SEC = "4" #&CDS_SEC = "4";
"GPIOAA0_VPOR2_NORD0_SALT7":   PN = "Y21"  !CDS_PN = "Y21";
"GPIOAA1_VPOR3_NORD1_SALT8":   PN = "V21"  !CDS_PN = "V21";
"GPIOAA2_VPOR4_NORD2_SALT9":   PN = "Y22"  !CDS_PN = "Y22";
"GPIOAA3_VPOR5_NORD3_SALT10":   PN = "AA22"  !CDS_PN = "AA22";
"GPIOAA4_VPOR6_NORD4_SALT11":   PN = "U22"  !CDS_PN = "U22";
"GPIOAA5_VPOR7_NORD5_SALT12":   PN = "T20"  !CDS_PN = "T20";
"GPIOAA6_VPOR8_NORD6_SALT13":   PN = "N18"  !CDS_PN = "N18";
"GPIOAA7_VPOR9_NORD7_SALT14":   PN = "P19"  !CDS_PN = "P19";
"GPIOH0_NCTS6":   PN = "A18"  !CDS_PN = "A18";
"GPIOH1_NDCD6":   PN = "B18"  !CDS_PN = "B18";
"GPIOH2_NDSR6":   PN = "D17"  !CDS_PN = "D17";
"GPIOH3_NRI6":   PN = "C17"  !CDS_PN = "C17";
"GPIOH4_NDTR6":   PN = "A17"  !CDS_PN = "A17";
"GPIOH5_NRTS6":   PN = "B17"  !CDS_PN = "B17";
"GPIOH6_TXD6":   PN = "A16"  !CDS_PN = "A16";
"GPIOH7_RXD6":   PN = "D18"  !CDS_PN = "D18";
"GPIOS0_VPOB2_SPI2CS1#":   PN = "V20"  !CDS_PN = "V20";
"GPIOS1_VPOB3_BMCINT":   PN = "U19"  !CDS_PN = "U19";
"GPIOS2_VPOB4_SALT5":   PN = "R18"  !CDS_PN = "R18";
"GPIOS3_VPOB5_SALT6":   PN = "P18"  !CDS_PN = "P18";
"GPIOS4_VPOB6":   PN = "R19"  !CDS_PN = "R19";
"GPIOS5_VPOB7":   PN = "W20"  !CDS_PN = "W20";
"GPIOS6_VPOB8":   PN = "U20"  !CDS_PN = "U20";
"GPIOS7_VPOB9":   PN = "AA20"  !CDS_PN = "AA20";
"GPIOZ0_VPOG2_NORA0_SIOPBI#":   PN = "Y20"  !CDS_PN = "Y20";
"GPIOZ1_VPOG3_NORA1_SIOPWRGD":   PN = "AB20"  !CDS_PN = "AB20";
"GPIOZ2_VPOG4_NORA2_SIOPBO#":   PN = "AB21"  !CDS_PN = "AB21";
"GPIOZ3_VPOG5_NORA3_SIOSCI#":   PN = "AA21"  !CDS_PN = "AA21";
"GPIOZ4_VPOG6_NORA4":   PN = "U21"  !CDS_PN = "U21";
"GPIOZ5_VPOG7_NORA5":   PN = "W22"  !CDS_PN = "W22";
"GPIOZ6_VPOG8_NORA6":   PN = "V22"  !CDS_PN = "V22";
"GPIOZ7_VPOG9_NORA7":   PN = "W21"  !CDS_PN = "W21";
"USB2A_DN":   PN = "A8"  !CDS_PN = "A8";
"USB2A_DP":   PN = "A7"  !CDS_PN = "A7";
"USB2AVRES":   PN = "B8"  !CDS_PN = "B8";
"USB2B_DN":   PN = "A6"  !CDS_PN = "A6";
"USB2B_DP":   PN = "B6"  !CDS_PN = "B6";
"USB2BVRES":   PN = "B7"  !CDS_PN = "B7";
BODY = "AST2520A1-GP-GP","I105": #LOCATION = "U25W4" !CDS_LOCATION = "U25W4" &SEC = "5" #&CDS_SEC = "5";
"ENTEST":   PN = "K3"  !CDS_PN = "K3";
"EXTRST#":   PN = "V18"  !CDS_PN = "V18";
"FWSPICK":   PN = "AA18"  !CDS_PN = "AA18";
"FWSPICS0#":   PN = "AB19"  !CDS_PN = "AB19";
"FWSPIMISO":   PN = "T18"  !CDS_PN = "T18";
"FWSPIMOSI":   PN = "U17"  !CDS_PN = "U17";
"GPIOAB0_VPODE_NOROE#":   PN = "N19"  !CDS_PN = "N19";
"GPIOAB1_VPOHS_NORWE#":   PN = "T21"  !CDS_PN = "T21";
"GPIOAB2_VPOVS_WDTRST1":   PN = "T22"  !CDS_PN = "T22";
"GPIOAB3_VPOCLK_WDTRST2":   PN = "R20"  !CDS_PN = "R20";
"GPIOAC0_ESPID0_LAD0":   PN = "G21"  !CDS_PN = "G21";
"GPIOAC1_ESPID1_LAD1":   PN = "G20"  !CDS_PN = "G20";
"GPIOAC2_ESPID2_LAD2":   PN = "D22"  !CDS_PN = "D22";
"GPIOAC3_ESPID3_LAD3":   PN = "E22"  !CDS_PN = "E22";
"GPIOAC4_ESPICK_LCLK":   PN = "C22"  !CDS_PN = "C22";
"GPIOAC5_ESPICS#_LFRAME#":   PN = "F21"  !CDS_PN = "F21";
"GPIOAC6_ESPIALT#_LSIRQ#":   PN = "F22"  !CDS_PN = "F22";
"GPIOAC7_ESPIRST#_LPCRST#":   PN = "G22"  !CDS_PN = "G22";
"GPIOJ4_VGAHS":   PN = "N5"  !CDS_PN = "N5";
"GPIOJ5_VGAVS":   PN = "R4"  !CDS_PN = "R4";
"GPIOJ6_DDCCLK":   PN = "R3"  !CDS_PN = "R3";
"GPIOJ7_DDCDAT":   PN = "T3"  !CDS_PN = "T3";
"GPIOQ6_OSCCLK":   PN = "B10"  !CDS_PN = "B10";
"GPIOQ7_PEWAKE#":   PN = "N20"  !CDS_PN = "N20";
"GPIOR0_FWSPICS1#":   PN = "AA19"  !CDS_PN = "AA19";
"GPIOR1_FWSPICS2#":   PN = "T19"  !CDS_PN = "T19";
"GPIOR2_SPI2CS0#":   PN = "T17"  !CDS_PN = "T17";
"GPIOR3_SPI2CK":   PN = "Y19"  !CDS_PN = "Y19";
"GPIOR4_SPI2MOSI":   PN = "W19"  !CDS_PN = "W19";
"GPIOR5_SPI2MISO":   PN = "V19"  !CDS_PN = "V19";
"HBLED#":   PN = "Y18"  !CDS_PN = "Y18";
"MALERT#":   PN = "U16"  !CDS_PN = "U16";
"MRESET#":   PN = "AB17"  !CDS_PN = "AB17";
DRAWING = "@baseboard_fab2_lib.baseboard_fab2(sch_1):page147";
BODY = "RES","I21": #LOCATION = "R25W90" !CDS_LOCATION = "R25W90" #SEC = "1" !CDS_SEC = "1";
"A":   PN = "1"  !CDS_PN = "1";
"B":   PN = "2"  !CDS_PN = "2";
BODY = "RES","I62": #LOCATION = "R1U2" !CDS_LOCATION = "R1U2" #SEC = "1" !CDS_SEC = "1";
"A":   PN = "1"  !CDS_PN = "1";
"B":   PN = "2"  !CDS_PN = "2";
BODY = "RES","I3": #LOCATION = "R25W92" !CDS_LOCATION = "R25W92" #SEC = "1" !CDS_SEC = "1";
"A":   PN = "1"  !CDS_PN = "1";
"B":   PN = "2"  !CDS_PN = "2";
BODY = "RES","I4": #LOCATION = "R25W91" !CDS_LOCATION = "R25W91" #SEC = "1" !CDS_SEC = "1";
"A":   PN = "1"  !CDS_PN = "1";
"B":   PN = "2"  !CDS_PN = "2";
BODY = "RES","I8": #LOCATION = "R25W88" !CDS_LOCATION = "R25W88" #SEC = "1" !CDS_SEC = "1";
"A":   PN = "1"  !CDS_PN = "1";
"B":   PN = "2"  !CDS_PN = "2";
BODY = "RES","I22": #LOCATION = "R25W89" !CDS_LOCATION = "R25W89" #SEC = "1" !CDS_SEC = "1";
"A":   PN = "1"  !CDS_PN = "1";
"B":   PN = "2"  !CDS_PN = "2";
BODY = "RES","I23": #LOCATION = "R25W85" !CDS_LOCATION = "R25W85" #SEC = "1" !CDS_SEC = "1";
"A":   PN = "1"  !CDS_PN = "1";
"B":   PN = "2"  !CDS_PN = "2";
BODY = "RES","I24": #LOCATION = "R25W86" !CDS_LOCATION = "R25W86" #SEC = "1" !CDS_SEC = "1";
"A":   PN = "1"  !CDS_PN = "1";
"B":   PN = "2"  !CDS_PN = "2";
BODY = "RES","I25": #LOCATION = "R25W87" !CDS_LOCATION = "R25W87" #SEC = "1" !CDS_SEC = "1";
"A":   PN = "1"  !CDS_PN = "1";
"B":   PN = "2"  !CDS_PN = "2";
BODY = "CAP","I38": #LOCATION = "C25W8" !CDS_LOCATION = "C25W8" #SEC = "1" !CDS_SEC = "1";
"A":   PN = "1"  !CDS_PN = "1";
"B":   PN = "2"  !CDS_PN = "2";
BODY = "CAP","I39": #LOCATION = "C25W9" !CDS_LOCATION = "C25W9" #SEC = "1" !CDS_SEC = "1";
"A":   PN = "1"  !CDS_PN = "1";
"B":   PN = "2"  !CDS_PN = "2";
BODY = "RES","I40": #LOCATION = "R25W57" !CDS_LOCATION = "R25W57" #SEC = "1" !CDS_SEC = "1";
"A":   PN = "1"  !CDS_PN = "1";
"B":   PN = "2"  !CDS_PN = "2";
BODY = "RES","I42": #LOCATION = "R25W79" !CDS_LOCATION = "R25W79" #SEC = "1" !CDS_SEC = "1";
"A":   PN = "1"  !CDS_PN = "1";
"B":   PN = "2"  !CDS_PN = "2";
BODY = "RES","I43": #LOCATION = "R25W80" !CDS_LOCATION = "R25W80" #SEC = "1" !CDS_SEC = "1";
"A":   PN = "1"  !CDS_PN = "1";
"B":   PN = "2"  !CDS_PN = "2";
BODY = "RES","I65": #LOCATION = "R1U4" !CDS_LOCATION = "R1U4" #SEC = "1" !CDS_SEC = "1";
"A":   PN = "1"  !CDS_PN = "1";
"B":   PN = "2"  !CDS_PN = "2";
BODY = "RES","I66": #LOCATION = "R1U5" !CDS_LOCATION = "R1U5" #SEC = "1" !CDS_SEC = "1";
"A":   PN = "1"  !CDS_PN = "1";
"B":   PN = "2"  !CDS_PN = "2";
BODY = "CAP","I36": #LOCATION = "C25W7" !CDS_LOCATION = "C25W7" &SEC = "1" #&CDS_SEC = "1";
"A":   PN = "1"  !CDS_PN = "1";
"B":   PN = "2"  !CDS_PN = "2";
BODY = "RES","I61": #LOCATION = "R1U1" !CDS_LOCATION = "R1U1" #SEC = "1" !CDS_SEC = "1";
"A":   PN = "1"  !CDS_PN = "1";
"B":   PN = "2"  !CDS_PN = "2";
BODY = "RES","I75": #LOCATION = "R2N13" !CDS_LOCATION = "R2N13" &SEC = "1" #&CDS_SEC = "1";
"A":   PN = "1"  !CDS_PN = "1";
"B":   PN = "2"  !CDS_PN = "2";
BODY = "AST2520A1-GP-GP","I106": #LOCATION = "U25W4" !CDS_LOCATION = "U25W4" &SEC = "6" #&CDS_SEC = "6";
"ADC0_GPIW0":   PN = "F4"  !CDS_PN = "F4";
"ADC1_GPIW1":   PN = "F5"  !CDS_PN = "F5";
"ADC2_GPIW2":   PN = "E2"  !CDS_PN = "E2";
"ADC3_GPIW3":   PN = "E1"  !CDS_PN = "E1";
"ADC4_GPIW4":   PN = "F3"  !CDS_PN = "F3";
"ADC5_GPIW5":   PN = "E3"  !CDS_PN = "E3";
"ADC6_GPIW6":   PN = "G5"  !CDS_PN = "G5";
"ADC7_GPIW7":   PN = "G4"  !CDS_PN = "G4";
"ADC8_GPIX0":   PN = "F2"  !CDS_PN = "F2";
"ADC9_GPIX1":   PN = "G3"  !CDS_PN = "G3";
"ADC10_GPIX2":   PN = "G2"  !CDS_PN = "G2";
"ADC11_GPIX3":   PN = "F1"  !CDS_PN = "F1";
"ADC12_GPIX4":   PN = "H5"  !CDS_PN = "H5";
"ADC13_GPIX5":   PN = "G1"  !CDS_PN = "G1";
"ADC14_GPIX6":   PN = "H3"  !CDS_PN = "H3";
"ADC15_GPIX7":   PN = "H4"  !CDS_PN = "H4";
"ADCREXT":   PN = "J1"  !CDS_PN = "J1";
"ADCVREFN":   PN = "H1"  !CDS_PN = "H1";
"ADCVREFP":   PN = "H2"  !CDS_PN = "H2";
"GPIOA6_TIMER7_MDC2":   PN = "C13"  !CDS_PN = "C13";
"GPIOA7_TIMER8_MDIO2":   PN = "B13"  !CDS_PN = "B13";
"GPION0_PWM0":   PN = "V2"  !CDS_PN = "V2";
"GPION1_PWM1":   PN = "W2"  !CDS_PN = "W2";
"GPION2_PWM2_VPIG2":   PN = "V3"  !CDS_PN = "V3";
"GPION3_PWM3_VPIG3":   PN = "U3"  !CDS_PN = "U3";
"GPION4_PWM4_VPIG4":   PN = "W3"  !CDS_PN = "W3";
"GPION5_PWM5_VPIG5":   PN = "AA3"  !CDS_PN = "AA3";
"GPION6_PWM6_VPIG6":   PN = "Y3"  !CDS_PN = "Y3";
"GPION7_PWM7_VPIG7":   PN = "T4"  !CDS_PN = "T4";
"GPIOO0_TACH0_VPIG8":   PN = "U5"  !CDS_PN = "U5";
"GPIOO1_TACH1_VPIG9":   PN = "U4"  !CDS_PN = "U4";
"GPIOO2_TACH2":   PN = "V5"  !CDS_PN = "V5";
"GPIOO3_TACH3":   PN = "AB4"  !CDS_PN = "AB4";
"GPIOO4_TACH4_VPIR2":   PN = "AB3"  !CDS_PN = "AB3";
"GPIOO5_TACH5_VPIR3":   PN = "Y4"  !CDS_PN = "Y4";
"GPIOO6_TACH6_VPIR4":   PN = "AA4"  !CDS_PN = "AA4";
"GPIOO7_TACH7_VPIR5":   PN = "W4"  !CDS_PN = "W4";
"GPIOP0_TACH8_VPIR6":   PN = "V4"  !CDS_PN = "V4";
"GPIOP1_TACH9_VPIR7":   PN = "W5"  !CDS_PN = "W5";
"GPIOP2_TACH10_VPIR8":   PN = "AA5"  !CDS_PN = "AA5";
"GPIOP3_TACH11_VPIR9":   PN = "AB5"  !CDS_PN = "AB5";
"GPIOP4_TACH12":   PN = "Y6"  !CDS_PN = "Y6";
"GPIOP5_TACH13":   PN = "Y5"  !CDS_PN = "Y5";
"GPIOP6_TACH14":   PN = "W6"  !CDS_PN = "W6";
"GPIOP7_TACH15":   PN = "V6"  !CDS_PN = "V6";
"GPIOR6_MDC1":   PN = "D8"  !CDS_PN = "D8";
"GPIOR7_MDIO1":   PN = "E10"  !CDS_PN = "E10";
"RGMII1RXCK_RMII1RCLKI_GPIOU4":   PN = "B4"  !CDS_PN = "B4";
"RGMII1RXCTL_GPIOU5":   PN = "A4"  !CDS_PN = "A4";
"RGMII1RXD0_RMII1RXD0_GPIOU6":   PN = "A3"  !CDS_PN = "A3";
"RGMII1RXD1_RMII1RXD1_GPIOU7":   PN = "D6"  !CDS_PN = "D6";
"RGMII1RXD2_RMII1CRSDV_GPIOV0":   PN = "C5"  !CDS_PN = "C5";
"RGMII1RXD3_RMII1RXER_GPIOV1":   PN = "C4"  !CDS_PN = "C4";
"RGMII1TXCK_RMII1RCLKO_GPIOT0":   PN = "B5"  !CDS_PN = "B5";
"RGMII1TXCTL_RMII1TXEN_GPIOT1":   PN = "E9"  !CDS_PN = "E9";
"RGMII1TXD0_RMII1TXD0_GPIOT2":   PN = "F9"  !CDS_PN = "F9";
"RGMII1TXD1_RMII1TXD1_GPIOT3":   PN = "A5"  !CDS_PN = "A5";
"RGMII1TXD2_GPIOT4":   PN = "E7"  !CDS_PN = "E7";
"RGMII1TXD3_GPIOT5":   PN = "D7"  !CDS_PN = "D7";
"RGMII2RXCK_RMII2RCLKI_GPIOV2":   PN = "C2"  !CDS_PN = "C2";
"RGMII2RXCTL_GPIOV3":   PN = "C1"  !CDS_PN = "C1";
"RGMII2RXD0_RMII2RXD0_GPIOV4":   PN = "C3"  !CDS_PN = "C3";
"RGMII2RXD1_RMII2RXD1_GPIOV5":   PN = "D1"  !CDS_PN = "D1";
"RGMII2RXD2_RMII2CRSDV_GPIOV6":   PN = "D2"  !CDS_PN = "D2";
"RGMII2RXD3_RMII2RXER_GPIOV7":   PN = "E6"  !CDS_PN = "E6";
"RGMII2TXCK_RMII2RCLKO_GPIOT6":   PN = "B2"  !CDS_PN = "B2";
"RGMII2TXCTL_RMII2TXEN_GPIOT7":   PN = "B1"  !CDS_PN = "B1";
"RGMII2TXD0_RMII2TXD0_GPIOU0":   PN = "A2"  !CDS_PN = "A2";
"RGMII2TXD1_RMII2TXD1_GPIOU1":   PN = "B3"  !CDS_PN = "B3";
"RGMII2TXD2_GPIOU2":   PN = "D5"  !CDS_PN = "D5";
"RGMII2TXD3_GPIOU3":   PN = "D4"  !CDS_PN = "D4";
"RGMIICK":   PN = "D3"  !CDS_PN = "D3";
DRAWING = "@baseboard_fab2_lib.baseboard_fab2(sch_1):page151";
BODY = "RES","I2": #LOCATION = "R25W95" !CDS_LOCATION = "R25W95" &SEC = "1" #&CDS_SEC = "1";
"A":   PN = "1"  !CDS_PN = "1";
"B":   PN = "2"  !CDS_PN = "2";
BODY = "RES","I9": #LOCATION = "R25W94" !CDS_LOCATION = "R25W94" #SEC = "1" !CDS_SEC = "1";
"A":   PN = "1"  !CDS_PN = "1";
"B":   PN = "2"  !CDS_PN = "2";
BODY = "RES","I10": #LOCATION = "R25W96" !CDS_LOCATION = "R25W96" &SEC = "1" #&CDS_SEC = "1";
"A":   PN = "1"  !CDS_PN = "1";
"B":   PN = "2"  !CDS_PN = "2";
BODY = "RES","I11": #LOCATION = "R25W97" !CDS_LOCATION = "R25W97" &SEC = "1" #&CDS_SEC = "1";
"A":   PN = "1"  !CDS_PN = "1";
"B":   PN = "2"  !CDS_PN = "2";
BODY = "RES","I12": #LOCATION = "R25W98" !CDS_LOCATION = "R25W98" &SEC = "1" #&CDS_SEC = "1";
"A":   PN = "1"  !CDS_PN = "1";
"B":   PN = "2"  !CDS_PN = "2";
BODY = "RES","I13": #LOCATION = "R25W100" !CDS_LOCATION = "R25W100" &SEC = "1" #&CDS_SEC = "1";
"A":   PN = "1"  !CDS_PN = "1";
"B":   PN = "2"  !CDS_PN = "2";
BODY = "RES","I14": #LOCATION = "R25W99" !CDS_LOCATION = "R25W99" &SEC = "1" #&CDS_SEC = "1";
"A":   PN = "1"  !CDS_PN = "1";
"B":   PN = "2"  !CDS_PN = "2";
BODY = "RES","I27": #LOCATION = "R25W101" !CDS_LOCATION = "R25W101" &SEC = "1" #&CDS_SEC = "1";
"A":   PN = "1"  !CDS_PN = "1";
"B":   PN = "2"  !CDS_PN = "2";
BODY = "RES","I28": #LOCATION = "R25W102" !CDS_LOCATION = "R25W102" &SEC = "1" #&CDS_SEC = "1";
"A":   PN = "1"  !CDS_PN = "1";
"B":   PN = "2"  !CDS_PN = "2";
BODY = "RES","I29": #LOCATION = "R25W103" !CDS_LOCATION = "R25W103" &SEC = "1" #&CDS_SEC = "1";
"A":   PN = "1"  !CDS_PN = "1";
"B":   PN = "2"  !CDS_PN = "2";
BODY = "RES","I30": #LOCATION = "R25W104" !CDS_LOCATION = "R25W104" &SEC = "1" #&CDS_SEC = "1";
"A":   PN = "1"  !CDS_PN = "1";
"B":   PN = "2"  !CDS_PN = "2";
BODY = "RES","I31": #LOCATION = "R25W105" !CDS_LOCATION = "R25W105" &SEC = "1" #&CDS_SEC = "1";
"A":   PN = "1"  !CDS_PN = "1";
"B":   PN = "2"  !CDS_PN = "2";
BODY = "RES","I32": #LOCATION = "R25W106" !CDS_LOCATION = "R25W106" &SEC = "1" #&CDS_SEC = "1";
"A":   PN = "1"  !CDS_PN = "1";
"B":   PN = "2"  !CDS_PN = "2";
BODY = "RES","I33": #LOCATION = "R25W107" !CDS_LOCATION = "R25W107" &SEC = "1" #&CDS_SEC = "1";
"A":   PN = "1"  !CDS_PN = "1";
"B":   PN = "2"  !CDS_PN = "2";
BODY = "RES","I34": #LOCATION = "R25W108" !CDS_LOCATION = "R25W108" &SEC = "1" #&CDS_SEC = "1";
"A":   PN = "1"  !CDS_PN = "1";
"B":   PN = "2"  !CDS_PN = "2";
BODY = "RES","I35": #LOCATION = "R25W109" !CDS_LOCATION = "R25W109" &SEC = "1" #&CDS_SEC = "1";
"A":   PN = "1"  !CDS_PN = "1";
"B":   PN = "2"  !CDS_PN = "2";
BODY = "RES","I36": #LOCATION = "R25W110" !CDS_LOCATION = "R25W110" &SEC = "1" #&CDS_SEC = "1";
"A":   PN = "1"  !CDS_PN = "1";
"B":   PN = "2"  !CDS_PN = "2";
BODY = "RES","I43": #LOCATION = "R25W111" !CDS_LOCATION = "R25W111" &SEC = "1" #&CDS_SEC = "1";
"A":   PN = "1"  !CDS_PN = "1";
"B":   PN = "2"  !CDS_PN = "2";
BODY = "RES","I44": #LOCATION = "R25W112" !CDS_LOCATION = "R25W112" &SEC = "1" #&CDS_SEC = "1";
"A":   PN = "1"  !CDS_PN = "1";
"B":   PN = "2"  !CDS_PN = "2";
BODY = "RES","I45": #LOCATION = "R25W113" !CDS_LOCATION = "R25W113" &SEC = "1" #&CDS_SEC = "1";
"A":   PN = "1"  !CDS_PN = "1";
"B":   PN = "2"  !CDS_PN = "2";
BODY = "RES","I46": #LOCATION = "R25W114" !CDS_LOCATION = "R25W114" &SEC = "1" #&CDS_SEC = "1";
"A":   PN = "1"  !CDS_PN = "1";
"B":   PN = "2"  !CDS_PN = "2";
BODY = "RES","I47": #LOCATION = "R25W115" !CDS_LOCATION = "R25W115" &SEC = "1" #&CDS_SEC = "1";
"A":   PN = "1"  !CDS_PN = "1";
"B":   PN = "2"  !CDS_PN = "2";
BODY = "RES","I48": #LOCATION = "R25W116" !CDS_LOCATION = "R25W116" #SEC = "1" !CDS_SEC = "1";
"A":   PN = "1"  !CDS_PN = "1";
"B":   PN = "2"  !CDS_PN = "2";
DRAWING = "@baseboard_fab2_lib.baseboard_fab2(sch_1):page150";
BODY = "CAP","I1": #LOCATION = "C25W60" !CDS_LOCATION = "C25W60" &SEC = "1" #&CDS_SEC = "1";
"A":   PN = "1"  !CDS_PN = "1";
"B":   PN = "2"  !CDS_PN = "2";
BODY = "SC4D7U10V3KX-GP","I2": #LOCATION = "C25W65" !CDS_LOCATION = "C25W65" &SEC = "1" #&CDS_SEC = "1";
"1":   PN = "1"  !CDS_PN = "1";
"2":   PN = "2"  !CDS_PN = "2";
BODY = "CAP","I4": #LOCATION = "C25W71" !CDS_LOCATION = "C25W71" &SEC = "1" #&CDS_SEC = "1";
"A":   PN = "1"  !CDS_PN = "1";
"B":   PN = "2"  !CDS_PN = "2";
BODY = "SC4D7U10V3KX-GP","I6": #LOCATION = "C25W70" !CDS_LOCATION = "C25W70" &SEC = "1" #&CDS_SEC = "1";
"1":   PN = "1"  !CDS_PN = "1";
"2":   PN = "2"  !CDS_PN = "2";
BODY = "0R3J-0-U-GP","I7": #LOCATION = "R25W120" !CDS_LOCATION = "R25W120" &SEC = "1" #&CDS_SEC = "1";
"1":   PN = "1"  !CDS_PN = "1";
"2":   PN = "2"  !CDS_PN = "2";
BODY = "SCD1U16V2KX-3GP","I10": #LOCATION = "C25W55" !CDS_LOCATION = "C25W55" &SEC = "1" #&CDS_SEC = "1";
"1":   PN = "1"  !CDS_PN = "1";
"2":   PN = "2"  !CDS_PN = "2";
BODY = "CAP","I12": #LOCATION = "C25W54" !CDS_LOCATION = "C25W54" &SEC = "1" #&CDS_SEC = "1";
"A":   PN = "1"  !CDS_PN = "1";
"B":   PN = "2"  !CDS_PN = "2";
BODY = "CAP","I13": #LOCATION = "C25W53" !CDS_LOCATION = "C25W53" &SEC = "1" #&CDS_SEC = "1";
"A":   PN = "1"  !CDS_PN = "1";
"B":   PN = "2"  !CDS_PN = "2";
BODY = "CAP","I14": #LOCATION = "C25W52" !CDS_LOCATION = "C25W52" &SEC = "1" #&CDS_SEC = "1";
"A":   PN = "1"  !CDS_PN = "1";
"B":   PN = "2"  !CDS_PN = "2";
BODY = "SC4D7U10V3KX-GP","I17": #LOCATION = "C25W39" !CDS_LOCATION = "C25W39" &SEC = "1" #&CDS_SEC = "1";
"1":   PN = "1"  !CDS_PN = "1";
"2":   PN = "2"  !CDS_PN = "2";
BODY = "SCD1U16V2KX-3GP","I18": #LOCATION = "C25W38" !CDS_LOCATION = "C25W38" &SEC = "1" #&CDS_SEC = "1";
"1":   PN = "1"  !CDS_PN = "1";
"2":   PN = "2"  !CDS_PN = "2";
BODY = "CAP","I19": #LOCATION = "C25W51" !CDS_LOCATION = "C25W51" &SEC = "1" #&CDS_SEC = "1";
"A":   PN = "1"  !CDS_PN = "1";
"B":   PN = "2"  !CDS_PN = "2";
BODY = "SC4D7U10V3KX-GP","I21": #LOCATION = "C25W50" !CDS_LOCATION = "C25W50" &SEC = "1" #&CDS_SEC = "1";
"1":   PN = "1"  !CDS_PN = "1";
"2":   PN = "2"  !CDS_PN = "2";
BODY = "SCD1U16V2KX-3GP","I24": #LOCATION = "C25W64" !CDS_LOCATION = "C25W64" &SEC = "1" #&CDS_SEC = "1";
"1":   PN = "1"  !CDS_PN = "1";
"2":   PN = "2"  !CDS_PN = "2";
BODY = "CAP","I25": #LOCATION = "C25W63" !CDS_LOCATION = "C25W63" &SEC = "1" #&CDS_SEC = "1";
"A":   PN = "1"  !CDS_PN = "1";
"B":   PN = "2"  !CDS_PN = "2";
BODY = "HCB1608KF-800T30-GP","I26": #LOCATION = "FB2T6" !CDS_LOCATION = "FB2T6" &SEC = "1" #&CDS_SEC = "1";
"1":   PN = "1"  !CDS_PN = "1";
"2":   PN = "2"  !CDS_PN = "2";
BODY = "SC4D7U10V3KX-GP","I28": #LOCATION = "C25W69" !CDS_LOCATION = "C25W69" &SEC = "1" #&CDS_SEC = "1";
"1":   PN = "1"  !CDS_PN = "1";
"2":   PN = "2"  !CDS_PN = "2";
BODY = "SCD1U16V2KX-3GP","I30": #LOCATION = "C25W68" !CDS_LOCATION = "C25W68" &SEC = "1" #&CDS_SEC = "1";
"1":   PN = "1"  !CDS_PN = "1";
"2":   PN = "2"  !CDS_PN = "2";
BODY = "CAP","I31": #LOCATION = "C25W67" !CDS_LOCATION = "C25W67" &SEC = "1" #&CDS_SEC = "1";
"A":   PN = "1"  !CDS_PN = "1";
"B":   PN = "2"  !CDS_PN = "2";
BODY = "HCB1608KF-800T30-GP","I32": #LOCATION = "FB2T1" !CDS_LOCATION = "FB2T1" &SEC = "1" #&CDS_SEC = "1";
"1":   PN = "1"  !CDS_PN = "1";
"2":   PN = "2"  !CDS_PN = "2";
BODY = "CAP","I33": #LOCATION = "C25W66" !CDS_LOCATION = "C25W66" &SEC = "1" #&CDS_SEC = "1";
"A":   PN = "1"  !CDS_PN = "1";
"B":   PN = "2"  !CDS_PN = "2";
BODY = "CAP","I35": #LOCATION = "C25W37" !CDS_LOCATION = "C25W37" &SEC = "1" #&CDS_SEC = "1";
"A":   PN = "1"  !CDS_PN = "1";
"B":   PN = "2"  !CDS_PN = "2";
BODY = "SCD1U16V2KX-3GP","I36": #LOCATION = "C25W49" !CDS_LOCATION = "C25W49" &SEC = "1" #&CDS_SEC = "1";
"1":   PN = "1"  !CDS_PN = "1";
"2":   PN = "2"  !CDS_PN = "2";
BODY = "CAP","I38": #LOCATION = "C25W48" !CDS_LOCATION = "C25W48" &SEC = "1" #&CDS_SEC = "1";
"A":   PN = "1"  !CDS_PN = "1";
"B":   PN = "2"  !CDS_PN = "2";
BODY = "HCB1608KF-800T30-GP","I39": #LOCATION = "FB2T7" !CDS_LOCATION = "FB2T7" &SEC = "1" #&CDS_SEC = "1";
"1":   PN = "1"  !CDS_PN = "1";
"2":   PN = "2"  !CDS_PN = "2";
BODY = "SC4D7U10V3KX-GP","I43": #LOCATION = "C25W30" !CDS_LOCATION = "C25W30" &SEC = "1" #&CDS_SEC = "1";
"1":   PN = "1"  !CDS_PN = "1";
"2":   PN = "2"  !CDS_PN = "2";
BODY = "CAP","I45": #LOCATION = "C25W29" !CDS_LOCATION = "C25W29" #SEC = "1" !CDS_SEC = "1";
"A":   PN = "1"  !CDS_PN = "1";
"B":   PN = "2"  !CDS_PN = "2";
BODY = "CAP","I46": #LOCATION = "C25W28" !CDS_LOCATION = "C25W28" &SEC = "1" #&CDS_SEC = "1";
"A":   PN = "1"  !CDS_PN = "1";
"B":   PN = "2"  !CDS_PN = "2";
BODY = "CAP","I48": #LOCATION = "C25W27" !CDS_LOCATION = "C25W27" &SEC = "1" #&CDS_SEC = "1";
"A":   PN = "1"  !CDS_PN = "1";
"B":   PN = "2"  !CDS_PN = "2";
BODY = "SC4D7U10V3KX-GP","I50": #LOCATION = "C25W36" !CDS_LOCATION = "C25W36" &SEC = "1" #&CDS_SEC = "1";
"1":   PN = "1"  !CDS_PN = "1";
"2":   PN = "2"  !CDS_PN = "2";
BODY = "CAP","I51": #LOCATION = "C25W35" !CDS_LOCATION = "C25W35" &SEC = "1" #&CDS_SEC = "1";
"A":   PN = "1"  !CDS_PN = "1";
"B":   PN = "2"  !CDS_PN = "2";
BODY = "SCD1U16V2KX-3GP","I53": #LOCATION = "C25W34" !CDS_LOCATION = "C25W34" &SEC = "1" #&CDS_SEC = "1";
"1":   PN = "1"  !CDS_PN = "1";
"2":   PN = "2"  !CDS_PN = "2";
BODY = "SC4D7U10V3KX-GP","I54": #LOCATION = "C25W47" !CDS_LOCATION = "C25W47" &SEC = "1" #&CDS_SEC = "1";
"1":   PN = "1"  !CDS_PN = "1";
"2":   PN = "2"  !CDS_PN = "2";
BODY = "CAP","I55": #LOCATION = "C25W46" !CDS_LOCATION = "C25W46" &SEC = "1" #&CDS_SEC = "1";
"A":   PN = "1"  !CDS_PN = "1";
"B":   PN = "2"  !CDS_PN = "2";
BODY = "0R3J-0-U-GP","I57": #LOCATION = "R25W93" !CDS_LOCATION = "R25W93" &SEC = "1" #&CDS_SEC = "1";
"1":   PN = "1"  !CDS_PN = "1";
"2":   PN = "2"  !CDS_PN = "2";
BODY = "CAP","I59": #LOCATION = "C25W33" !CDS_LOCATION = "C25W33" &SEC = "1" #&CDS_SEC = "1";
"A":   PN = "1"  !CDS_PN = "1";
"B":   PN = "2"  !CDS_PN = "2";
BODY = "SCD1U16V2KX-3GP","I61": #LOCATION = "C25W45" !CDS_LOCATION = "C25W45" &SEC = "1" #&CDS_SEC = "1";
"1":   PN = "1"  !CDS_PN = "1";
"2":   PN = "2"  !CDS_PN = "2";
BODY = "CAP","I62": #LOCATION = "C25W44" !CDS_LOCATION = "C25W44" &SEC = "1" #&CDS_SEC = "1";
"A":   PN = "1"  !CDS_PN = "1";
"B":   PN = "2"  !CDS_PN = "2";
BODY = "CAP","I63": #LOCATION = "C25W43" !CDS_LOCATION = "C25W43" &SEC = "1" #&CDS_SEC = "1";
"A":   PN = "1"  !CDS_PN = "1";
"B":   PN = "2"  !CDS_PN = "2";
BODY = "SC4D7U10V3KX-GP","I65": #LOCATION = "C25W62" !CDS_LOCATION = "C25W62" &SEC = "1" #&CDS_SEC = "1";
"1":   PN = "1"  !CDS_PN = "1";
"2":   PN = "2"  !CDS_PN = "2";
BODY = "SCD1U16V2KX-3GP","I67": #LOCATION = "C25W61" !CDS_LOCATION = "C25W61" &SEC = "1" #&CDS_SEC = "1";
"1":   PN = "1"  !CDS_PN = "1";
"2":   PN = "2"  !CDS_PN = "2";
BODY = "SC4D7U10V3KX-GP","I69": #LOCATION = "C25W59" !CDS_LOCATION = "C25W59" &SEC = "1" #&CDS_SEC = "1";
"1":   PN = "1"  !CDS_PN = "1";
"2":   PN = "2"  !CDS_PN = "2";
BODY = "CAP","I71": #LOCATION = "C25W26" !CDS_LOCATION = "C25W26" &SEC = "1" #&CDS_SEC = "1";
"A":   PN = "1"  !CDS_PN = "1";
"B":   PN = "2"  !CDS_PN = "2";
BODY = "CAP","I72": #LOCATION = "C25W25" !CDS_LOCATION = "C25W25" #SEC = "1" !CDS_SEC = "1";
"A":   PN = "1"  !CDS_PN = "1";
"B":   PN = "2"  !CDS_PN = "2";
BODY = "CAP","I73": #LOCATION = "C25W24" !CDS_LOCATION = "C25W24" #SEC = "1" !CDS_SEC = "1";
"A":   PN = "1"  !CDS_PN = "1";
"B":   PN = "2"  !CDS_PN = "2";
BODY = "CAP","I75": #LOCATION = "C25W23" !CDS_LOCATION = "C25W23" #SEC = "1" !CDS_SEC = "1";
"A":   PN = "1"  !CDS_PN = "1";
"B":   PN = "2"  !CDS_PN = "2";
BODY = "HCB1608KF-800T30-GP","I76": #LOCATION = "FB2T3" !CDS_LOCATION = "FB2T3" &SEC = "1" #&CDS_SEC = "1";
"1":   PN = "1"  !CDS_PN = "1";
"2":   PN = "2"  !CDS_PN = "2";
BODY = "CAP","I78": #LOCATION = "C25W32" !CDS_LOCATION = "C25W32" &SEC = "1" #&CDS_SEC = "1";
"A":   PN = "1"  !CDS_PN = "1";
"B":   PN = "2"  !CDS_PN = "2";
BODY = "SCD1U16V2KX-3GP","I79": #LOCATION = "C25W31" !CDS_LOCATION = "C25W31" &SEC = "1" #&CDS_SEC = "1";
"1":   PN = "1"  !CDS_PN = "1";
"2":   PN = "2"  !CDS_PN = "2";
BODY = "CAP","I80": #LOCATION = "C25W42" !CDS_LOCATION = "C25W42" &SEC = "1" #&CDS_SEC = "1";
"A":   PN = "1"  !CDS_PN = "1";
"B":   PN = "2"  !CDS_PN = "2";
BODY = "CAP","I81": #LOCATION = "C25W41" !CDS_LOCATION = "C25W41" &SEC = "1" #&CDS_SEC = "1";
"A":   PN = "1"  !CDS_PN = "1";
"B":   PN = "2"  !CDS_PN = "2";
BODY = "CAP","I82": #LOCATION = "C25W40" !CDS_LOCATION = "C25W40" &SEC = "1" #&CDS_SEC = "1";
"A":   PN = "1"  !CDS_PN = "1";
"B":   PN = "2"  !CDS_PN = "2";
BODY = "HCB1608KF-800T30-GP","I84": #LOCATION = "FB2T4" !CDS_LOCATION = "FB2T4" &SEC = "1" #&CDS_SEC = "1";
"1":   PN = "1"  !CDS_PN = "1";
"2":   PN = "2"  !CDS_PN = "2";
BODY = "SCD1U16V2KX-3GP","I85": #LOCATION = "C25W58" !CDS_LOCATION = "C25W58" &SEC = "1" #&CDS_SEC = "1";
"1":   PN = "1"  !CDS_PN = "1";
"2":   PN = "2"  !CDS_PN = "2";
BODY = "CAP","I86": #LOCATION = "C25W57" !CDS_LOCATION = "C25W57" &SEC = "1" #&CDS_SEC = "1";
"A":   PN = "1"  !CDS_PN = "1";
"B":   PN = "2"  !CDS_PN = "2";
BODY = "CAP","I87": #LOCATION = "C25W56" !CDS_LOCATION = "C25W56" &SEC = "1" #&CDS_SEC = "1";
"A":   PN = "1"  !CDS_PN = "1";
"B":   PN = "2"  !CDS_PN = "2";
BODY = "HCB1608KF-800T30-GP","I89": #LOCATION = "FB2T5" !CDS_LOCATION = "FB2T5" &SEC = "1" #&CDS_SEC = "1";
"1":   PN = "1"  !CDS_PN = "1";
"2":   PN = "2"  !CDS_PN = "2";
DRAWING = "@baseboard_fab2_lib.baseboard_fab2(sch_1):page148";
BODY = "RES","I16": #LOCATION = "R25W59" !CDS_LOCATION = "R25W59" &SEC = "1" #&CDS_SEC = "1";
"A":   PN = "1"  !CDS_PN = "1";
"B":   PN = "2"  !CDS_PN = "2";
BODY = "CAP_A","I20": #LOCATION = "C1T21" !CDS_LOCATION = "C1T21" #SEC = "1" !CDS_SEC = "1";
"A":   PN = "1"  !CDS_PN = "1";
"B":   PN = "2"  !CDS_PN = "2";
BODY = "RES","I23": #LOCATION = "R25W75" !CDS_LOCATION = "R25W75" #SEC = "1" !CDS_SEC = "1";
"A":   PN = "1"  !CDS_PN = "1";
"B":   PN = "2"  !CDS_PN = "2";
BODY = "AST2520A1-GP-GP","I28": LOCATION = "U25W4" #&CDS_LOCATION = "U25W4" &SEC = "7" #&CDS_SEC = "7";
"ADCAV33":   PN = "J6"  !CDS_PN = "J6";
"BATVDD":   PN = "E4"  !CDS_PN = "E4";
"DACAV33":   PN = "K6"  !CDS_PN = "K6";
"DACDV33":   PN = "K5"  !CDS_PN = "K5";
"GND0":   PN = "A1"  !CDS_PN = "A1";
"GND1":   PN = "A22"  !CDS_PN = "A22";
"GND2":   PN = "AA11"  !CDS_PN = "AA11";
"GND3":   PN = "AA13"  !CDS_PN = "AA13";
"GND4":   PN = "AA15"  !CDS_PN = "AA15";
"GND5":   PN = "AA7"  !CDS_PN = "AA7";
"GND6":   PN = "AA9"  !CDS_PN = "AA9";
"GND7":   PN = "AB1"  !CDS_PN = "AB1";
"GND8":   PN = "AB22"  !CDS_PN = "AB22";
"GND9":   PN = "C6"  !CDS_PN = "C6";
"GND10":   PN = "E8"  !CDS_PN = "E8";
"GND11":   PN = "F16"  !CDS_PN = "F16";
"GND12":   PN = "G19"  !CDS_PN = "G19";
"GND13":   PN = "G6"  !CDS_PN = "G6";
"GND14":   PN = "H6"  !CDS_PN = "H6";
"GND15":   PN = "J10"  !CDS_PN = "J10";
"GND16":   PN = "J11"  !CDS_PN = "J11";
"GND17":   PN = "J12"  !CDS_PN = "J12";
"GND18":   PN = "J13"  !CDS_PN = "J13";
"GND19":   PN = "J14"  !CDS_PN = "J14";
"GND20":   PN = "J21"  !CDS_PN = "J21";
"GND21":   PN = "J22"  !CDS_PN = "J22";
"GND22":   PN = "J5"  !CDS_PN = "J5";
"GND23":   PN = "J9"  !CDS_PN = "J9";
"GND24":   PN = "K10"  !CDS_PN = "K10";
"GND25":   PN = "K11"  !CDS_PN = "K11";
"GND26":   PN = "K12"  !CDS_PN = "K12";
"GND27":   PN = "K13"  !CDS_PN = "K13";
"GND28":   PN = "K14"  !CDS_PN = "K14";
"GND29":   PN = "K16"  !CDS_PN = "K16";
"GND30":   PN = "K9"  !CDS_PN = "K9";
"GND31":   PN = "L10"  !CDS_PN = "L10";
"GND32":   PN = "L11"  !CDS_PN = "L11";
"GND33":   PN = "L12"  !CDS_PN = "L12";
"GND34":   PN = "L13"  !CDS_PN = "L13";
"GND35":   PN = "L14"  !CDS_PN = "L14";
"GND36":   PN = "L9"  !CDS_PN = "L9";
"GND37":   PN = "M1"  !CDS_PN = "M1";
"GND38":   PN = "M10"  !CDS_PN = "M10";
"GND39":   PN = "M11"  !CDS_PN = "M11";
"GND40":   PN = "M12"  !CDS_PN = "M12";
"GND41":   PN = "M13"  !CDS_PN = "M13";
"GND42":   PN = "M14"  !CDS_PN = "M14";
"GND43":   PN = "M16"  !CDS_PN = "M16";
"GND44":   PN = "M17"  !CDS_PN = "M17";
"GND45":   PN = "M2"  !CDS_PN = "M2";
"GND46":   PN = "M3"  !CDS_PN = "M3";
"GND47":   PN = "M4"  !CDS_PN = "M4";
"GND48":   PN = "M5"  !CDS_PN = "M5";
"GND49":   PN = "M6"  !CDS_PN = "M6";
"GND50":   PN = "M7"  !CDS_PN = "M7";
"GND51":   PN = "M9"  !CDS_PN = "M9";
"GND52":   PN = "N10"  !CDS_PN = "N10";
"GND53":   PN = "N11"  !CDS_PN = "N11";
"GND54":   PN = "N12"  !CDS_PN = "N12";
"GND55":   PN = "N13"  !CDS_PN = "N13";
"GND56":   PN = "N14"  !CDS_PN = "N14";
"GND57":   PN = "N9"  !CDS_PN = "N9";
"GND58":   PN = "T16"  !CDS_PN = "T16";
"GND59":   PN = "T6"  !CDS_PN = "T6";
"GND60":   PN = "T7"  !CDS_PN = "T7";
"GND61":   PN = "U11"  !CDS_PN = "U11";
"GND62":   PN = "U6"  !CDS_PN = "U6";
"GND63":   PN = "V10"  !CDS_PN = "V10";
"GND64":   PN = "V12"  !CDS_PN = "V12";
"GND65":   PN = "V14"  !CDS_PN = "V14";
"GND66":   PN = "V16"  !CDS_PN = "V16";
"GND67":   PN = "V8"  !CDS_PN = "V8";
"GND68":   PN = "E5"  !CDS_PN = "E5";
"GPIOY0_SIOS3#":   PN = "R22"  !CDS_PN = "R22";
"GPIOY1_SIOS5#":   PN = "R21"  !CDS_PN = "R21";
"GPIOY2_SIOPWREQ#":   PN = "P22"  !CDS_PN = "P22";
"IV11D0":   PN = "F6"  !CDS_PN = "F6";
"IV11D1":   PN = "G10"  !CDS_PN = "G10";
"IV11D2":   PN = "G11"  !CDS_PN = "G11";
"IV11D3":   PN = "G12"  !CDS_PN = "G12";
"IV11D4":   PN = "G13"  !CDS_PN = "G13";
"IV11D5":   PN = "G14"  !CDS_PN = "G14";
"IV11D6":   PN = "G15"  !CDS_PN = "G15";
"IV11D7":   PN = "G7"  !CDS_PN = "G7";
"IV11D8":   PN = "G8"  !CDS_PN = "G8";
"IV11D9":   PN = "G9"  !CDS_PN = "G9";
"IV11D10":   PN = "H16"  !CDS_PN = "H16";
"IV11D11":   PN = "J16"  !CDS_PN = "J16";
"IV11D12":   PN = "L7"  !CDS_PN = "L7";
"IV11D13":   PN = "N16"  !CDS_PN = "N16";
"IV11D14":   PN = "N7"  !CDS_PN = "N7";
"IV11D15":   PN = "P10"  !CDS_PN = "P10";
"IV11D16":   PN = "P11"  !CDS_PN = "P11";
"IV11D17":   PN = "P12"  !CDS_PN = "P12";
"IV11D18":   PN = "P13"  !CDS_PN = "P13";
"IV11D19":   PN = "P14"  !CDS_PN = "P14";
"IV11D20":   PN = "P16"  !CDS_PN = "P16";
"IV11D21":   PN = "P7"  !CDS_PN = "P7";
"IV11D22":   PN = "P9"  !CDS_PN = "P9";
"IV11D23":   PN = "R16"  !CDS_PN = "R16";
"IV11D24":   PN = "R7"  !CDS_PN = "R7";
"LPVDD0":   PN = "J17"  !CDS_PN = "J17";
"LPVDD1":   PN = "K17"  !CDS_PN = "K17";
"MVDD0":   PN = "T10"  !CDS_PN = "T10";
"MVDD1":   PN = "T12"  !CDS_PN = "T12";
"MVDD2":   PN = "T13"  !CDS_PN = "T13";
"MVDD3":   PN = "T14"  !CDS_PN = "T14";
"MVDD4":   PN = "T8"  !CDS_PN = "T8";
"PEAV11":   PN = "L17"  !CDS_PN = "L17";
"PEAV33":   PN = "L16"  !CDS_PN = "L16";
"PECIVDD":   PN = "AA17"  !CDS_PN = "AA17";
"PLLAV330":   PN = "Y17"  !CDS_PN = "Y17";
"PLLAV331":   PN = "W17"  !CDS_PN = "W17";
"PLLDV11":   PN = "V17"  !CDS_PN = "V17";
"PV33D0":   PN = "F12"  !CDS_PN = "F12";
"PV33D1":   PN = "F13"  !CDS_PN = "F13";
"PV33D2":   PN = "F14"  !CDS_PN = "F14";
"PV33D3":   PN = "F15"  !CDS_PN = "F15";
"PV33D4":   PN = "G16"  !CDS_PN = "G16";
"PV33D5":   PN = "H17"  !CDS_PN = "H17";
"PV33D6":   PN = "K7"  !CDS_PN = "K7";
"PV33D7":   PN = "N17"  !CDS_PN = "N17";
"PV33D8":   PN = "N6"  !CDS_PN = "N6";
"PV33D9":   PN = "P17"  !CDS_PN = "P17";
"PV33D10":   PN = "P6"  !CDS_PN = "P6";
"PV33D11":   PN = "R17"  !CDS_PN = "R17";
"PV33D12":   PN = "R6"  !CDS_PN = "R6";
"PV33D13":   PN = "T11"  !CDS_PN = "T11";
"PV33D14":   PN = "T15"  !CDS_PN = "T15";
"R1VDD0":   PN = "F10"  !CDS_PN = "F10";
"R1VDD1":   PN = "F11"  !CDS_PN = "F11";
"R2VDD0":   PN = "F7"  !CDS_PN = "F7";
"R2VDD1":   PN = "F8"  !CDS_PN = "F8";
"USB2AV33":   PN = "C7"  !CDS_PN = "C7";
"VPLLAV110":   PN = "L5"  !CDS_PN = "L5";
"VPLLAV111":   PN = "L6"  !CDS_PN = "L6";
"VPLLAV330":   PN = "J7"  !CDS_PN = "J7";
"VPLLAV331":   PN = "H7"  !CDS_PN = "H7";
DRAWING = "@baseboard_fab2_lib.baseboard_fab2(sch_1):page149";
BODY = "H5AN4G6NAFR-TFC-GP","I1": #LOCATION = "U25W5" !CDS_LOCATION = "U25W5" &SEC = "1" #&CDS_SEC = "1";
"A0":   PN = "P3"  !CDS_PN = "P3";
"A1":   PN = "P7"  !CDS_PN = "P7";
"A2":   PN = "R3"  !CDS_PN = "R3";
"A3":   PN = "N7"  !CDS_PN = "N7";
"A4":   PN = "N3"  !CDS_PN = "N3";
"A5":   PN = "P8"  !CDS_PN = "P8";
"A6":   PN = "P2"  !CDS_PN = "P2";
"A7":   PN = "R8"  !CDS_PN = "R8";
"A8":   PN = "R2"  !CDS_PN = "R2";
"A9":   PN = "R7"  !CDS_PN = "R7";
"A10/AP":   PN = "M3"  !CDS_PN = "M3";
"A11":   PN = "T2"  !CDS_PN = "T2";
"A12/BC#":   PN = "M7"  !CDS_PN = "M7";
"A13":   PN = "T8"  !CDS_PN = "T8";
"ACT#":   PN = "L3"  !CDS_PN = "L3";
"ALERT#":   PN = "P9"  !CDS_PN = "P9";
"BA0":   PN = "N2"  !CDS_PN = "N2";
"BA1":   PN = "N8"  !CDS_PN = "N8";
"BG0":   PN = "M2"  !CDS_PN = "M2";
"CAS#/A15":   PN = "M8"  !CDS_PN = "M8";
"CK_C":   PN = "K8"  !CDS_PN = "K8";
"CK_T":   PN = "K7"  !CDS_PN = "K7";
"CKE":   PN = "K2"  !CDS_PN = "K2";
"CS#":   PN = "L7"  !CDS_PN = "L7";
"DML#/DBIL#":   PN = "E7"  !CDS_PN = "E7";
"DMU#/DBIU#":   PN = "E2"  !CDS_PN = "E2";
"DQL0":   PN = "G2"  !CDS_PN = "G2";
"DQL1":   PN = "F7"  !CDS_PN = "F7";
"DQL2":   PN = "H3"  !CDS_PN = "H3";
"DQL3":   PN = "H7"  !CDS_PN = "H7";
"DQL4":   PN = "H2"  !CDS_PN = "H2";
"DQL5":   PN = "H8"  !CDS_PN = "H8";
"DQL6":   PN = "J3"  !CDS_PN = "J3";
"DQL7":   PN = "J7"  !CDS_PN = "J7";
"DQSL_C":   PN = "F3"  !CDS_PN = "F3";
"DQSL_T":   PN = "G3"  !CDS_PN = "G3";
"DQSU_C":   PN = "A7"  !CDS_PN = "A7";
"DQSU_T":   PN = "B7"  !CDS_PN = "B7";
"DQU0":   PN = "A3"  !CDS_PN = "A3";
"DQU1":   PN = "B8"  !CDS_PN = "B8";
"DQU2":   PN = "C3"  !CDS_PN = "C3";
"DQU3":   PN = "C7"  !CDS_PN = "C7";
"DQU4":   PN = "C2"  !CDS_PN = "C2";
"DQU5":   PN = "C8"  !CDS_PN = "C8";
"DQU6":   PN = "D3"  !CDS_PN = "D3";
"DQU7":   PN = "D7"  !CDS_PN = "D7";
"NC#T7":   PN = "T7"  !CDS_PN = "T7";
"ODT":   PN = "K3"  !CDS_PN = "K3";
"PAR":   PN = "T3"  !CDS_PN = "T3";
"RAS#/A16":   PN = "L8"  !CDS_PN = "L8";
"RESET#":   PN = "P1"  !CDS_PN = "P1";
"TEN":   PN = "N9"  !CDS_PN = "N9";
"VDD<0>":   PN = "B3"  !CDS_PN = "B3";
"VDD<1>":   PN = "B9"  !CDS_PN = "B9";
"VDD<2>":   PN = "D1"  !CDS_PN = "D1";
"VDD<3>":   PN = "G7"  !CDS_PN = "G7";
"VDD<4>":   PN = "J1"  !CDS_PN = "J1";
"VDD<5>":   PN = "J9"  !CDS_PN = "J9";
"VDD<6>":   PN = "L1"  !CDS_PN = "L1";
"VDD<7>":   PN = "L9"  !CDS_PN = "L9";
"VDD<8>":   PN = "R1"  !CDS_PN = "R1";
"VDD<9>":   PN = "T9"  !CDS_PN = "T9";
"VDDQ<0>":   PN = "A1"  !CDS_PN = "A1";
"VDDQ<1>":   PN = "A9"  !CDS_PN = "A9";
"VDDQ<2>":   PN = "C1"  !CDS_PN = "C1";
"VDDQ<3>":   PN = "D9"  !CDS_PN = "D9";
"VDDQ<4>":   PN = "F2"  !CDS_PN = "F2";
"VDDQ<5>":   PN = "F8"  !CDS_PN = "F8";
"VDDQ<6>":   PN = "G1"  !CDS_PN = "G1";
"VDDQ<7>":   PN = "G9"  !CDS_PN = "G9";
"VDDQ<8>":   PN = "J2"  !CDS_PN = "J2";
"VDDQ<9>":   PN = "J8"  !CDS_PN = "J8";
"VPP<0>":   PN = "B1"  !CDS_PN = "B1";
"VPP<1>":   PN = "R9"  !CDS_PN = "R9";
"VREFCA":   PN = "M1"  !CDS_PN = "M1";
"VSS<0>":   PN = "B2"  !CDS_PN = "B2";
"VSS<1>":   PN = "E1"  !CDS_PN = "E1";
"VSS<2>":   PN = "E9"  !CDS_PN = "E9";
"VSS<3>":   PN = "G8"  !CDS_PN = "G8";
"VSS<4>":   PN = "K1"  !CDS_PN = "K1";
"VSS<5>":   PN = "K9"  !CDS_PN = "K9";
"VSS<6>":   PN = "M9"  !CDS_PN = "M9";
"VSS<7>":   PN = "N1"  !CDS_PN = "N1";
"VSS<8>":   PN = "T1"  !CDS_PN = "T1";
"VSSQ<0>":   PN = "A2"  !CDS_PN = "A2";
"VSSQ<1>":   PN = "A8"  !CDS_PN = "A8";
"VSSQ<2>":   PN = "C9"  !CDS_PN = "C9";
"VSSQ<3>":   PN = "D2"  !CDS_PN = "D2";
"VSSQ<4>":   PN = "D8"  !CDS_PN = "D8";
"VSSQ<5>":   PN = "E3"  !CDS_PN = "E3";
"VSSQ<6>":   PN = "E8"  !CDS_PN = "E8";
"VSSQ<7>":   PN = "F1"  !CDS_PN = "F1";
"VSSQ<8>":   PN = "H1"  !CDS_PN = "H1";
"VSSQ<9>":   PN = "H9"  !CDS_PN = "H9";
"WE#/A14":   PN = "L2"  !CDS_PN = "L2";
"ZQ":   PN = "F9"  !CDS_PN = "F9";
BODY = "RES","I14": #LOCATION = "R9F34" !CDS_LOCATION = "R9F34" #SEC = "1" !CDS_SEC = "1";
"A":   PN = "1"  !CDS_PN = "1";
"B":   PN = "2"  !CDS_PN = "2";
BODY = "RES","I16": #LOCATION = "R9F29" !CDS_LOCATION = "R9F29" #SEC = "1" !CDS_SEC = "1";
"A":   PN = "1"  !CDS_PN = "1";
"B":   PN = "2"  !CDS_PN = "2";
BODY = "TTL1G07_A","I34": #LOCATION = "U9F3" !CDS_LOCATION = "U9F3" #SEC = "1" !CDS_SEC = "1";
"A":   PN = "2"  !CDS_PN = "2";
"Y":   PN = "4"  !CDS_PN = "4";
BODY = "CAP","I37": #LOCATION = "C25W16" !CDS_LOCATION = "C25W16" &SEC = "1" #&CDS_SEC = "1";
"A":   PN = "1"  !CDS_PN = "1";
"B":   PN = "2"  !CDS_PN = "2";
BODY = "SC1U16V3KX-2GP","I38": #LOCATION = "C25W17" !CDS_LOCATION = "C25W17" &SEC = "1" #&CDS_SEC = "1";
"1":   PN = "1"  !CDS_PN = "1";
"2":   PN = "2"  !CDS_PN = "2";
BODY = "SCD1U16V2KX-3GP","I39": #LOCATION = "C25W15" !CDS_LOCATION = "C25W15" &SEC = "1" #&CDS_SEC = "1";
"1":   PN = "1"  !CDS_PN = "1";
"2":   PN = "2"  !CDS_PN = "2";
BODY = "SCD1U16V2KX-3GP","I44": #LOCATION = "C25W14" !CDS_LOCATION = "C25W14" &SEC = "1" #&CDS_SEC = "1";
"1":   PN = "1"  !CDS_PN = "1";
"2":   PN = "2"  !CDS_PN = "2";
BODY = "RES","I55": #LOCATION = "R25W117" !CDS_LOCATION = "R25W117" &SEC = "1" #&CDS_SEC = "1";
"A":   PN = "1"  !CDS_PN = "1";
"B":   PN = "2"  !CDS_PN = "2";
BODY = "CAP","I65": #LOCATION = "C25W13" !CDS_LOCATION = "C25W13" &SEC = "1" #&CDS_SEC = "1";
"A":   PN = "1"  !CDS_PN = "1";
"B":   PN = "2"  !CDS_PN = "2";
BODY = "SC1U16V3KX-2GP","I68": #LOCATION = "C25W18" !CDS_LOCATION = "C25W18" &SEC = "1" #&CDS_SEC = "1";
"1":   PN = "1"  !CDS_PN = "1";
"2":   PN = "2"  !CDS_PN = "2";
BODY = "SC4D7U10V3KX-GP","I69": #LOCATION = "C25W19" !CDS_LOCATION = "C25W19" &SEC = "1" #&CDS_SEC = "1";
"1":   PN = "1"  !CDS_PN = "1";
"2":   PN = "2"  !CDS_PN = "2";
BODY = "CAP","I71": #LOCATION = "C25W1" !CDS_LOCATION = "C25W1" &SEC = "1" #&CDS_SEC = "1";
"A":   PN = "1"  !CDS_PN = "1";
"B":   PN = "2"  !CDS_PN = "2";
BODY = "CAP","I72": #LOCATION = "C25W2" !CDS_LOCATION = "C25W2" &SEC = "1" #&CDS_SEC = "1";
"A":   PN = "1"  !CDS_PN = "1";
"B":   PN = "2"  !CDS_PN = "2";
BODY = "CAP","I73": #LOCATION = "C25W3" !CDS_LOCATION = "C25W3" &SEC = "1" #&CDS_SEC = "1";
"A":   PN = "1"  !CDS_PN = "1";
"B":   PN = "2"  !CDS_PN = "2";
BODY = "CAP","I74": #LOCATION = "C25W4" !CDS_LOCATION = "C25W4" &SEC = "1" #&CDS_SEC = "1";
"A":   PN = "1"  !CDS_PN = "1";
"B":   PN = "2"  !CDS_PN = "2";
BODY = "RES","I94": #LOCATION = "R9E24" !CDS_LOCATION = "R9E24" #SEC = "1" !CDS_SEC = "1";
"A":   PN = "1"  !CDS_PN = "1";
"B":   PN = "2"  !CDS_PN = "2";
BODY = "CAP","I96": #LOCATION = "C25W5" !CDS_LOCATION = "C25W5" &SEC = "1" #&CDS_SEC = "1";
"A":   PN = "1"  !CDS_PN = "1";
"B":   PN = "2"  !CDS_PN = "2";
BODY = "CAP","I97": #LOCATION = "C25W6" !CDS_LOCATION = "C25W6" &SEC = "1" #&CDS_SEC = "1";
"A":   PN = "1"  !CDS_PN = "1";
"B":   PN = "2"  !CDS_PN = "2";
BODY = "LED","I98": #LOCATION = "DS9E1" !CDS_LOCATION = "DS9E1" #SEC = "1" !CDS_SEC = "1";
"A":   PN = "1"  !CDS_PN = "1";
"C":   PN = "2"  !CDS_PN = "2";
BODY = "FET_N_DUAL","I109": #LOCATION = "Q9E1" !CDS_LOCATION = "Q9E1" #SEC = "2" !CDS_SEC = "2";
"DRAIN<0>":   PN = "3"  !CDS_PN = "3";
"GATE<0>":   PN = "5"  !CDS_PN = "5";
"SOURCE<0>":   PN = "4"  !CDS_PN = "4";
BODY = "RES","I111": #LOCATION = "R9E21" !CDS_LOCATION = "R9E21" #SEC = "1" !CDS_SEC = "1";
"A":   PN = "1"  !CDS_PN = "1";
"B":   PN = "2"  !CDS_PN = "2";
BODY = "FET_N_DUAL","I113": #LOCATION = "Q9E1" !CDS_LOCATION = "Q9E1" #SEC = "1" !CDS_SEC = "1";
"DRAIN<0>":   PN = "6"  !CDS_PN = "6";
"GATE<0>":   PN = "2"  !CDS_PN = "2";
"SOURCE<0>":   PN = "1"  !CDS_PN = "1";
BODY = "RES","I120": #LOCATION = "R25W119" !CDS_LOCATION = "R25W119" &SEC = "1" #&CDS_SEC = "1";
"A":   PN = "1"  !CDS_PN = "1";
"B":   PN = "2"  !CDS_PN = "2";
BODY = "RES","I122": #LOCATION = "R25W118" !CDS_LOCATION = "R25W118" &SEC = "1" #&CDS_SEC = "1";
"A":   PN = "1"  !CDS_PN = "1";
"B":   PN = "2"  !CDS_PN = "2";
BODY = "RES","I124": #LOCATION = "R1T30" !CDS_LOCATION = "R1T30" #SEC = "1" !CDS_SEC = "1";
"A":   PN = "1"  !CDS_PN = "1";
"B":   PN = "2"  !CDS_PN = "2";
BODY = "RES","I125": #LOCATION = "R1T29" !CDS_LOCATION = "R1T29" #SEC = "1" !CDS_SEC = "1";
"A":   PN = "1"  !CDS_PN = "1";
"B":   PN = "2"  !CDS_PN = "2";
BODY = "CAP","I126": #LOCATION = "C25W12" !CDS_LOCATION = "C25W12" #SEC = "1" !CDS_SEC = "1";
"A":   PN = "1"  !CDS_PN = "1";
"B":   PN = "2"  !CDS_PN = "2";
BODY = "RES","I156": #LOCATION = "R8B25" !CDS_LOCATION = "R8B25" #SEC = "1" !CDS_SEC = "1";
"A":   PN = "1"  !CDS_PN = "1";
"B":   PN = "2"  !CDS_PN = "2";
BODY = "CAP","I158": #LOCATION = "C25W10" !CDS_LOCATION = "C25W10" #SEC = "1" !CDS_SEC = "1";
"A":   PN = "1"  !CDS_PN = "1";
"B":   PN = "2"  !CDS_PN = "2";
BODY = "CAP","I159": #LOCATION = "C25W11" !CDS_LOCATION = "C25W11" #SEC = "1" !CDS_SEC = "1";
"A":   PN = "1"  !CDS_PN = "1";
"B":   PN = "2"  !CDS_PN = "2";
BODY = "120R2F-GP","I160": #LOCATION = "R25W1" !CDS_LOCATION = "R25W1" &SEC = "1" #&CDS_SEC = "1";
"1":   PN = "1"  !CDS_PN = "1";
"2":   PN = "2"  !CDS_PN = "2";
BODY = "120R2F-GP","I161": #LOCATION = "R25W2" !CDS_LOCATION = "R25W2" &SEC = "1" #&CDS_SEC = "1";
"1":   PN = "1"  !CDS_PN = "1";
"2":   PN = "2"  !CDS_PN = "2";
BODY = "120R2F-GP","I162": #LOCATION = "R25W4" !CDS_LOCATION = "R25W4" &SEC = "1" #&CDS_SEC = "1";
"1":   PN = "1"  !CDS_PN = "1";
"2":   PN = "2"  !CDS_PN = "2";
BODY = "120R2F-GP","I163": #LOCATION = "R25W3" !CDS_LOCATION = "R25W3" &SEC = "1" #&CDS_SEC = "1";
"1":   PN = "1"  !CDS_PN = "1";
"2":   PN = "2"  !CDS_PN = "2";
BODY = "120R2F-GP","I164": #LOCATION = "R25W5" !CDS_LOCATION = "R25W5" &SEC = "1" #&CDS_SEC = "1";
"1":   PN = "1"  !CDS_PN = "1";
"2":   PN = "2"  !CDS_PN = "2";
BODY = "120R2F-GP","I165": #LOCATION = "R25W6" !CDS_LOCATION = "R25W6" &SEC = "1" #&CDS_SEC = "1";
"1":   PN = "1"  !CDS_PN = "1";
"2":   PN = "2"  !CDS_PN = "2";
BODY = "120R2F-GP","I166": #LOCATION = "R25W7" !CDS_LOCATION = "R25W7" &SEC = "1" #&CDS_SEC = "1";
"1":   PN = "1"  !CDS_PN = "1";
"2":   PN = "2"  !CDS_PN = "2";
BODY = "120R2F-GP","I167": #LOCATION = "R25W8" !CDS_LOCATION = "R25W8" &SEC = "1" #&CDS_SEC = "1";
"1":   PN = "1"  !CDS_PN = "1";
"2":   PN = "2"  !CDS_PN = "2";
BODY = "120R2F-GP","I168": #LOCATION = "R25W9" !CDS_LOCATION = "R25W9" &SEC = "1" #&CDS_SEC = "1";
"1":   PN = "1"  !CDS_PN = "1";
"2":   PN = "2"  !CDS_PN = "2";
BODY = "120R2F-GP","I169": #LOCATION = "R25W10" !CDS_LOCATION = "R25W10" &SEC = "1" #&CDS_SEC = "1";
"1":   PN = "1"  !CDS_PN = "1";
"2":   PN = "2"  !CDS_PN = "2";
BODY = "120R2F-GP","I170": #LOCATION = "R25W12" !CDS_LOCATION = "R25W12" &SEC = "1" #&CDS_SEC = "1";
"1":   PN = "1"  !CDS_PN = "1";
"2":   PN = "2"  !CDS_PN = "2";
BODY = "120R2F-GP","I171": #LOCATION = "R25W11" !CDS_LOCATION = "R25W11" &SEC = "1" #&CDS_SEC = "1";
"1":   PN = "1"  !CDS_PN = "1";
"2":   PN = "2"  !CDS_PN = "2";
BODY = "120R2F-GP","I172": #LOCATION = "R25W13" !CDS_LOCATION = "R25W13" &SEC = "1" #&CDS_SEC = "1";
"1":   PN = "1"  !CDS_PN = "1";
"2":   PN = "2"  !CDS_PN = "2";
BODY = "120R2F-GP","I173": #LOCATION = "R25W16" !CDS_LOCATION = "R25W16" &SEC = "1" #&CDS_SEC = "1";
"1":   PN = "1"  !CDS_PN = "1";
"2":   PN = "2"  !CDS_PN = "2";
BODY = "120R2F-GP","I174": #LOCATION = "R25W15" !CDS_LOCATION = "R25W15" &SEC = "1" #&CDS_SEC = "1";
"1":   PN = "1"  !CDS_PN = "1";
"2":   PN = "2"  !CDS_PN = "2";
BODY = "120R2F-GP","I175": #LOCATION = "R25W14" !CDS_LOCATION = "R25W14" &SEC = "1" #&CDS_SEC = "1";
"1":   PN = "1"  !CDS_PN = "1";
"2":   PN = "2"  !CDS_PN = "2";
BODY = "120R2F-GP","I176": #LOCATION = "R25W22" !CDS_LOCATION = "R25W22" &SEC = "1" #&CDS_SEC = "1";
"1":   PN = "1"  !CDS_PN = "1";
"2":   PN = "2"  !CDS_PN = "2";
BODY = "120R2F-GP","I177": #LOCATION = "R25W23" !CDS_LOCATION = "R25W23" &SEC = "1" #&CDS_SEC = "1";
"1":   PN = "1"  !CDS_PN = "1";
"2":   PN = "2"  !CDS_PN = "2";
BODY = "120R2F-GP","I178": #LOCATION = "R25W24" !CDS_LOCATION = "R25W24" &SEC = "1" #&CDS_SEC = "1";
"1":   PN = "1"  !CDS_PN = "1";
"2":   PN = "2"  !CDS_PN = "2";
BODY = "120R2F-GP","I179": #LOCATION = "R25W25" !CDS_LOCATION = "R25W25" &SEC = "1" #&CDS_SEC = "1";
"1":   PN = "1"  !CDS_PN = "1";
"2":   PN = "2"  !CDS_PN = "2";
BODY = "120R2F-GP","I180": #LOCATION = "R25W26" !CDS_LOCATION = "R25W26" &SEC = "1" #&CDS_SEC = "1";
"1":   PN = "1"  !CDS_PN = "1";
"2":   PN = "2"  !CDS_PN = "2";
BODY = "120R2F-GP","I181": #LOCATION = "R25W17" !CDS_LOCATION = "R25W17" &SEC = "1" #&CDS_SEC = "1";
"1":   PN = "1"  !CDS_PN = "1";
"2":   PN = "2"  !CDS_PN = "2";
BODY = "120R2F-GP","I182": #LOCATION = "R25W18" !CDS_LOCATION = "R25W18" &SEC = "1" #&CDS_SEC = "1";
"1":   PN = "1"  !CDS_PN = "1";
"2":   PN = "2"  !CDS_PN = "2";
BODY = "120R2F-GP","I183": #LOCATION = "R25W19" !CDS_LOCATION = "R25W19" &SEC = "1" #&CDS_SEC = "1";
"1":   PN = "1"  !CDS_PN = "1";
"2":   PN = "2"  !CDS_PN = "2";
BODY = "120R2F-GP","I184": #LOCATION = "R25W20" !CDS_LOCATION = "R25W20" &SEC = "1" #&CDS_SEC = "1";
"1":   PN = "1"  !CDS_PN = "1";
"2":   PN = "2"  !CDS_PN = "2";
BODY = "120R2F-GP","I185": #LOCATION = "R25W21" !CDS_LOCATION = "R25W21" &SEC = "1" #&CDS_SEC = "1";
"1":   PN = "1"  !CDS_PN = "1";
"2":   PN = "2"  !CDS_PN = "2";
BODY = "120R2F-GP","I186": #LOCATION = "R25W27" !CDS_LOCATION = "R25W27" &SEC = "1" #&CDS_SEC = "1";
"1":   PN = "1"  !CDS_PN = "1";
"2":   PN = "2"  !CDS_PN = "2";
BODY = "120R2F-GP","I187": #LOCATION = "R25W28" !CDS_LOCATION = "R25W28" &SEC = "1" #&CDS_SEC = "1";
"1":   PN = "1"  !CDS_PN = "1";
"2":   PN = "2"  !CDS_PN = "2";
BODY = "120R2F-GP","I188": #LOCATION = "R25W30" !CDS_LOCATION = "R25W30" &SEC = "1" #&CDS_SEC = "1";
"1":   PN = "1"  !CDS_PN = "1";
"2":   PN = "2"  !CDS_PN = "2";
BODY = "120R2F-GP","I189": #LOCATION = "R25W29" !CDS_LOCATION = "R25W29" &SEC = "1" #&CDS_SEC = "1";
"1":   PN = "1"  !CDS_PN = "1";
"2":   PN = "2"  !CDS_PN = "2";
BODY = "120R2F-GP","I190": #LOCATION = "R25W31" !CDS_LOCATION = "R25W31" &SEC = "1" #&CDS_SEC = "1";
"1":   PN = "1"  !CDS_PN = "1";
"2":   PN = "2"  !CDS_PN = "2";
BODY = "120R2F-GP","I191": #LOCATION = "R25W32" !CDS_LOCATION = "R25W32" &SEC = "1" #&CDS_SEC = "1";
"1":   PN = "1"  !CDS_PN = "1";
"2":   PN = "2"  !CDS_PN = "2";
BODY = "120R2F-GP","I192": #LOCATION = "R25W33" !CDS_LOCATION = "R25W33" &SEC = "1" #&CDS_SEC = "1";
"1":   PN = "1"  !CDS_PN = "1";
"2":   PN = "2"  !CDS_PN = "2";
BODY = "120R2F-GP","I193": #LOCATION = "R25W34" !CDS_LOCATION = "R25W34" &SEC = "1" #&CDS_SEC = "1";
"1":   PN = "1"  !CDS_PN = "1";
"2":   PN = "2"  !CDS_PN = "2";
BODY = "120R2F-GP","I194": #LOCATION = "R25W35" !CDS_LOCATION = "R25W35" &SEC = "1" #&CDS_SEC = "1";
"1":   PN = "1"  !CDS_PN = "1";
"2":   PN = "2"  !CDS_PN = "2";
BODY = "120R2F-GP","I195": #LOCATION = "R25W36" !CDS_LOCATION = "R25W36" &SEC = "1" #&CDS_SEC = "1";
"1":   PN = "1"  !CDS_PN = "1";
"2":   PN = "2"  !CDS_PN = "2";
BODY = "120R2F-GP","I196": #LOCATION = "R25W37" !CDS_LOCATION = "R25W37" &SEC = "1" #&CDS_SEC = "1";
"1":   PN = "1"  !CDS_PN = "1";
"2":   PN = "2"  !CDS_PN = "2";
BODY = "120R2F-GP","I197": #LOCATION = "R25W38" !CDS_LOCATION = "R25W38" &SEC = "1" #&CDS_SEC = "1";
"1":   PN = "1"  !CDS_PN = "1";
"2":   PN = "2"  !CDS_PN = "2";
BODY = "120R2F-GP","I198": #LOCATION = "R25W39" !CDS_LOCATION = "R25W39" &SEC = "1" #&CDS_SEC = "1";
"1":   PN = "1"  !CDS_PN = "1";
"2":   PN = "2"  !CDS_PN = "2";
BODY = "120R2F-GP","I199": #LOCATION = "R25W41" !CDS_LOCATION = "R25W41" &SEC = "1" #&CDS_SEC = "1";
"1":   PN = "1"  !CDS_PN = "1";
"2":   PN = "2"  !CDS_PN = "2";
BODY = "120R2F-GP","I200": #LOCATION = "R25W40" !CDS_LOCATION = "R25W40" &SEC = "1" #&CDS_SEC = "1";
"1":   PN = "1"  !CDS_PN = "1";
"2":   PN = "2"  !CDS_PN = "2";
BODY = "120R2F-GP","I201": #LOCATION = "R25W42" !CDS_LOCATION = "R25W42" &SEC = "1" #&CDS_SEC = "1";
"1":   PN = "1"  !CDS_PN = "1";
"2":   PN = "2"  !CDS_PN = "2";
BODY = "120R2F-GP","I202": #LOCATION = "R25W43" !CDS_LOCATION = "R25W43" &SEC = "1" #&CDS_SEC = "1";
"1":   PN = "1"  !CDS_PN = "1";
"2":   PN = "2"  !CDS_PN = "2";
BODY = "120R2F-GP","I203": #LOCATION = "R25W44" !CDS_LOCATION = "R25W44" &SEC = "1" #&CDS_SEC = "1";
"1":   PN = "1"  !CDS_PN = "1";
"2":   PN = "2"  !CDS_PN = "2";
BODY = "120R2F-GP","I204": #LOCATION = "R25W45" !CDS_LOCATION = "R25W45" &SEC = "1" #&CDS_SEC = "1";
"1":   PN = "1"  !CDS_PN = "1";
"2":   PN = "2"  !CDS_PN = "2";
BODY = "120R2F-GP","I205": #LOCATION = "R25W46" !CDS_LOCATION = "R25W46" &SEC = "1" #&CDS_SEC = "1";
"1":   PN = "1"  !CDS_PN = "1";
"2":   PN = "2"  !CDS_PN = "2";
BODY = "120R2F-GP","I206": #LOCATION = "R25W47" !CDS_LOCATION = "R25W47" &SEC = "1" #&CDS_SEC = "1";
"1":   PN = "1"  !CDS_PN = "1";
"2":   PN = "2"  !CDS_PN = "2";
BODY = "120R2F-GP","I207": #LOCATION = "R25W48" !CDS_LOCATION = "R25W48" &SEC = "1" #&CDS_SEC = "1";
"1":   PN = "1"  !CDS_PN = "1";
"2":   PN = "2"  !CDS_PN = "2";
BODY = "120R2F-GP","I208": #LOCATION = "R25W49" !CDS_LOCATION = "R25W49" &SEC = "1" #&CDS_SEC = "1";
"1":   PN = "1"  !CDS_PN = "1";
"2":   PN = "2"  !CDS_PN = "2";
BODY = "120R2F-GP","I209": #LOCATION = "R25W50" !CDS_LOCATION = "R25W50" &SEC = "1" #&CDS_SEC = "1";
"1":   PN = "1"  !CDS_PN = "1";
"2":   PN = "2"  !CDS_PN = "2";
BODY = "120R2F-GP","I210": #LOCATION = "R25W51" !CDS_LOCATION = "R25W51" &SEC = "1" #&CDS_SEC = "1";
"1":   PN = "1"  !CDS_PN = "1";
"2":   PN = "2"  !CDS_PN = "2";
BODY = "120R2F-GP","I211": #LOCATION = "R25W52" !CDS_LOCATION = "R25W52" &SEC = "1" #&CDS_SEC = "1";
"1":   PN = "1"  !CDS_PN = "1";
"2":   PN = "2"  !CDS_PN = "2";
BODY = "120R2F-GP","I212": #LOCATION = "R1T28" !CDS_LOCATION = "R1T28" &SEC = "1" #&CDS_SEC = "1";
"1":   PN = "1"  !CDS_PN = "1";
"2":   PN = "2"  !CDS_PN = "2";
END.
